(kicad_pcb (version 20221018) (generator pcbnew)

  (general
    (thickness 0.908)
  )

  (paper "A4")
  (title_block
    (title "HDMI-MIPI Bridge")
    (date "2024-04-24")
    (rev "1.3.2")
  )

  (layers
    (0 "F.Cu" signal)
    (1 "In1.Cu" signal)
    (2 "In2.Cu" signal)
    (31 "B.Cu" signal)
    (32 "B.Adhes" user "B.Adhesive")
    (33 "F.Adhes" user "F.Adhesive")
    (34 "B.Paste" user)
    (35 "F.Paste" user)
    (36 "B.SilkS" user "B.Silkscreen")
    (37 "F.SilkS" user "F.Silkscreen")
    (38 "B.Mask" user)
    (39 "F.Mask" user)
    (40 "Dwgs.User" user "User.Drawings")
    (41 "Cmts.User" user "User.Comments")
    (42 "Eco1.User" user "User.Eco1")
    (43 "Eco2.User" user "User.Eco2")
    (44 "Edge.Cuts" user)
    (45 "Margin" user)
    (46 "B.CrtYd" user "B.Courtyard")
    (47 "F.CrtYd" user "F.Courtyard")
    (48 "B.Fab" user)
    (49 "F.Fab" user)
  )

  (setup
    (stackup
      (layer "F.SilkS" (type "Top Silk Screen"))
      (layer "F.Paste" (type "Top Solder Paste"))
      (layer "F.Mask" (type "Top Solder Mask") (color "Black") (thickness 0.01))
      (layer "F.Cu" (type "copper") (thickness 0.035))
      (layer "dielectric 1" (type "core") (thickness 0.254) (material "FR4") (epsilon_r 4.2) (loss_tangent 0.02))
      (layer "In1.Cu" (type "copper") (thickness 0.035))
      (layer "dielectric 2" (type "prepreg") (thickness 0.24) (material "FR4") (epsilon_r 4.2) (loss_tangent 0.02))
      (layer "In2.Cu" (type "copper") (thickness 0.035))
      (layer "dielectric 3" (type "core") (thickness 0.254) (material "FR4") (epsilon_r 4.2) (loss_tangent 0.02))
      (layer "B.Cu" (type "copper") (thickness 0.035))
      (layer "B.Mask" (type "Bottom Solder Mask") (color "Black") (thickness 0.01))
      (layer "B.Paste" (type "Bottom Solder Paste"))
      (layer "B.SilkS" (type "Bottom Silk Screen"))
      (copper_finish "None")
      (dielectric_constraints yes)
    )
    (pad_to_mask_clearance 0)
    (aux_axis_origin 115 135)
    (pcbplotparams
      (layerselection 0x00010fc_ffffffff)
      (plot_on_all_layers_selection 0x0000000_00000000)
      (disableapertmacros false)
      (usegerberextensions false)
      (usegerberattributes true)
      (usegerberadvancedattributes true)
      (creategerberjobfile true)
      (dashed_line_dash_ratio 12.000000)
      (dashed_line_gap_ratio 3.000000)
      (svgprecision 6)
      (plotframeref false)
      (viasonmask false)
      (mode 1)
      (useauxorigin false)
      (hpglpennumber 1)
      (hpglpenspeed 20)
      (hpglpendiameter 15.000000)
      (dxfpolygonmode true)
      (dxfimperialunits true)
      (dxfusepcbnewfont true)
      (psnegative false)
      (psa4output false)
      (plotreference true)
      (plotvalue true)
      (plotinvisibletext false)
      (sketchpadsonfab false)
      (subtractmaskfromsilk false)
      (outputformat 1)
      (mirror false)
      (drillshape 1)
      (scaleselection 1)
      (outputdirectory "")
    )
  )

  (net 0 "")
  (net 1 "Net-(U1C-BIASDA)")
  (net 2 "GND")
  (net 3 "Net-(U1C-DAOUT)")
  (net 4 "Net-(U1C-PCKIN)")
  (net 5 "Net-(U1B-AVDD25)")
  (net 6 "Net-(C5-Pad1)")
  (net 7 "Net-(C10-Pad2)")
  (net 8 "Net-(U1B-VDDC1)")
  (net 9 "+3V3")
  (net 10 "Net-(Y1-EN)")
  (net 11 "CH1_2V5")
  (net 12 "CH1_1V2")
  (net 13 "Net-(Y1-OUT)")
  (net 14 "+5V")
  (net 15 "/Channel 1/CH1_REFCLK")
  (net 16 "Net-(U4C-BIASDA)")
  (net 17 "Net-(U4C-DAOUT)")
  (net 18 "Net-(U4C-PCKIN)")
  (net 19 "Net-(C27-Pad2)")
  (net 20 "Net-(U1B-VDDIO1)")
  (net 21 "Net-(U1B-VDDIO2)")
  (net 22 "Net-(C31-Pad2)")
  (net 23 "Net-(U4B-VDDIO1)")
  (net 24 "CH2_2V5")
  (net 25 "CH2_1V2")
  (net 26 "Net-(U4B-VDDIO2)")
  (net 27 "/Channel 2/CH2_REFCLK")
  (net 28 "Net-(FB1-Pad2)")
  (net 29 "Net-(FB7-Pad2)")
  (net 30 "Net-(Y2-EN)")
  (net 31 "Net-(Y2-OUT)")
  (net 32 "Net-(U4B-AVDD25)")
  (net 33 "Net-(U4B-VDDC1)")
  (net 34 "CSI3_D4_N")
  (net 35 "CSI3_D4_P")
  (net 36 "CSI3_D3_N")
  (net 37 "CSI3_D3_P")
  (net 38 "CSI3_D2_N")
  (net 39 "CSI3_D2_P")
  (net 40 "CSI3_D1_N")
  (net 41 "CSI3_D1_P")
  (net 42 "CSI3_CLK_N")
  (net 43 "CSI3_CLK_P")
  (net 44 "/CSI/CSI2_CLK_N")
  (net 45 "/CSI/CSI2_CLK_P")
  (net 46 "/CSI/CSI2_D1_N")
  (net 47 "/CSI/CSI2_D1_P")
  (net 48 "CSI1_D4_N")
  (net 49 "CSI1_D4_P")
  (net 50 "CSI1_D3_N")
  (net 51 "CSI1_D3_P")
  (net 52 "CSI1_D2_N")
  (net 53 "CSI1_D2_P")
  (net 54 "CSI1_D1_N")
  (net 55 "CSI1_D1_P")
  (net 56 "CSI1_CLK_N")
  (net 57 "CSI1_CLK_P")
  (net 58 "/CSI/GPIO1")
  (net 59 "/CSI/GPIO2")
  (net 60 "/CSI/GPIO3")
  (net 61 "/CSI/GPIO4")
  (net 62 "/CSI/UART3_TX")
  (net 63 "/CSI/UART3_RX")
  (net 64 "/CSI/UART4_TX")
  (net 65 "/CSI/UART4_RX")
  (net 66 "I2C3_SDA")
  (net 67 "I2C3_SCL")
  (net 68 "I2C1_SDA")
  (net 69 "I2C1_SCL")
  (net 70 "/CSI/SPI_SCK")
  (net 71 "/CSI/SPI_MISO")
  (net 72 "/CSI/SPI_MOSI")
  (net 73 "/CSI/SPI_CS")
  (net 74 "/Channel 1/HDMI1_D2_P")
  (net 75 "/Channel 1/HDMI1_D2_N")
  (net 76 "/Channel 1/HDMI1_D1_P")
  (net 77 "/Channel 1/HDMI1_D1_N")
  (net 78 "/Channel 1/HDMI1_D0_P")
  (net 79 "/Channel 1/HDMI1_D0_N")
  (net 80 "/Channel 1/HDMI1_CLK_P")
  (net 81 "/Channel 1/HDMI1_CLK_N")
  (net 82 "/Channel 1/HDMI1_CEC")
  (net 83 "/Channel 1/DUMMY1")
  (net 84 "/Channel 1/HDMI1_DDC_SCL")
  (net 85 "/Channel 1/HDMI1_DDC_SDA")
  (net 86 "/Channel 1/HDMI1_POWER")
  (net 87 "/Channel 1/HDMI1_HPD")
  (net 88 "/Channel 2/HDMI2_D2_P")
  (net 89 "/Channel 2/HDMI2_D2_N")
  (net 90 "/Channel 2/HDMI2_D1_P")
  (net 91 "/Channel 2/HDMI2_D1_N")
  (net 92 "/Channel 2/HDMI2_D0_P")
  (net 93 "/Channel 2/HDMI2_D0_N")
  (net 94 "/Channel 2/HDMI2_CLK_P")
  (net 95 "/Channel 2/DUMMY2")
  (net 96 "/Channel 2/HDMI2_POWER")
  (net 97 "/Channel 1/HDMI1_HPDI")
  (net 98 "/Channel 1/CH1_~{RST}")
  (net 99 "unconnected-(IC1-NC-Pad4)")
  (net 100 "/Channel 1/CH1_AVDD33")
  (net 101 "unconnected-(IC2-NC-Pad4)")
  (net 102 "unconnected-(IC3-NC-Pad4)")
  (net 103 "unconnected-(IC4-NC-Pad4)")
  (net 104 "/Channel 1/HDMI1_DDC_SDA_3V3")
  (net 105 "/Channel 1/HDMI1_DDC_SCL_3V3")
  (net 106 "/Channel 2/HDMI2_HPDI")
  (net 107 "/Channel 2/CH2_~{RST}")
  (net 108 "/Channel 2/CH2_AVDD33")
  (net 109 "Net-(C48-Pad1)")
  (net 110 "Net-(C49-Pad1)")
  (net 111 "/Channel 2/HDMI2_DDC_SDA_3V3")
  (net 112 "/Channel 2/HDMI2_DDC_SCL_3V3")
  (net 113 "Net-(U1B-REXT)")
  (net 114 "Net-(U4B-REXT)")
  (net 115 "/Channel 1/HDMI1_HPDO")
  (net 116 "Net-(U1A-EDID_SDA)")
  (net 117 "Net-(U1A-EDID_SCL)")
  (net 118 "Net-(U3-EN)")
  (net 119 "/Channel 2/HDMI2_HPDO")
  (net 120 "Net-(U4A-EDID_SDA)")
  (net 121 "Net-(U4A-EDID_SCL)")
  (net 122 "Net-(U6-EN)")
  (net 123 "unconnected-(U1C-PFIL-PadA6)")
  (net 124 "unconnected-(U1B-INT-PadB3)")
  (net 125 "unconnected-(U1A-IR-PadB4)")
  (net 126 "unconnected-(U1C-A_SCK-PadF7)")
  (net 127 "unconnected-(U1C-A_SD-PadF8)")
  (net 128 "unconnected-(U1C-A_WFS-PadG7)")
  (net 129 "unconnected-(U1C-A_OSCK-PadG8)")
  (net 130 "unconnected-(U2-NC-Pad14)")
  (net 131 "unconnected-(U4C-PFIL-PadA6)")
  (net 132 "unconnected-(U4B-INT-PadB3)")
  (net 133 "unconnected-(U4A-IR-PadB4)")
  (net 134 "unconnected-(U4C-A_SCK-PadF7)")
  (net 135 "unconnected-(U4C-A_SD-PadF8)")
  (net 136 "unconnected-(U4C-A_WFS-PadG7)")
  (net 137 "/Channel 2/HDMI2_CLK_N")
  (net 138 "/Channel 2/HDMI2_CEC")
  (net 139 "/Channel 2/HDMI2_DDC_SCL")
  (net 140 "/Channel 2/HDMI2_DDC_SDA")
  (net 141 "/Channel 2/HDMI2_HPD")
  (net 142 "unconnected-(U4C-A_OSCK-PadG8)")
  (net 143 "unconnected-(U5-NC-Pad14)")
  (net 144 "unconnected-(J6-Pad21)")
  (net 145 "unconnected-(J6-Pad24)")

  (footprint "antmicro-footprints:C_0402_1005Metric" (layer "F.Cu")
    (at 155.01 110.45)
    (descr "Capacitor SMD 0402")
    (tags "capacitor SMD 0402")
    (property "Author" "Antmicro")
    (property "Dielectric" "X5R")
    (property "License" "Apache-2.0")
    (property "MPN" "GRM155R61H104KE14D")
    (property "Manufacturer" "Murata")
    (property "Public" "False")
    (property "Sheetfile" "channel2.kicad_sch")
    (property "Sheetname" "Channel 2")
    (property "Val" "100n")
    (property "Voltage" "50V")
    (property "ki_description" "SMD Multilayer Ceramic Capacitor, 0.1 µF, 50 V, 0402 [1005 Metric], ± 10%, X5R, GRM Series")
    (property "ki_keywords" "0402, SMT, CAPACITOR, PASSIVE, CERAMIC, MLCC")
    (attr smd)
    (fp_text reference "C32" (at -1.52 7.52) (layer "F.SilkS")
        (effects (font (size 0.65 0.65) (thickness 0.13)) (justify left bottom))
    )
    (fp_text value "C_100n_0402" (at 0 1.4) (layer "F.Fab")
        (effects (font (size 0.65 0.65) (thickness 0.13)) (justify left bottom))
    )
    (fp_text user "${REFERENCE}" (at -0.932 3.168) (layer "F.Fab") hide
        (effects (font (size 0.7 0.7) (thickness 0.15)) (justify left bottom))
    )
    (fp_text user "Author: Antmicro" (at -0.932 4.17) (layer "F.Fab") hide
        (effects (font (size 0.7 0.7) (thickness 0.15)) (justify left bottom))
    )
    (fp_text user "License: Apache-2.0" (at -0.932 5.17) (layer "F.Fab") hide
        (effects (font (size 0.7 0.7) (thickness 0.15)) (justify left bottom))
    )
    (fp_rect (start -0.925 -0.47) (end 0.925 0.47)
      (stroke (width 0.05) (type default)) (fill none) (layer "F.CrtYd"))
    (fp_line (start -0.494 -0.25) (end 0.504 -0.25)
      (stroke (width 0.15) (type solid)) (layer "F.Fab"))
    (fp_line (start -0.494 0.248) (end -0.494 -0.25)
      (stroke (width 0.15) (type solid)) (layer "F.Fab"))
    (fp_line (start 0.504 -0.25) (end 0.504 0.248)
      (stroke (width 0.15) (type solid)) (layer "F.Fab"))
    (fp_line (start 0.504 0.248) (end -0.494 0.248)
      (stroke (width 0.15) (type solid)) (layer "F.Fab"))
    (pad "1" smd roundrect (at -0.48 0) (size 0.59 0.64) (layers "F.Cu" "F.Paste" "F.Mask") (roundrect_rratio 0.25)
      (net 2 "GND") (pintype "passive"))
    (pad "2" smd roundrect (at 0.48 0) (size 0.59 0.64) (layers "F.Cu" "F.Paste" "F.Mask") (roundrect_rratio 0.25)
      (net 23 "Net-(U4B-VDDIO1)") (pintype "passive"))
  )

  (footprint "antmicro-footprints:C_0603_1608Metric" (layer "F.Cu")
    (at 154.6 107.25)
    (descr "Capacitor SMD 0603")
    (tags "capacitor 0603")
    (property "Author" "Antmicro")
    (property "Dielectric" "")
    (property "License" "Apache-2.0")
    (property "MPN" "C1608X5R1V475M080AC")
    (property "Manufacturer" "TDK")
    (property "Public" "False")
    (property "Sheetfile" "channel2.kicad_sch")
    (property "Sheetname" "Channel 2")
    (property "Val" "4u7")
    (property "Voltage" "")
    (property "ki_description" "SMD Multilayer Ceramic Capacitor, 4.7 µF, 35 V, 0603 [1608 Metric], ± 20%, X5R, C")
    (property "ki_keywords" "0603, SMT, CAPACITOR, PASSIVE, CERAMIC, MLCC")
    (attr smd)
    (fp_text reference "C54" (at -1.1 7.65) (layer "F.SilkS")
        (effects (font (size 0.65 0.65) (thickness 0.13)) (justify left bottom))
    )
    (fp_text value "C_4u7_0603" (at 0 1.6) (layer "F.Fab")
        (effects (font (size 0.65 0.65) (thickness 0.13)) (justify left bottom))
    )
    (fp_text user "${REFERENCE}" (at -1.682 3.895) (layer "F.Fab") hide
        (effects (font (size 0.7 0.7) (thickness 0.15)) (justify left bottom))
    )
    (fp_text user "Author: Antmicro" (at -1.682 4.894) (layer "F.Fab") hide
        (effects (font (size 0.7 0.7) (thickness 0.15)) (justify left bottom))
    )
    (fp_text user "License: Apache-2.0" (at -1.682 5.895) (layer "F.Fab") hide
        (effects (font (size 0.7 0.7) (thickness 0.15)) (justify left bottom))
    )
    (fp_line (start -0.15 -0.4) (end 0.15 -0.4)
      (stroke (width 0.15) (type solid)) (layer "F.SilkS"))
    (fp_line (start -0.15 0.4) (end 0.15 0.4)
      (stroke (width 0.15) (type solid)) (layer "F.SilkS"))
    (fp_rect (start -1.25 -0.65) (end 1.25 0.65)
      (stroke (width 0.05) (type solid)) (fill none) (layer "F.CrtYd"))
    (fp_rect (start -0.8 -0.4) (end 0.8 0.4)
      (stroke (width 0.15) (type solid)) (fill none) (layer "F.Fab"))
    (pad "1" smd roundrect (at -0.7 0) (size 0.8 1) (layers "F.Cu" "F.Paste" "F.Mask") (roundrect_rratio 0.2)
      (net 2 "GND") (pintype "passive"))
    (pad "2" smd roundrect (at 0.7 0) (size 0.8 1) (layers "F.Cu" "F.Paste" "F.Mask") (roundrect_rratio 0.2)
      (net 33 "Net-(U4B-VDDC1)") (pintype "passive"))
  )

  (footprint "antmicro-footprints:BGA-64_8x8_6.0x6.0mm" locked (layer "F.Cu")
    (at 135.4239 110.4001 -90)
    (property "Author" "Antmicro")
    (property "License" "Apache-2.0")
    (property "MPN" "TC358743XBG")
    (property "Manufacturer" "Toshiba")
    (property "Sheetfile" "channel1.kicad_sch")
    (property "Sheetname" "Channel 1")
    (property "ki_description" "HDMI to MIPI CSI-2 bridge. Supports HDMI 1.4. MIPI CSI-2 compliant. 80-Pin VFBGA")
    (property "ki_keywords" "SMT, INTERFACE, IC, CONTROLLER")
    (attr smd)
    (fp_text reference "U1" (at -3.3001 1.5239) (layer "F.SilkS")
        (effects (font (size 0.65 0.65) (thickness 0.13)) (justify left bottom))
    )
    (fp_text value "TC358743XBG" (at -7.0104 4.8768 90) (layer "F.Fab")
        (effects (font (size 0.65 0.65) (thickness 0.13)) (justify right bottom))
    )
    (fp_text user "Author: Antmicro" (at -9 7.2 90) (layer "F.Fab") hide
        (effects (font (size 0.7 0.7) (thickness 0.15)) (justify right bottom))
    )
    (fp_text user "License: Apache-2.0" (at -9 8.4 90) (layer "F.Fab") hide
        (effects (font (size 0.7 0.7) (thickness 0.15)) (justify right bottom))
    )
    (fp_text user "${REFERENCE}" (at -9 5.999 90) (layer "F.Fab") hide
        (effects (font (size 0.7 0.7) (thickness 0.15)) (justify right bottom))
    )
    (fp_line (start -3.121 -2) (end -3.121 -1.621)
      (stroke (width 0.15) (type solid)) (layer "F.SilkS"))
    (fp_line (start -3.121 3.12) (end -3.121 1.62)
      (stroke (width 0.15) (type solid)) (layer "F.SilkS"))
    (fp_line (start -2 -3.121) (end -3.121 -2)
      (stroke (width 0.15) (type solid)) (layer "F.SilkS"))
    (fp_line (start -1.621 -3.121) (end -2 -3.121)
      (stroke (width 0.15) (type solid)) (layer "F.SilkS"))
    (fp_line (start -1.621 3.12) (end -3.121 3.12)
      (stroke (width 0.15) (type solid)) (layer "F.SilkS"))
    (fp_line (start 1.62 -3.121) (end 3.12 -3.121)
      (stroke (width 0.15) (type solid)) (layer "F.SilkS"))
    (fp_line (start 1.62 -3.121) (end 3.12 -3.121)
      (stroke (width 0.15) (type solid)) (layer "F.SilkS"))
    (fp_line (start 1.62 -3.121) (end 3.12 -3.121)
      (stroke (width 0.15) (type solid)) (layer "F.SilkS"))
    (fp_line (start 1.62 3.12) (end 3.12 3.12)
      (stroke (width 0.15) (type solid)) (layer "F.SilkS"))
    (fp_line (start 3.12 -3.121) (end 3.12 -1.621)
      (stroke (width 0.15) (type solid)) (layer "F.SilkS"))
    (fp_line (start 3.12 -3.121) (end 3.12 -1.621)
      (stroke (width 0.15) (type solid)) (layer "F.SilkS"))
    (fp_line (start 3.12 -3.121) (end 3.12 -1.621)
      (stroke (width 0.15) (type solid)) (layer "F.SilkS"))
    (fp_line (start 3.12 3.12) (end 3.12 1.62)
      (stroke (width 0.15) (type solid)) (layer "F.SilkS"))
    (fp_circle (center -3 -2.9954) (end -2.951 -2.9954)
      (stroke (width 0.15) (type solid)) (fill solid) (layer "F.SilkS"))
    (fp_line (start -3.21 -3.21) (end 3.2 -3.21)
      (stroke (width 0.05) (type solid)) (layer "F.CrtYd"))
    (fp_line (start -3.21 3.2) (end -3.21 -3.21)
      (stroke (width 0.05) (type solid)) (layer "F.CrtYd"))
    (fp_line (start 3.2 -3.21) (end 3.2 3.2)
      (stroke (width 0.05) (type solid)) (layer "F.CrtYd"))
    (fp_line (start 3.2 3.2) (end -3.21 3.2)
      (stroke (width 0.05) (type solid)) (layer "F.CrtYd"))
    (fp_line (start -3 -2) (end -3 2.999)
      (stroke (width 0.15) (type solid)) (layer "F.Fab"))
    (fp_line (start -3 2.999) (end 2.999 2.999)
      (stroke (width 0.15) (type solid)) (layer "F.Fab"))
    (fp_line (start -2 -3) (end -3 -2)
      (stroke (width 0.15) (type solid)) (layer "F.Fab"))
    (fp_line (start 2.999 -3) (end -2 -3)
      (stroke (width 0.15) (type solid)) (layer "F.Fab"))
    (fp_line (start 2.999 2.999) (end 2.999 -3)
      (stroke (width 0.15) (type solid)) (layer "F.Fab"))
    (pad "A1" smd circle locked (at -2.275 -2.275 270) (size 0.3 0.3) (layers "F.Cu" "F.Paste" "F.Mask")
      (net 113 "Net-(U1B-REXT)") (pinfunction "REXT") (pintype "input"))
    (pad "A2" smd circle locked (at -1.625 -2.275 270) (size 0.3 0.3) (layers "F.Cu" "F.Paste" "F.Mask")
      (net 2 "GND") (pinfunction "GND") (pintype "power_in"))
    (pad "A3" smd circle locked (at -0.975 -2.275 270) (size 0.3 0.3) (layers "F.Cu" "F.Paste" "F.Mask")
      (net 2 "GND") (pinfunction "VPGM") (pintype "input"))
    (pad "A4" smd circle locked (at -0.326 -2.275 270) (size 0.3 0.3) (layers "F.Cu" "F.Paste" "F.Mask")
      (net 1 "Net-(U1C-BIASDA)") (pinfunction "BIASDA") (pintype "output"))
    (pad "A5" smd circle locked (at 0.325 -2.275 270) (size 0.3 0.3) (layers "F.Cu" "F.Paste" "F.Mask")
      (net 3 "Net-(U1C-DAOUT)") (pinfunction "DAOUT") (pintype "output"))
    (pad "A6" smd circle locked (at 0.974 -2.275 270) (size 0.3 0.3) (layers "F.Cu" "F.Paste" "F.Mask")
      (net 123 "unconnected-(U1C-PFIL-PadA6)") (pinfunction "PFIL") (pintype "output+no_connect"))
    (pad "A7" smd circle locked (at 1.624 -2.275 270) (size 0.3 0.3) (layers "F.Cu" "F.Paste" "F.Mask")
      (net 48 "CSI1_D4_N") (pinfunction "CSID3_N") (pintype "output"))
    (pad "A8" smd circle locked (at 2.274 -2.275 270) (size 0.3 0.3) (layers "F.Cu" "F.Paste" "F.Mask")
      (net 49 "CSI1_D4_P") (pinfunction "CSID3_P") (pintype "output"))
    (pad "B1" smd circle locked (at -2.275 -1.625 270) (size 0.3 0.3) (layers "F.Cu" "F.Paste" "F.Mask")
      (net 100 "/Channel 1/CH1_AVDD33") (pinfunction "AVDD33") (pintype "power_in"))
    (pad "B2" smd circle locked (at -1.625 -1.625 270) (size 0.3 0.3) (layers "F.Cu" "F.Paste" "F.Mask")
      (net 6 "Net-(C5-Pad1)") (pinfunction "AVDD12") (pintype "power_in"))
    (pad "B3" smd circle locked (at -0.975 -1.625 270) (size 0.3 0.3) (layers "F.Cu" "F.Paste" "F.Mask")
      (net 124 "unconnected-(U1B-INT-PadB3)") (pinfunction "INT") (pintype "output+no_connect"))
    (pad "B4" smd circle locked (at -0.326 -1.625 270) (size 0.3 0.3) (layers "F.Cu" "F.Paste" "F.Mask")
      (net 125 "unconnected-(U1A-IR-PadB4)") (pinfunction "IR") (pintype "input+no_connect"))
    (pad "B5" smd circle locked (at 0.325 -1.625 270) (size 0.3 0.3) (layers "F.Cu" "F.Paste" "F.Mask")
      (net 5 "Net-(U1B-AVDD25)") (pinfunction "AVDD25") (pintype "power_in"))
    (pad "B6" smd circle locked (at 0.974 -1.625 270) (size 0.3 0.3) (layers "F.Cu" "F.Paste" "F.Mask")
      (net 4 "Net-(U1C-PCKIN)") (pinfunction "PCKIN") (pintype "input"))
    (pad "B7" smd circle locked (at 1.624 -1.625 270) (size 0.3 0.3) (layers "F.Cu" "F.Paste" "F.Mask")
      (net 50 "CSI1_D3_N") (pinfunction "CSID2_N") (pintype "output"))
    (pad "B8" smd circle locked (at 2.274 -1.625 270) (size 0.3 0.3) (layers "F.Cu" "F.Paste" "F.Mask")
      (net 51 "CSI1_D3_P") (pinfunction "CSID2_P") (pintype "output"))
    (pad "C1" smd circle locked (at -2.275 -0.975 270) (size 0.3 0.3) (layers "F.Cu" "F.Paste" "F.Mask")
      (net 80 "/Channel 1/HDMI1_CLK_P") (pinfunction "HDMIC_P") (pintype "input"))
    (pad "C2" smd circle locked (at -1.625 -0.975 270) (size 0.3 0.3) (layers "F.Cu" "F.Paste" "F.Mask")
      (net 81 "/Channel 1/HDMI1_CLK_N") (pinfunction "HDMIC_N") (pintype "input"))
    (pad "C3" smd circle locked (at -0.975 -0.975 270) (size 0.3 0.3) (layers "F.Cu" "F.Paste" "F.Mask")
      (net 19 "Net-(C27-Pad2)") (pinfunction "VDDC2") (pintype "power_in"))
    (pad "C4" smd circle locked (at -0.326 -0.975 270) (size 0.3 0.3) (layers "F.Cu" "F.Paste" "F.Mask")
      (net 2 "GND") (pinfunction "GND") (pintype "passive"))
    (pad "C5" smd circle locked (at 0.325 -0.975 270) (size 0.3 0.3) (layers "F.Cu" "F.Paste" "F.Mask")
      (net 2 "GND") (pinfunction "GND") (pintype "passive"))
    (pad "C6" smd circle locked (at 0.974 -0.975 270) (size 0.3 0.3) (layers "F.Cu" "F.Paste" "F.Mask")
      (net 7 "Net-(C10-Pad2)") (pinfunction "VDD_MIPI") (pintype "power_in"))
    (pad "C7" smd circle locked (at 1.624 -0.975 270) (size 0.3 0.3) (layers "F.Cu" "F.Paste" "F.Mask")
      (net 56 "CSI1_CLK_N") (pinfunction "CSIC_N") (pintype "output"))
    (pad "C8" smd circle locked (at 2.274 -0.975 270) (size 0.3 0.3) (layers "F.Cu" "F.Paste" "F.Mask")
      (net 57 "CSI1_CLK_P") (pinfunction "CSIC_P") (pintype "output"))
    (pad "D1" smd circle locked (at -2.275 -0.326 270) (size 0.3 0.3) (layers "F.Cu" "F.Paste" "F.Mask")
      (net 78 "/Channel 1/HDMI1_D0_P") (pinfunction "HDMID0_P") (pintype "input"))
    (pad "D2" smd circle locked (at -1.625 -0.326 270) (size 0.3 0.3) (layers "F.Cu" "F.Paste" "F.Mask")
      (net 79 "/Channel 1/HDMI1_D0_N") (pinfunction "HDMID0_N") (pintype "input"))
    (pad "D3" smd circle locked (at -0.975 -0.326 270) (size 0.3 0.3) (layers "F.Cu" "F.Paste" "F.Mask")
      (net 6 "Net-(C5-Pad1)") (pinfunction "AVDD12") (pintype "passive"))
    (pad "D4" smd circle locked (at -0.326 -0.326 270) (size 0.3 0.3) (layers "F.Cu" "F.Paste" "F.Mask")
      (net 2 "GND") (pinfunction "GND") (pintype "passive"))
    (pad "D5" smd circle locked (at 0.325 -0.326 270) (size 0.3 0.3) (layers "F.Cu" "F.Paste" "F.Mask")
      (net 2 "GND") (pinfunction "GND") (pintype "passive"))
    (pad "D6" smd circle locked (at 0.974 -0.326 270) (size 0.3 0.3) (layers "F.Cu" "F.Paste" "F.Mask")
      (net 2 "GND") (pinfunction "GND") (pintype "passive"))
    (pad "D7" smd circle locked (at 1.624 -0.326 270) (size 0.3 0.3) (layers "F.Cu" "F.Paste" "F.Mask")
      (net 52 "CSI1_D2_N") (pinfunction "CSID1_N") (pintype "output"))
    (pad "D8" smd circle locked (at 2.274 -0.326 270) (size 0.3 0.3) (layers "F.Cu" "F.Paste" "F.Mask")
      (net 53 "CSI1_D2_P") (pinfunction "CSID1_P") (pintype "output"))
    (pad "E1" smd circle locked (at -2.275 0.325 270) (size 0.3 0.3) (layers "F.Cu" "F.Paste" "F.Mask")
      (net 76 "/Channel 1/HDMI1_D1_P") (pinfunction "HDMID1_P") (pintype "input"))
    (pad "E2" smd circle locked (at -1.625 0.325 270) (size 0.3 0.3) (layers "F.Cu" "F.Paste" "F.Mask")
      (net 77 "/Channel 1/HDMI1_D1_N") (pinfunction "HDMID1_N") (pintype "input"))
    (pad "E3" smd circle locked (at -0.975 0.325 270) (size 0.3 0.3) (layers "F.Cu" "F.Paste" "F.Mask")
      (net 2 "GND") (pinfunction "GND") (pintype "passive"))
    (pad "E4" smd circle locked (at -0.326 0.325 270) (size 0.3 0.3) (layers "F.Cu" "F.Paste" "F.Mask")
      (net 2 "GND") (pinfunction "GND") (pintype "passive"))
    (pad "E5" smd circle locked (at 0.325 0.325 270) (size 0.3 0.3) (layers "F.Cu" "F.Paste" "F.Mask")
      (net 2 "GND") (pinfunction "TEST") (pintype "input"))
    (pad "E6" smd circle locked (at 0.974 0.325 270) (size 0.3 0.3) (layers "F.Cu" "F.Paste" "F.Mask")
      (net 2 "GND") (pinfunction "GND") (pintype "passive"))
    (pad "E7" smd circle locked (at 1.624 0.325 270) (size 0.3 0.3) (layers "F.Cu" "F.Paste" "F.Mask")
      (net 54 "CSI1_D1_N") (pinfunction "CSID0_N") (pintype "output"))
    (pad "E8" smd circle locked (at 2.274 0.325 270) (size 0.3 0.3) (layers "F.Cu" "F.Paste" "F.Mask")
      (net 55 "CSI1_D1_P") (pinfunction "CSID0_P") (pintype "output"))
    (pad "F1" smd circle locked (at -2.275 0.974 270) (size 0.3 0.3) (layers "F.Cu" "F.Paste" "F.Mask")
      (net 74 "/Channel 1/HDMI1_D2_P") (pinfunction "HDMID2_P") (pintype "input"))
    (pad "F2" smd circle locked (at -1.625 0.974 270) (size 0.3 0.3) (layers "F.Cu" "F.Paste" "F.Mask")
      (net 75 "/Channel 1/HDMI1_D2_N") (pinfunction "HDMID2_N") (pintype "input"))
    (pad "F3" smd circle locked (at -0.975 0.974 270) (size 0.3 0.3) (layers "F.Cu" "F.Paste" "F.Mask")
      (net 100 "/Channel 1/CH1_AVDD33") (pinfunction "AVDD33") (pintype "passive"))
    (pad "F4" smd circle locked (at -0.326 0.974 270) (size 0.3 0.3) (layers "F.Cu" "F.Paste" "F.Mask")
      (net 20 "Net-(U1B-VDDIO1)") (pinfunction "VDDIO1") (pintype "power_in"))
    (pad "F5" smd circle locked (at 0.325 0.974 270) (size 0.3 0.3) (layers "F.Cu" "F.Paste" "F.Mask")
      (net 19 "Net-(C27-Pad2)") (pinfunction "VDDC2") (pintype "passive"))
    (pad "F6" smd circle locked (at 0.974 0.974 270) (size 0.3 0.3) (layers "F.Cu" "F.Paste" "F.Mask")
      (net 7 "Net-(C10-Pad2)") (pinfunction "VDD_MIPI") (pintype "passive"))
    (pad "F7" smd circle locked (at 1.624 0.974 270) (size 0.3 0.3) (layers "F.Cu" "F.Paste" "F.Mask")
      (net 126 "unconnected-(U1C-A_SCK-PadF7)") (pinfunction "A_SCK") (pintype "output+no_connect"))
    (pad "F8" smd circle locked (at 2.274 0.974 270) (size 0.3 0.3) (layers "F.Cu" "F.Paste" "F.Mask")
      (net 127 "unconnected-(U1C-A_SD-PadF8)") (pinfunction "A_SD") (pintype "output+no_connect"))
    (pad "G1" smd circle locked (at -2.275 1.624 270) (size 0.3 0.3) (layers "F.Cu" "F.Paste" "F.Mask")
      (net 82 "/Channel 1/HDMI1_CEC") (pinfunction "CEC") (pintype "bidirectional"))
    (pad "G2" smd circle locked (at -1.625 1.624 270) (size 0.3 0.3) (layers "F.Cu" "F.Paste" "F.Mask")
      (net 8 "Net-(U1B-VDDC1)") (pinfunction "VDDC1") (pintype "power_in"))
    (pad "G3" smd circle locked (at -0.975 1.624 270) (size 0.3 0.3) (layers "F.Cu" "F.Paste" "F.Mask")
      (net 104 "/Channel 1/HDMI1_DDC_SDA_3V3") (pinfunction "DDC_SDA") (pintype "bidirectional"))
    (pad "G4" smd circle locked (at -0.326 1.624 270) (size 0.3 0.3) (layers "F.Cu" "F.Paste" "F.Mask")
      (net 68 "I2C1_SDA") (pinfunction "I2C_SDA") (pintype "bidirectional"))
    (pad "G5" smd circle locked (at 0.325 1.624 270) (size 0.3 0.3) (layers "F.Cu" "F.Paste" "F.Mask")
      (net 98 "/Channel 1/CH1_~{RST}") (pinfunction "~{RESET}") (pintype "input"))
    (pad "G6" smd circle locked (at 0.974 1.624 270) (size 0.3 0.3) (layers "F.Cu" "F.Paste" "F.Mask")
      (net 116 "Net-(U1A-EDID_SDA)") (pinfunction "EDID_SDA") (pintype "bidirectional"))
    (pad "G7" smd circle locked (at 1.624 1.624 270) (size 0.3 0.3) (layers "F.Cu" "F.Paste" "F.Mask")
      (net 128 "unconnected-(U1C-A_WFS-PadG7)") (pinfunction "A_WFS") (pintype "output+no_connect"))
    (pad "G8" smd circle locked (at 2.274 1.624 270) (size 0.3 0.3) (layers "F.Cu" "F.Paste" "F.Mask")
      (net 129 "unconnected-(U1C-A_OSCK-PadG8)") (pinfunction "A_OSCK") (pintype "output+no_connect"))
    (pad "H1" smd circle locked (at -2.275 2.274 270) (size 0.3 0.3) (layers "F.Cu" "F.Paste" "F.Mask")
      (net 115 "/Channel 1/HDMI1_HPDO") (pinfunction "HPDO") (pintype "output"))
    (pad "H2" smd circle locked (at -1.625 2.274 270) (size 0.3 0.3) (layers "F.Cu" "F.Paste" "F.Mask")
      (net 97 "/Channel 1/HDMI1_HPDI") (pinfunction "HPDI") (pintype "input"))
    (pad "H3" smd circle locked (at -0.975 2.274 270) (size 0.3 0.3) (layers "F.Cu" "F.Paste" "F.Mask")
      (net 105 "/Channel 1/HDMI1_DDC_SCL_3V3") (pinfunction "DDC_SCL") (pintype "bidirectional"))
    (pad "H4" smd circle locked (at -0.326 2.274 270) (size 0.3 0.3) (layers "F.Cu" "F.Paste" "F.Mask")
      (net 69 "I2C1_SCL") (pinfunction "I2C_SCL") (pintype "bidirectional"))
    (pad "H5" smd circle locked (at 0.325 2.274 270) (size 0.3 0.3) (layers "F.Cu" "F.Paste" "F.Mask")
      (net 15 "/Channel 1/CH1_REFCLK") (pinfunction "REFCLK") (pintype "input"))
    (pad "H6" smd circle locked (at 0.974 2.274 270) (size 0.3 0.3) (layers "F.Cu" "F.Paste" "F.Mask")
      (net 117 "Net-(U1A-EDID_SCL)") (pinfunction "EDID_SCL") (pintype "bidirectional"))
    (pad "H7" smd circle locked (at 1.624 2.274 270) (size 0.3 0.3) (layers "F.Cu" "F.Paste" "F.Mask")
      (net 21 "Net-(U1B-VDDIO2)") (pinfunction "VDDIO2") (pintype "power_in"))
    (pad "H8" smd circle locked (at 2.274 2.274 270) (size 0.3 0.3) (layers "F.Cu" "F.Paste" "F.Mask")
      (net 2 "GND") (pinfunction "GND") (pintype "passive"))
  )

  (footprint "antmicro-footprints:C_0603_1608Metric" (layer "F.Cu")
    (at 147.6 118.95 180)
    (descr "Capacitor SMD 0603")
    (tags "capacitor 0603")
    (property "Author" "Antmicro")
    (property "Dielectric" "template_dielectric")
    (property "License" "Apache-2.0")
    (property "MPN" "GRM188R61A106KE69D")
    (property "Manufacturer" "Murata")
    (property "Public" "False")
    (property "Sheetfile" "channel1.kicad_sch")
    (property "Sheetname" "Channel 1")
    (property "Val" "10u")
    (property "Voltage" "")
    (property "ki_description" "SMD Multilayer Ceramic Capacitor, 10 µF, 10 V, 0603 [1608 Metric], ± 10%, X5R, GRM Series")
    (property "ki_keywords" "0603, SMT, CAPACITOR, PASSIVE, CERAMIC, MLCC")
    (attr smd)
    (fp_text reference "C17" (at -1.09 -1.45) (layer "F.SilkS")
        (effects (font (size 0.65 0.65) (thickness 0.13)) (justify right bottom))
    )
    (fp_text value "C_10u_0603" (at 0 1.6) (layer "F.Fab")
        (effects (font (size 0.65 0.65) (thickness 0.13)) (justify right bottom))
    )
    (fp_text user "${REFERENCE}" (at -1.682 3.895) (layer "F.Fab") hide
        (effects (font (size 0.7 0.7) (thickness 0.15)) (justify right bottom))
    )
    (fp_text user "Author: Antmicro" (at -1.682 4.894) (layer "F.Fab") hide
        (effects (font (size 0.7 0.7) (thickness 0.15)) (justify right bottom))
    )
    (fp_text user "License: Apache-2.0" (at -1.682 5.895) (layer "F.Fab") hide
        (effects (font (size 0.7 0.7) (thickness 0.15)) (justify right bottom))
    )
    (fp_line (start -0.15 -0.4) (end 0.15 -0.4)
      (stroke (width 0.15) (type solid)) (layer "F.SilkS"))
    (fp_line (start -0.15 0.4) (end 0.15 0.4)
      (stroke (width 0.15) (type solid)) (layer "F.SilkS"))
    (fp_rect (start -1.25 -0.65) (end 1.25 0.65)
      (stroke (width 0.05) (type solid)) (fill none) (layer "F.CrtYd"))
    (fp_rect (start -0.8 -0.4) (end 0.8 0.4)
      (stroke (width 0.15) (type solid)) (fill none) (layer "F.Fab"))
    (pad "1" smd roundrect (at -0.7 0 180) (size 0.8 1) (layers "F.Cu" "F.Paste" "F.Mask") (roundrect_rratio 0.2)
      (net 2 "GND") (pintype "passive"))
    (pad "2" smd roundrect (at 0.7 0 180) (size 0.8 1) (layers "F.Cu" "F.Paste" "F.Mask") (roundrect_rratio 0.2)
      (net 9 "+3V3") (pintype "passive"))
  )

  (footprint "antmicro-footprints:R_0402_1005Metric" (layer "F.Cu")
    (at 168.1 107.95 -90)
    (descr "Resistor SMD 0402")
    (tags "resistor SMD 0402")
    (property "Author" "Antmicro")
    (property "License" "Apache-2.0")
    (property "MPN" "CR0402-FX-1002GLF")
    (property "Manufacturer" "Bourns")
    (property "Public" "False")
    (property "Sheetfile" "channel2.kicad_sch")
    (property "Sheetname" "Channel 2")
    (property "Tolerance" "1%")
    (property "Val" "10k")
    (property "ki_description" "SMD Chip Resistor, 10 kohm, ± 1%, 62.5 mW, 0402 [1005 Metric], Thick Film, General Purpose")
    (property "ki_keywords" "0402, SMT, RESISTOR, PASSIVE")
    (attr smd)
    (fp_text reference "R23" (at 1.15 -2.4 -90) (layer "F.SilkS")
        (effects (font (size 0.65 0.65) (thickness 0.13)) (justify left bottom))
    )
    (fp_text value "R_10k_0402" (at 0 1.4 -90) (layer "F.Fab")
        (effects (font (size 0.65 0.65) (thickness 0.13)) (justify left bottom))
    )
    (fp_text user "${REFERENCE}" (at -0.95 3.168 -90) (layer "F.Fab") hide
        (effects (font (size 0.7 0.7) (thickness 0.15)) (justify left bottom))
    )
    (fp_text user "Author: Antmicro" (at -0.95 4.169 -90) (layer "F.Fab") hide
        (effects (font (size 0.7 0.7) (thickness 0.15)) (justify left bottom))
    )
    (fp_text user "License: Apache-2.0" (at -0.95 5.169 -90) (layer "F.Fab") hide
        (effects (font (size 0.7 0.7) (thickness 0.15)) (justify left bottom))
    )
    (fp_rect (start -0.925 -0.47) (end 0.925 0.47)
      (stroke (width 0.05) (type default)) (fill none) (layer "F.CrtYd"))
    (fp_rect (start -0.5 -0.25) (end 0.5 0.25)
      (stroke (width 0.15) (type solid)) (fill none) (layer "F.Fab"))
    (pad "1" smd roundrect (at -0.48 0 270) (size 0.59 0.64) (layers "F.Cu" "F.Paste" "F.Mask") (roundrect_rratio 0.25)
      (net 112 "/Channel 2/HDMI2_DDC_SCL_3V3") (pintype "passive"))
    (pad "2" smd roundrect (at 0.48 0 270) (size 0.59 0.64) (layers "F.Cu" "F.Paste" "F.Mask") (roundrect_rratio 0.25)
      (net 9 "+3V3") (pintype "passive"))
  )

  (footprint "antmicro-footprints:R_0603_1608Metric" (layer "F.Cu")
    (at 168.9 103.4)
    (descr "Resistor SMD 0603")
    (tags "resistor SMD 0603")
    (property "Author" "Antmicro")
    (property "Current" "1A")
    (property "License" "Apache-2.0")
    (property "MPN" "CR0603-J/-000ELF")
    (property "Manufacturer" "Bourns")
    (property "Public" "False")
    (property "Sheetfile" "channel2.kicad_sch")
    (property "Sheetname" "Channel 2")
    (property "Tolerance" "")
    (property "Val" "0R")
    (property "ki_description" "Zero Ohm Resistor, Jumper, 0603 [1608 Metric], Thick Film, 100 mW, 1 A, Surface Mount Device, CR")
    (property "ki_keywords" "0603, SMT, RESISTOR, PASSIVE")
    (attr smd)
    (fp_text reference "R15" (at 1.1 0.35) (layer "F.SilkS")
        (effects (font (size 0.7 0.7) (thickness 0.15)) (justify left bottom))
    )
    (fp_text value "R_0R_0603" (at 0 1.6) (layer "F.Fab")
        (effects (font (size 0.7 0.7) (thickness 0.15)) (justify left bottom))
    )
    (fp_text user "License: Apache-2.0" (at -1.25 5.9) (layer "F.Fab") hide
        (effects (font (size 0.7 0.7) (thickness 0.15)) (justify left bottom))
    )
    (fp_text user "${REFERENCE}" (at -1.25 3.898) (layer "F.Fab") hide
        (effects (font (size 0.7 0.7) (thickness 0.15)) (justify left bottom))
    )
    (fp_text user "Author: Antmicro" (at -1.25 4.9) (layer "F.Fab") hide
        (effects (font (size 0.7 0.7) (thickness 0.15)) (justify left bottom))
    )
    (fp_line (start -0.15 -0.4) (end 0.15 -0.4)
      (stroke (width 0.15) (type solid)) (layer "F.SilkS"))
    (fp_line (start -0.15 0.4) (end 0.15 0.4)
      (stroke (width 0.15) (type solid)) (layer "F.SilkS"))
    (fp_rect (start -1.25 -0.65) (end 1.25 0.65)
      (stroke (width 0.05) (type solid)) (fill none) (layer "F.CrtYd"))
    (fp_rect (start -0.8 -0.4) (end 0.8 0.4)
      (stroke (width 0.15) (type solid)) (fill none) (layer "F.Fab"))
    (pad "1" smd roundrect (at -0.7 0) (size 0.8 1) (layers "F.Cu" "F.Paste" "F.Mask") (roundrect_rratio 0.2)
      (net 96 "/Channel 2/HDMI2_POWER") (pintype "passive"))
    (pad "2" smd roundrect (at 0.7 0) (size 0.8 1) (layers "F.Cu" "F.Paste" "F.Mask") (roundrect_rratio 0.2)
      (net 106 "/Channel 2/HDMI2_HPDI") (pintype "passive"))
  )

  (footprint "antmicro-footprints:C_0603_1608Metric" (layer "F.Cu")
    (at 163.94 107.03 180)
    (descr "Capacitor SMD 0603")
    (tags "capacitor 0603")
    (property "Author" "Antmicro")
    (property "Dielectric" "")
    (property "License" "Apache-2.0")
    (property "MPN" "C1608X5R1V475M080AC")
    (property "Manufacturer" "TDK")
    (property "Public" "False")
    (property "Sheetfile" "channel2.kicad_sch")
    (property "Sheetname" "Channel 2")
    (property "Val" "4u7")
    (property "Voltage" "")
    (property "ki_description" "SMD Multilayer Ceramic Capacitor, 4.7 µF, 35 V, 0603 [1608 Metric], ± 20%, X5R, C")
    (property "ki_keywords" "0603, SMT, CAPACITOR, PASSIVE, CERAMIC, MLCC")
    (attr smd)
    (fp_text reference "C52" (at 1.42 -0.15) (layer "F.SilkS")
        (effects (font (size 0.65 0.65) (thickness 0.13)) (justify right bottom))
    )
    (fp_text value "C_4u7_0603" (at 0 1.6) (layer "F.Fab")
        (effects (font (size 0.65 0.65) (thickness 0.13)) (justify right bottom))
    )
    (fp_text user "Author: Antmicro" (at -1.682 4.894) (layer "F.Fab") hide
        (effects (font (size 0.7 0.7) (thickness 0.15)) (justify right bottom))
    )
    (fp_text user "License: Apache-2.0" (at -1.682 5.895) (layer "F.Fab") hide
        (effects (font (size 0.7 0.7) (thickness 0.15)) (justify right bottom))
    )
    (fp_text user "${REFERENCE}" (at -1.682 3.895) (layer "F.Fab") hide
        (effects (font (size 0.7 0.7) (thickness 0.15)) (justify right bottom))
    )
    (fp_line (start -0.15 -0.4) (end 0.15 -0.4)
      (stroke (width 0.15) (type solid)) (layer "F.SilkS"))
    (fp_line (start -0.15 0.4) (end 0.15 0.4)
      (stroke (width 0.15) (type solid)) (layer "F.SilkS"))
    (fp_rect (start -1.25 -0.65) (end 1.25 0.65)
      (stroke (width 0.05) (type solid)) (fill none) (layer "F.CrtYd"))
    (fp_rect (start -0.8 -0.4) (end 0.8 0.4)
      (stroke (width 0.15) (type solid)) (fill none) (layer "F.Fab"))
    (pad "1" smd roundrect (at -0.7 0 180) (size 0.8 1) (layers "F.Cu" "F.Paste" "F.Mask") (roundrect_rratio 0.2)
      (net 2 "GND") (pintype "passive"))
    (pad "2" smd roundrect (at 0.7 0 180) (size 0.8 1) (layers "F.Cu" "F.Paste" "F.Mask") (roundrect_rratio 0.2)
      (net 109 "Net-(C48-Pad1)") (pintype "passive"))
  )

  (footprint "antmicro-footprints:C_0402_1005Metric" (layer "F.Cu")
    (at 155.015 109.45)
    (descr "Capacitor SMD 0402")
    (tags "capacitor SMD 0402")
    (property "Author" "Antmicro")
    (property "Dielectric" "X5R")
    (property "License" "Apache-2.0")
    (property "MPN" "GRM155R61H104KE14D")
    (property "Manufacturer" "Murata")
    (property "Public" "False")
    (property "Sheetfile" "channel2.kicad_sch")
    (property "Sheetname" "Channel 2")
    (property "Val" "100n")
    (property "Voltage" "50V")
    (property "ki_description" "SMD Multilayer Ceramic Capacitor, 0.1 µF, 50 V, 0402 [1005 Metric], ± 10%, X5R, GRM Series")
    (property "ki_keywords" "0402, SMT, CAPACITOR, PASSIVE, CERAMIC, MLCC")
    (attr smd)
    (fp_text reference "C34" (at -1.515 7.55) (layer "F.SilkS")
        (effects (font (size 0.65 0.65) (thickness 0.13)) (justify left bottom))
    )
    (fp_text value "C_100n_0402" (at 0 1.4) (layer "F.Fab")
        (effects (font (size 0.65 0.65) (thickness 0.13)) (justify left bottom))
    )
    (fp_text user "${REFERENCE}" (at -0.932 3.168) (layer "F.Fab") hide
        (effects (font (size 0.7 0.7) (thickness 0.15)) (justify left bottom))
    )
    (fp_text user "Author: Antmicro" (at -0.932 4.17) (layer "F.Fab") hide
        (effects (font (size 0.7 0.7) (thickness 0.15)) (justify left bottom))
    )
    (fp_text user "License: Apache-2.0" (at -0.932 5.17) (layer "F.Fab") hide
        (effects (font (size 0.7 0.7) (thickness 0.15)) (justify left bottom))
    )
    (fp_rect (start -0.925 -0.47) (end 0.925 0.47)
      (stroke (width 0.05) (type default)) (fill none) (layer "F.CrtYd"))
    (fp_line (start -0.494 -0.25) (end 0.504 -0.25)
      (stroke (width 0.15) (type solid)) (layer "F.Fab"))
    (fp_line (start -0.494 0.248) (end -0.494 -0.25)
      (stroke (width 0.15) (type solid)) (layer "F.Fab"))
    (fp_line (start 0.504 -0.25) (end 0.504 0.248)
      (stroke (width 0.15) (type solid)) (layer "F.Fab"))
    (fp_line (start 0.504 0.248) (end -0.494 0.248)
      (stroke (width 0.15) (type solid)) (layer "F.Fab"))
    (pad "1" smd roundrect (at -0.48 0) (size 0.59 0.64) (layers "F.Cu" "F.Paste" "F.Mask") (roundrect_rratio 0.25)
      (net 2 "GND") (pintype "passive"))
    (pad "2" smd roundrect (at 0.48 0) (size 0.59 0.64) (layers "F.Cu" "F.Paste" "F.Mask") (roundrect_rratio 0.25)
      (net 108 "/Channel 2/CH2_AVDD33") (pintype "passive"))
  )

  (footprint "antmicro-footprints:Oscillator_SMD_TXC_7C_5x3.2x1.2mm" (layer "F.Cu")
    (at 150.81 110.06)
    (property "Author" "Antmicro")
    (property "License" "Apache-2.0")
    (property "MPN" "7C-27.000MBB-T")
    (property "Manufacturer" "TXC")
    (property "Public" "False")
    (property "Sheetfile" "channel2.kicad_sch")
    (property "Sheetname" "Channel 2")
    (property "Val" "27 MHz")
    (property "ki_description" "Oscillator, 27 MHz, 50 ppm, SMT, 5mm x 3.2mm, 3.3 V, 7C Series")
    (property "ki_keywords" "OSCILLATOR")
    (attr smd)
    (fp_text reference "Y2" (at 1.53 3.65 180) (layer "F.SilkS")
        (effects (font (size 0.65 0.65) (thickness 0.13)) (justify right bottom))
    )
    (fp_text value "Oscillator_27MHz_TXC_7C" (at -4.1148 3.4544) (layer "F.Fab")
        (effects (font (size 0.65 0.65) (thickness 0.13)) (justify left bottom))
    )
    (fp_text user "License: Apache-2.0" (at -2.668 7.972) (layer "F.Fab") hide
        (effects (font (size 0.7 0.7) (thickness 0.15)) (justify left bottom))
    )
    (fp_text user "${REFERENCE}" (at -2.668 5.573) (layer "F.Fab") hide
        (effects (font (size 0.7 0.7) (thickness 0.15)) (justify left bottom))
    )
    (fp_text user "Author: Antmicro" (at -2.668 6.773) (layer "F.Fab") hide
        (effects (font (size 0.7 0.7) (thickness 0.15)) (justify left bottom))
    )
    (fp_line (start -1.7 1.1) (end -1.7 -1.1)
      (stroke (width 0.12) (type solid)) (layer "F.SilkS"))
    (fp_line (start -0.4 -2.6) (end 0.4 -2.6)
      (stroke (width 0.12) (type solid)) (layer "F.SilkS"))
    (fp_line (start -0.4 2.6) (end 0.4 2.6)
      (stroke (width 0.12) (type solid)) (layer "F.SilkS"))
    (fp_line (start 1.7 1.1) (end 1.7 -1.1)
      (stroke (width 0.12) (type solid)) (layer "F.SilkS"))
    (fp_circle (center -1.8438 -2.2532) (end -1.8438 -2.2032)
      (stroke (width 0.15) (type solid)) (fill solid) (layer "F.SilkS"))
    (fp_rect (start -1.9 -2.85) (end 1.9 2.8)
      (stroke (width 0.05) (type solid)) (fill none) (layer "F.CrtYd"))
    (pad "1" smd rect (at -1.099 -1.9 270) (size 1.4 1.2) (layers "F.Cu" "F.Paste" "F.Mask")
      (net 30 "Net-(Y2-EN)") (pinfunction "EN") (pintype "input"))
    (pad "2" smd rect (at -1.1 1.9 270) (size 1.4 1.2) (layers "F.Cu" "F.Paste" "F.Mask")
      (net 2 "GND") (pinfunction "GND") (pintype "power_in"))
    (pad "3" smd rect (at 1.099 1.9 270) (size 1.4 1.2) (layers "F.Cu" "F.Paste" "F.Mask")
      (net 31 "Net-(Y2-OUT)") (pinfunction "OUT") (pintype "output"))
    (pad "4" smd rect (at 1.1 -1.9 270) (size 1.4 1.2) (layers "F.Cu" "F.Paste" "F.Mask")
      (net 30 "Net-(Y2-EN)") (pinfunction "VDD") (pintype "power_in"))
  )

  (footprint "antmicro-footprints:C_0603_1608Metric" (layer "F.Cu")
    (at 169.2 115.7 -90)
    (descr "Capacitor SMD 0603")
    (tags "capacitor 0603")
    (property "Author" "Antmicro")
    (property "Dielectric" "template_dielectric")
    (property "License" "Apache-2.0")
    (property "MPN" "GRM188R61A106KE69D")
    (property "Manufacturer" "Murata")
    (property "Public" "False")
    (property "Sheetfile" "channel2.kicad_sch")
    (property "Sheetname" "Channel 2")
    (property "Val" "10u")
    (property "Voltage" "")
    (property "ki_description" "SMD Multilayer Ceramic Capacitor, 10 µF, 10 V, 0603 [1608 Metric], ± 10%, X5R, GRM Series")
    (property "ki_keywords" "0603, SMT, CAPACITOR, PASSIVE, CERAMIC, MLCC")
    (attr smd)
    (fp_text reference "C43" (at -3.3 -0.4 90) (layer "F.SilkS")
        (effects (font (size 0.65 0.65) (thickness 0.13)) (justify right bottom))
    )
    (fp_text value "C_10u_0603" (at 0 1.6 90) (layer "F.Fab")
        (effects (font (size 0.65 0.65) (thickness 0.13)) (justify right bottom))
    )
    (fp_text user "Author: Antmicro" (at -1.682 4.894 90) (layer "F.Fab") hide
        (effects (font (size 0.7 0.7) (thickness 0.15)) (justify right bottom))
    )
    (fp_text user "${REFERENCE}" (at -1.682 3.895 90) (layer "F.Fab") hide
        (effects (font (size 0.7 0.7) (thickness 0.15)) (justify right bottom))
    )
    (fp_text user "License: Apache-2.0" (at -1.682 5.895 90) (layer "F.Fab") hide
        (effects (font (size 0.7 0.7) (thickness 0.15)) (justify right bottom))
    )
    (fp_line (start -0.15 -0.4) (end 0.15 -0.4)
      (stroke (width 0.15) (type solid)) (layer "F.SilkS"))
    (fp_line (start -0.15 0.4) (end 0.15 0.4)
      (stroke (width 0.15) (type solid)) (layer "F.SilkS"))
    (fp_rect (start -1.25 -0.65) (end 1.25 0.65)
      (stroke (width 0.05) (type solid)) (fill none) (layer "F.CrtYd"))
    (fp_rect (start -0.8 -0.4) (end 0.8 0.4)
      (stroke (width 0.15) (type solid)) (fill none) (layer "F.Fab"))
    (pad "1" smd roundrect (at -0.7 0 270) (size 0.8 1) (layers "F.Cu" "F.Paste" "F.Mask") (roundrect_rratio 0.2)
      (net 2 "GND") (pintype "passive"))
    (pad "2" smd roundrect (at 0.7 0 270) (size 0.8 1) (layers "F.Cu" "F.Paste" "F.Mask") (roundrect_rratio 0.2)
      (net 25 "CH2_1V2") (pintype "passive"))
  )

  (footprint "antmicro-footprints:OSHW-Logo_7.5x8mm_Mask" (layer "F.Cu")
    (at 178 123.3 -90)
    (descr "Open Source Hardware Logo")
    (tags "Logo OSHW")
    (property "Author" "Antmicro")
    (property "License" "Apache-2.0")
    (property "MPN" "")
    (property "Manufacturer" "")
    (property "Public" "False")
    (property "Sheetfile" "antmicro-hdmi-mipi-bridge-hw.kicad_sch")
    (property "Sheetname" "")
    (property "exclude_from_bom" "")
    (property "ki_description" "Mechanical part")
    (attr exclude_from_pos_files exclude_from_bom)
    (fp_text reference "N2" (at 0 0 90) (layer "F.SilkS") hide
        (effects (font (size 1 1) (thickness 0.15)))
    )
    (fp_text value "oshw_logo" (at 0.75 0 90) (layer "F.Fab") hide
        (effects (font (size 1 1) (thickness 0.15)))
    )
    (fp_poly
      (pts
        (xy 2.391388 1.937645)
        (xy 2.448865 1.955206)
        (xy 2.485872 1.977395)
        (xy 2.497927 1.994942)
        (xy 2.494609 2.015742)
        (xy 2.473079 2.048419)
        (xy 2.454874 2.071562)
        (xy 2.417344 2.113402)
        (xy 2.389148 2.131005)
        (xy 2.365111 2.129856)
        (xy 2.293808 2.11171)
        (xy 2.241442 2.112534)
        (xy 2.198918 2.133098)
        (xy 2.184642 2.145134)
        (xy 2.138947 2.187483)
        (xy 2.138947 2.740526)
        (xy 1.955131 2.740526)
        (xy 1.955131 1.938421)
        (xy 2.047039 1.938421)
        (xy 2.102219 1.940603)
        (xy 2.130688 1.948351)
        (xy 2.138943 1.963468)
        (xy 2.138947 1.963916)
        (xy 2.142845 1.979749)
        (xy 2.160474 1.977684)
        (xy 2.184901 1.966261)
        (xy 2.23535 1.945005)
        (xy 2.276316 1.932216)
        (xy 2.329028 1.928938)
        (xy 2.391388 1.937645)
      )

      (stroke (width 0.01) (type solid)) (fill solid) (layer "F.Mask"))
    (fp_poly
      (pts
        (xy 2.173167 3.191447)
        (xy 2.237408 3.204112)
        (xy 2.27398 3.222864)
        (xy 2.312453 3.254017)
        (xy 2.257717 3.323127)
        (xy 2.223969 3.364979)
        (xy 2.201053 3.385398)
        (xy 2.178279 3.388517)
        (xy 2.144956 3.378472)
        (xy 2.129314 3.372789)
        (xy 2.065542 3.364404)
        (xy 2.00714 3.382378)
        (xy 1.964264 3.422982)
        (xy 1.957299 3.435929)
        (xy 1.949713 3.470224)
        (xy 1.943859 3.533427)
        (xy 1.940011 3.62106)
        (xy 1.938443 3.72864)
        (xy 1.938421 3.743944)
        (xy 1.938421 4.010526)
        (xy 1.754605 4.010526)
        (xy 1.754605 3.19171)
        (xy 1.846513 3.19171)
        (xy 1.899507 3.193094)
        (xy 1.927115 3.199252)
        (xy 1.937324 3.213194)
        (xy 1.938421 3.226344)
        (xy 1.938421 3.260978)
        (xy 1.98245 3.226344)
        (xy 2.032937 3.202716)
        (xy 2.10076 3.191033)
        (xy 2.173167 3.191447)
      )

      (stroke (width 0.01) (type solid)) (fill solid) (layer "F.Mask"))
    (fp_poly
      (pts
        (xy -1.320119 3.193486)
        (xy -1.295112 3.200982)
        (xy -1.28705 3.217451)
        (xy -1.286711 3.224886)
        (xy -1.285264 3.245594)
        (xy -1.275302 3.248845)
        (xy -1.248388 3.234648)
        (xy -1.232402 3.224948)
        (xy -1.181967 3.204175)
        (xy -1.121728 3.193904)
        (xy -1.058566 3.193114)
        (xy -0.999363 3.200786)
        (xy -0.950998 3.215898)
        (xy -0.920354 3.237432)
        (xy -0.914311 3.264366)
        (xy -0.917361 3.27166)
        (xy -0.939594 3.301937)
        (xy -0.97407 3.339175)
        (xy -0.980306 3.345195)
        (xy -1.013167 3.372875)
        (xy -1.04152 3.381818)
        (xy -1.081173 3.375576)
        (xy -1.097058 3.371429)
        (xy -1.146491 3.361467)
        (xy -1.181248 3.365947)
        (xy -1.2106 3.381746)
        (xy -1.237487 3.402949)
        (xy -1.25729 3.429614)
        (xy -1.271052 3.466827)
        (xy -1.279816 3.519673)
        (xy -1.284626 3.593237)
        (xy -1.286526 3.692605)
        (xy -1.286711 3.752601)
        (xy -1.286711 4.010526)
        (xy -1.453816 4.010526)
        (xy -1.453816 3.19171)
        (xy -1.370264 3.19171)
        (xy -1.320119 3.193486)
      )

      (stroke (width 0.01) (type solid)) (fill solid) (layer "F.Mask"))
    (fp_poly
      (pts
        (xy 1.320131 2.198533)
        (xy 1.32171 2.321089)
        (xy 1.327481 2.414179)
        (xy 1.338991 2.481651)
        (xy 1.35779 2.527355)
        (xy 1.385426 2.555139)
        (xy 1.423448 2.568854)
        (xy 1.470526 2.572358)
        (xy 1.519832 2.568432)
        (xy 1.557283 2.554089)
        (xy 1.584428 2.525478)
        (xy 1.602815 2.478751)
        (xy 1.613993 2.410058)
        (xy 1.619511 2.31555)
        (xy 1.620921 2.198533)
        (xy 1.620921 1.938421)
        (xy 1.804736 1.938421)
        (xy 1.804736 2.740526)
        (xy 1.712828 2.740526)
        (xy 1.657422 2.738281)
        (xy 1.628891 2.730396)
        (xy 1.620921 2.715428)
        (xy 1.61612 2.702097)
        (xy 1.597014 2.704917)
        (xy 1.558504 2.723783)
        (xy 1.470239 2.752887)
        (xy 1.376623 2.750825)
        (xy 1.286921 2.719221)
        (xy 1.244204 2.694257)
        (xy 1.211621 2.667226)
        (xy 1.187817 2.633405)
        (xy 1.171439 2.588068)
        (xy 1.161131 2.526489)
        (xy 1.155541 2.443943)
        (xy 1.153312 2.335705)
        (xy 1.153026 2.252004)
        (xy 1.153026 1.938421)
        (xy 1.320131 1.938421)
        (xy 1.320131 2.198533)
      )

      (stroke (width 0.01) (type solid)) (fill solid) (layer "F.Mask"))
    (fp_poly
      (pts
        (xy -1.002043 1.952226)
        (xy -0.960454 1.97209)
        (xy -0.920175 2.000784)
        (xy -0.88949 2.033809)
        (xy -0.867139 2.075931)
        (xy -0.851864 2.131915)
        (xy -0.842408 2.206528)
        (xy -0.837513 2.304535)
        (xy -0.835919 2.430702)
        (xy -0.835894 2.443914)
        (xy -0.835527 2.740526)
        (xy -1.019343 2.740526)
        (xy -1.019343 2.467081)
        (xy -1.019473 2.365777)
        (xy -1.020379 2.292353)
        (xy -1.022827 2.241271)
        (xy -1.027586 2.20699)
        (xy -1.035426 2.183971)
        (xy -1.047115 2.166673)
        (xy -1.063398 2.149581)
        (xy -1.120366 2.112857)
        (xy -1.182555 2.106042)
        (xy -1.241801 2.129261)
        (xy -1.262405 2.146543)
        (xy -1.27753 2.162791)
        (xy -1.28839 2.180191)
        (xy -1.29569 2.204212)
        (xy -1.300137 2.240322)
        (xy -1.302436 2.293988)
        (xy -1.303296 2.37068)
        (xy -1.303422 2.464043)
        (xy -1.303422 2.740526)
        (xy -1.487237 2.740526)
        (xy -1.487237 1.938421)
        (xy -1.395329 1.938421)
        (xy -1.340149 1.940603)
        (xy -1.31168 1.948351)
        (xy -1.303425 1.963468)
        (xy -1.303422 1.963916)
        (xy -1.299592 1.97872)
        (xy -1.282699 1.97704)
        (xy -1.249112 1.960773)
        (xy -1.172937 1.93684)
        (xy -1.0858 1.934178)
        (xy -1.002043 1.952226)
      )

      (stroke (width 0.01) (type solid)) (fill solid) (layer "F.Mask"))
    (fp_poly
      (pts
        (xy 2.946576 1.945419)
        (xy 3.043395 1.986549)
        (xy 3.07389 2.006571)
        (xy 3.112865 2.03734)
        (xy 3.137331 2.061533)
        (xy 3.141578 2.069413)
        (xy 3.129584 2.086899)
        (xy 3.098887 2.11657)
        (xy 3.074312 2.137279)
        (xy 3.007046 2.191336)
        (xy 2.95393 2.146642)
        (xy 2.912884 2.117789)
        (xy 2.872863 2.107829)
        (xy 2.827059 2.110261)
        (xy 2.754324 2.128345)
        (xy 2.704256 2.165881)
        (xy 2.673829 2.226562)
        (xy 2.660017 2.314081)
        (xy 2.660013 2.314136)
        (xy 2.661208 2.411958)
        (xy 2.679772 2.48373)
        (xy 2.716804 2.532595)
        (xy 2.74205 2.549143)
        (xy 2.809097 2.569749)
        (xy 2.880709 2.569762)
        (xy 2.943015 2.549768)
        (xy 2.957763 2.54)
        (xy 2.99475 2.515047)
        (xy 3.023668 2.510958)
        (xy 3.054856 2.52953)
        (xy 3.089336 2.562887)
        (xy 3.143912 2.619196)
        (xy 3.083318 2.669142)
        (xy 2.989698 2.725513)
        (xy 2.884125 2.753293)
        (xy 2.773798 2.751282)
        (xy 2.701343 2.732862)
        (xy 2.616656 2.68731)
        (xy 2.548927 2.61565)
        (xy 2.518157 2.565066)
        (xy 2.493236 2.492488)
        (xy 2.480766 2.400569)
        (xy 2.48067 2.300948)
        (xy 2.49287 2.205267)
        (xy 2.51729 2.125169)
        (xy 2.521136 2.116956)
        (xy 2.578093 2.036413)
        (xy 2.655209 1.977771)
        (xy 2.74639 1.942247)
        (xy 2.845543 1.931057)
        (xy 2.946576 1.945419)
      )

      (stroke (width 0.01) (type solid)) (fill solid) (layer "F.Mask"))
    (fp_poly
      (pts
        (xy 0.811669 1.94831)
        (xy 0.896192 1.99434)
        (xy 0.962321 2.067006)
        (xy 0.993478 2.126106)
        (xy 1.006855 2.178305)
        (xy 1.015522 2.252719)
        (xy 1.019237 2.338442)
        (xy 1.017754 2.424569)
        (xy 1.010831 2.500193)
        (xy 1.002745 2.540584)
        (xy 0.975465 2.59584)
        (xy 0.92822 2.65453)
        (xy 0.871282 2.705852)
        (xy 0.814924 2.739005)
        (xy 0.81355 2.739531)
        (xy 0.743616 2.754018)
        (xy 0.660737 2.754377)
        (xy 0.581977 2.741188)
        (xy 0.551566 2.730617)
        (xy 0.473239 2.686201)
        (xy 0.417143 2.628007)
        (xy 0.380286 2.550965)
        (xy 0.35968 2.450001)
        (xy 0.355018 2.397116)
        (xy 0.355613 2.330663)
        (xy 0.534736 2.330663)
        (xy 0.54077 2.42763)
        (xy 0.558138 2.501523)
        (xy 0.58574 2.548736)
        (xy 0.605404 2.562237)
        (xy 0.655787 2.571651)
        (xy 0.715673 2.568864)
        (xy 0.767449 2.555316)
        (xy 0.781027 2.547862)
        (xy 0.816849 2.504451)
        (xy 0.840493 2.438014)
        (xy 0.850558 2.357161)
        (xy 0.845642 2.270502)
        (xy 0.834655 2.218349)
        (xy 0.803109 2.157951)
        (xy 0.753311 2.120197)
        (xy 0.693337 2.107143)
        (xy 0.631264 2.120849)
        (xy 0.583582 2.154372)
        (xy 0.558525 2.182031)
        (xy 0.5439 2.209294)
        (xy 0.536929 2.24619)
        (xy 0.534833 2.30275)
        (xy 0.534736 2.330663)
        (xy 0.355613 2.330663)
        (xy 0.356282 2.255994)
        (xy 0.379265 2.140271)
        (xy 0.423972 2.049941)
        (xy 0.490405 1.985)
        (xy 0.578565 1.945445)
        (xy 0.597495 1.940858)
        (xy 0.711266 1.93009)
        (xy 0.811669 1.94831)
      )

      (stroke (width 0.01) (type solid)) (fill solid) (layer "F.Mask"))
    (fp_poly
      (pts
        (xy 0.37413 3.195104)
        (xy 0.44022 3.200066)
        (xy 0.526626 3.459079)
        (xy 0.613031 3.718092)
        (xy 0.640124 3.626184)
        (xy 0.656428 3.569384)
        (xy 0.677875 3.492625)
        (xy 0.701035 3.408251)
        (xy 0.71328 3.362993)
        (xy 0.759344 3.19171)
        (xy 0.949387 3.19171)
        (xy 0.892582 3.371349)
        (xy 0.864607 3.459704)
        (xy 0.830813 3.566281)
        (xy 0.79552 3.677454)
        (xy 0.764013 3.776579)
        (xy 0.69225 4.002171)
        (xy 0.537286 4.012253)
        (xy 0.49527 3.873528)
        (xy 0.469359 3.787351)
        (xy 0.441083 3.692347)
        (xy 0.416369 3.608441)
        (xy 0.415394 3.605102)
        (xy 0.396935 3.548248)
        (xy 0.380649 3.509456)
        (xy 0.369242 3.494787)
        (xy 0.366898 3.496483)
        (xy 0.358671 3.519225)
        (xy 0.343038 3.56794)
        (xy 0.321904 3.636502)
        (xy 0.29717 3.718785)
        (xy 0.283787 3.764046)
        (xy 0.211311 4.010526)
        (xy 0.057495 4.010526)
        (xy -0.065469 3.622006)
        (xy -0.100012 3.513022)
        (xy -0.131479 3.414048)
        (xy -0.158384 3.329736)
        (xy -0.179241 3.264734)
        (xy -0.192562 3.223692)
        (xy -0.196612 3.211701)
        (xy -0.193406 3.199423)
        (xy -0.168235 3.194046)
        (xy -0.115854 3.194584)
        (xy -0.107655 3.19499)
        (xy -0.010518 3.200066)
        (xy 0.0531 3.434013)
        (xy 0.076484 3.519333)
        (xy 0.097381 3.594335)
        (xy 0.113951 3.652507)
        (xy 0.124354 3.687337)
        (xy 0.126276 3.693016)
        (xy 0.134241 3.686486)
        (xy 0.150304 3.652654)
        (xy 0.172621 3.596127)
        (xy 0.199345 3.52151)
        (xy 0.221937 3.454107)
        (xy 0.308041 3.190143)
        (xy 0.37413 3.195104)
      )

      (stroke (width 0.01) (type solid)) (fill solid) (layer "F.Mask"))
    (fp_poly
      (pts
        (xy -3.373216 1.947104)
        (xy -3.285795 1.985754)
        (xy -3.21943 2.05029)
        (xy -3.174024 2.140812)
        (xy -3.149482 2.257418)
        (xy -3.147723 2.275624)
        (xy -3.146344 2.403984)
        (xy -3.164216 2.516496)
        (xy -3.20025 2.607688)
        (xy -3.219545 2.637022)
        (xy -3.286755 2.699106)
        (xy -3.37235 2.739316)
        (xy -3.46811 2.756003)
        (xy -3.565813 2.747517)
        (xy -3.640083 2.72138)
        (xy -3.703953 2.677335)
        (xy -3.756154 2.619587)
        (xy -3.757057 2.618236)
        (xy -3.778256 2.582593)
        (xy -3.792033 2.546752)
        (xy -3.800376 2.501519)
        (xy -3.805273 2.437701)
        (xy -3.807431 2.385368)
        (xy -3.808329 2.33791)
        (xy -3.641257 2.33791)
        (xy -3.639624 2.385154)
        (xy -3.633696 2.448046)
        (xy -3.623239 2.488407)
        (xy -3.604381 2.517122)
        (xy -3.586719 2.533896)
        (xy -3.524106 2.569016)
        (xy -3.458592 2.57371)
        (xy -3.397579 2.54844)
        (xy -3.367072 2.520124)
        (xy -3.345089 2.491589)
        (xy -3.332231 2.464284)
        (xy -3.326588 2.42875)
        (xy -3.326249 2.375524)
        (xy -3.327988 2.326506)
        (xy -3.331729 2.256482)
        (xy -3.337659 2.211064)
        (xy -3.348347 2.18144)
        (xy -3.366361 2.158797)
        (xy -3.380637 2.145855)
        (xy -3.440349 2.11186)
        (xy -3.504766 2.110165)
        (xy -3.558781 2.130301)
        (xy -3.60486 2.172352)
        (xy -3.632311 2.241428)
        (xy -3.641257 2.33791)
        (xy -3.808329 2.33791)
        (xy -3.809401 2.281299)
        (xy -3.806036 2.203468)
        (xy -3.795955 2.14493)
        (xy -3.777774 2.098737)
        (xy -3.75011 2.057942)
        (xy -3.739854 2.045828)
        (xy -3.675722 1.985474)
        (xy -3.606934 1.95022)
        (xy -3.522811 1.93545)
        (xy -3.481791 1.934243)
        (xy -3.373216 1.947104)
      )

      (stroke (width 0.01) (type solid)) (fill solid) (layer "F.Mask"))
    (fp_poly
      (pts
        (xy -0.267369 4.010526)
        (xy -0.359277 4.010526)
        (xy -0.412623 4.008962)
        (xy -0.440407 4.002485)
        (xy -0.45041 3.988418)
        (xy -0.451185 3.978906)
        (xy -0.452872 3.959832)
        (xy -0.46351 3.956174)
        (xy -0.491465 3.967932)
        (xy -0.513205 3.978906)
        (xy -0.596668 4.004911)
        (xy -0.687396 4.006416)
        (xy -0.761158 3.987021)
        (xy -0.829846 3.940165)
        (xy -0.882206 3.871004)
        (xy -0.910878 3.789427)
        (xy -0.911608 3.784866)
        (xy -0.915868 3.735101)
        (xy -0.917986 3.663659)
        (xy -0.917816 3.609626)
        (xy -0.73528 3.609626)
        (xy -0.731051 3.681441)
        (xy -0.721432 3.740634)
        (xy -0.70841 3.77406)
        (xy -0.659144 3.81974)
        (xy -0.60065 3.836115)
        (xy -0.540329 3.822873)
        (xy -0.488783 3.783373)
        (xy -0.469262 3.756807)
        (xy -0.457848 3.725106)
        (xy -0.452502 3.678832)
        (xy -0.451185 3.609328)
        (xy -0.453542 3.540499)
        (xy -0.459767 3.480026)
        (xy -0.468592 3.439556)
        (xy -0.470063 3.435929)
        (xy -0.505653 3.392802)
        (xy -0.5576 3.369124)
        (xy -0.615722 3.365301)
        (xy -0.66984 3.381738)
        (xy -0.709774 3.41884)
        (xy -0.713917 3.426222)
        (xy -0.726884 3.471239)
        (xy -0.733948 3.535967)
        (xy -0.73528 3.609626)
        (xy -0.917816 3.609626)
        (xy -0.917729 3.58223)
        (xy -0.916528 3.538405)
        (xy -0.908355 3.429988)
        (xy -0.89137 3.348588)
        (xy -0.863113 3.288412)
        (xy -0.821128 3.243666)
        (xy -0.780368 3.2174)
        (xy -0.723419 3.198935)
        (xy -0.652589 3.192602)
        (xy -0.580059 3.19776)
        (xy -0.518014 3.213769)
        (xy -0.485232 3.23292)
        (xy -0.451185 3.263732)
        (xy -0.451185 2.87421)
        (xy -0.267369 2.87421)
        (xy -0.267369 4.010526)
      )

      (stroke (width 0.01) (type solid)) (fill solid) (layer "F.Mask"))
    (fp_poly
      (pts
        (xy 3.558784 1.935554)
        (xy 3.601574 1.945949)
        (xy 3.683609 1.984013)
        (xy 3.753757 2.042149)
        (xy 3.802305 2.111852)
        (xy 3.808975 2.127502)
        (xy 3.818124 2.168496)
        (xy 3.824529 2.229138)
        (xy 3.82671 2.29043)
        (xy 3.82671 2.406316)
        (xy 3.584407 2.406316)
        (xy 3.484471 2.406693)
        (xy 3.414069 2.408987)
        (xy 3.369313 2.414938)
        (xy 3.346315 2.426285)
        (xy 3.341189 2.444771)
        (xy 3.350048 2.472136)
        (xy 3.365917 2.504155)
        (xy 3.410184 2.557592)
        (xy 3.471699 2.584215)
        (xy 3.546885 2.583347)
        (xy 3.632053 2.554371)
        (xy 3.705659 2.518611)
        (xy 3.766734 2.566904)
        (xy 3.82781 2.615197)
        (xy 3.770351 2.668285)
        (xy 3.693641 2.718445)
        (xy 3.599302 2.748688)
        (xy 3.497827 2.757151)
        (xy 3.399711 2.741974)
        (xy 3.383881 2.736824)
        (xy 3.297647 2.691791)
        (xy 3.233501 2.624652)
        (xy 3.190091 2.533405)
        (xy 3.166064 2.416044)
        (xy 3.165784 2.413529)
        (xy 3.163633 2.285627)
        (xy 3.172329 2.239997)
        (xy 3.342105 2.239997)
        (xy 3.357697 2.247013)
        (xy 3.400029 2.252388)
        (xy 3.462434 2.255457)
        (xy 3.501981 2.255921)
        (xy 3.575728 2.25563)
        (xy 3.62184 2.253783)
        (xy 3.6461 2.248912)
        (xy 3.654294 2.239555)
        (xy 3.652206 2.224245)
        (xy 3.650455 2.218322)
        (xy 3.62056 2.162668)
        (xy 3.573542 2.117815)
        (xy 3.532049 2.098105)
        (xy 3.476926 2.099295)
        (xy 3.421068 2.123875)
        (xy 3.374212 2.16457)
        (xy 3.346094 2.214108)
        (xy 3.342105 2.239997)
        (xy 3.172329 2.239997)
        (xy 3.185074 2.173133)
        (xy 3.227611 2.078727)
        (xy 3.288747 2.005088)
        (xy 3.365985 1.954893)
        (xy 3.45683 1.930822)
        (xy 3.558784 1.935554)
      )

      (stroke (width 0.01) (type solid)) (fill solid) (layer "F.Mask"))
    (fp_poly
      (pts
        (xy 0.018628 1.935547)
        (xy 0.081908 1.947548)
        (xy 0.147557 1.972648)
        (xy 0.154572 1.975848)
        (xy 0.204356 2.002026)
        (xy 0.238834 2.026353)
        (xy 0.249978 2.041937)
        (xy 0.239366 2.067353)
        (xy 0.213588 2.104853)
        (xy 0.202146 2.118852)
        (xy 0.154992 2.173954)
        (xy 0.094201 2.138086)
        (xy 0.036347 2.114192)
        (xy -0.0305 2.10142)
        (xy -0.094606 2.100613)
        (xy -0.144236 2.112615)
        (xy -0.156146 2.120105)
        (xy -0.178828 2.15445)
        (xy -0.181584 2.194013)
        (xy -0.164612 2.22492)
        (xy -0.154573 2.230913)
        (xy -0.12449 2.238357)
        (xy -0.071611 2.247106)
        (xy -0.006425 2.255467)
        (xy 0.0056 2.256778)
        (xy 0.110297 2.274888)
        (xy 0.186232 2.305651)
        (xy 0.236592 2.351907)
        (xy 0.264564 2.416497)
        (xy 0.273278 2.495387)
        (xy 0.26124 2.585065)
        (xy 0.222151 2.655486)
        (xy 0.155855 2.706777)
        (xy 0.062194 2.739067)
        (xy -0.041777 2.751807)
        (xy -0.126562 2.751654)
        (xy -0.195335 2.740083)
        (xy -0.242303 2.724109)
        (xy -0.30165 2.696275)
        (xy -0.356494 2.663973)
        (xy -0.375987 2.649755)
        (xy -0.426119 2.608835)
        (xy -0.305197 2.486477)
        (xy -0.236457 2.531967)
        (xy -0.167512 2.566133)
        (xy -0.093889 2.584004)
        (xy -0.023117 2.585889)
        (xy 0.037274 2.572101)
        (xy 0.079757 2.542949)
        (xy 0.093474 2.518352)
        (xy 0.091417 2.478904)
        (xy 0.05733 2.448737)
        (xy -0.008692 2.427906)
        (xy -0.081026 2.418279)
        (xy -0.192348 2.39991)
        (xy -0.275048 2.365254)
        (xy -0.330235 2.313297)
        (xy -0.359012 2.243023)
        (xy -0.362999 2.159707)
        (xy -0.343307 2.072681)
        (xy -0.298411 2.006902)
        (xy -0.227909 1.962068)
        (xy -0.131399 1.937879)
        (xy -0.0599 1.933137)
        (xy 0.018628 1.935547)
      )

      (stroke (width 0.01) (type solid)) (fill solid) (layer "F.Mask"))
    (fp_poly
      (pts
        (xy 2.701193 3.196078)
        (xy 2.781068 3.216845)
        (xy 2.847962 3.259705)
        (xy 2.880351 3.291723)
        (xy 2.933445 3.367413)
        (xy 2.963873 3.455216)
        (xy 2.974327 3.56315)
        (xy 2.97438 3.571875)
        (xy 2.974473 3.659605)
        (xy 2.469534 3.659605)
        (xy 2.480298 3.705559)
        (xy 2.499732 3.747178)
        (xy 2.533745 3.790544)
        (xy 2.54086 3.797467)
        (xy 2.602003 3.834935)
        (xy 2.671729 3.841289)
        (xy 2.751987 3.816638)
        (xy 2.765592 3.81)
        (xy 2.807319 3.789819)
        (xy 2.835268 3.778321)
        (xy 2.840145 3.777258)
        (xy 2.857168 3.787583)
        (xy 2.889633 3.812845)
        (xy 2.906114 3.82665)
        (xy 2.940264 3.858361)
        (xy 2.951478 3.879299)
        (xy 2.943695 3.89856)
        (xy 2.939535 3.903827)
        (xy 2.911357 3.926878)
        (xy 2.864862 3.954892)
        (xy 2.832434 3.971246)
        (xy 2.740385 4.000059)
        (xy 2.638476 4.009395)
        (xy 2.541963 3.998332)
        (xy 2.514934 3.990412)
        (xy 2.431276 3.945581)
        (xy 2.369266 3.876598)
        (xy 2.328545 3.782794)
        (xy 2.308755 3.663498)
        (xy 2.306582 3.601118)
        (xy 2.312926 3.510298)
        (xy 2.473157 3.510298)
        (xy 2.488655 3.517012)
        (xy 2.530312 3.52228)
        (xy 2.590876 3.525389)
        (xy 2.631907 3.525921)
        (xy 2.705711 3.525408)
        (xy 2.752293 3.523006)
        (xy 2.777848 3.517422)
        (xy 2.788569 3.507361)
        (xy 2.790657 3.492763)
        (xy 2.776331 3.447796)
        (xy 2.740262 3.403353)
        (xy 2.692815 3.369242)
        (xy 2.645349 3.355288)
        (xy 2.580879 3.367666)
        (xy 2.52507 3.403452)
        (xy 2.486374 3.455033)
        (xy 2.473157 3.510298)
        (xy 2.312926 3.510298)
        (xy 2.315821 3.468866)
        (xy 2.344336 3.363498)
        (xy 2.392729 3.284178)
        (xy 2.461604 3.230071)
        (xy 2.551565 3.200343)
        (xy 2.6003 3.194618)
        (xy 2.701193 3.196078)
      )

      (stroke (width 0.01) (type solid)) (fill solid) (layer "F.Mask"))
    (fp_poly
      (pts
        (xy -1.802982 1.957027)
        (xy -1.78633 1.964866)
        (xy -1.728695 2.007086)
        (xy -1.674195 2.0687)
        (xy -1.633501 2.136543)
        (xy -1.621926 2.167734)
        (xy -1.611366 2.223449)
        (xy -1.605069 2.290781)
        (xy -1.604304 2.318585)
        (xy -1.604211 2.406316)
        (xy -2.10915 2.406316)
        (xy -2.098387 2.45227)
        (xy -2.071967 2.50662)
        (xy -2.025778 2.553591)
        (xy -1.970828 2.583848)
        (xy -1.935811 2.590131)
        (xy -1.888323 2.582506)
        (xy -1.831665 2.563383)
        (xy -1.812418 2.554584)
        (xy -1.741241 2.519036)
        (xy -1.680498 2.565367)
        (xy -1.645448 2.596703)
        (xy -1.626798 2.622567)
        (xy -1.625853 2.630158)
        (xy -1.642515 2.648556)
        (xy -1.67903 2.676515)
        (xy -1.712172 2.698327)
        (xy -1.801607 2.737537)
        (xy -1.901871 2.755285)
        (xy -2.001246 2.75067)
        (xy -2.080461 2.726551)
        (xy -2.16212 2.674884)
        (xy -2.220151 2.606856)
        (xy -2.256454 2.518843)
        (xy -2.272928 2.407216)
        (xy -2.274389 2.356138)
        (xy -2.268543 2.239091)
        (xy -2.267825 2.235686)
        (xy -2.100511 2.235686)
        (xy -2.095903 2.246662)
        (xy -2.076964 2.252715)
        (xy -2.037902 2.25531)
        (xy -1.972923 2.25591)
        (xy -1.947903 2.255921)
        (xy -1.871779 2.255014)
        (xy -1.823504 2.25172)
        (xy -1.79754 2.245181)
        (xy -1.788352 2.234537)
        (xy -1.788027 2.231119)
        (xy -1.798513 2.203956)
        (xy -1.824758 2.165903)
        (xy -1.836041 2.152579)
        (xy -1.877928 2.114896)
        (xy -1.921591 2.10008)
        (xy -1.945115 2.098842)
        (xy -2.008757 2.114329)
        (xy -2.062127 2.15593)
        (xy -2.095981 2.216353)
        (xy -2.096581 2.218322)
        (xy -2.100511 2.235686)
        (xy -2.267825 2.235686)
        (xy -2.249101 2.146928)
        (xy -2.214078 2.07319)
        (xy -2.171244 2.020848)
        (xy -2.092052 1.964092)
        (xy -1.99896 1.933762)
        (xy -1.899945 1.931021)
        (xy -1.802982 1.957027)
      )

      (stroke (width 0.01) (type solid)) (fill solid) (layer "F.Mask"))
    (fp_poly
      (pts
        (xy 1.379992 3.196673)
        (xy 1.450427 3.21378)
        (xy 1.470787 3.222844)
        (xy 1.510253 3.246583)
        (xy 1.540541 3.273321)
        (xy 1.562952 3.307699)
        (xy 1.578786 3.35436)
        (xy 1.589343 3.417946)
        (xy 1.595924 3.503099)
        (xy 1.599828 3.614462)
        (xy 1.60131 3.688849)
        (xy 1.606765 4.010526)
        (xy 1.51358 4.010526)
        (xy 1.457047 4.008156)
        (xy 1.427922 4.000055)
        (xy 1.420394 3.986451)
        (xy 1.41642 3.971741)
        (xy 1.398652 3.974554)
        (xy 1.37444 3.986348)
        (xy 1.313828 4.004427)
        (xy 1.235929 4.009299)
        (xy 1.153995 4.00133)
        (xy 1.081281 3.980889)
        (xy 1.074759 3.978051)
        (xy 1.008302 3.931365)
        (xy 0.964491 3.866464)
        (xy 0.944332 3.7906)
        (xy 0.945872 3.763344)
        (xy 1.110345 3.763344)
        (xy 1.124837 3.800024)
        (xy 1.167805 3.826309)
        (xy 1.237129 3.840417)
        (xy 1.274177 3.84229)
        (xy 1.335919 3.837494)
        (xy 1.37696 3.818858)
        (xy 1.386973 3.81)
        (xy 1.4141 3.761806)
        (xy 1.420394 3.718092)
        (xy 1.420394 3.659605)
        (xy 1.33893 3.659605)
        (xy 1.244234 3.664432)
        (xy 1.177813 3.679613)
        (xy 1.135846 3.7062)
        (xy 1.126449 3.718052)
        (xy 1.110345 3.763344)
        (xy 0.945872 3.763344)
        (xy 0.948829 3.711026)
        (xy 0.978985 3.634995)
        (xy 1.020131 3.583612)
        (xy 1.045052 3.561397)
        (xy 1.069448 3.546798)
        (xy 1.101191 3.537897)
        (xy 1.148152 3.532775)
        (xy 1.218204 3.529515)
        (xy 1.24599 3.528577)
        (xy 1.420394 3.522879)
        (xy 1.420138 3.470091)
        (xy 1.413384 3.414603)
        (xy 1.388964 3.381052)
        (xy 1.33963 3.359618)
        (xy 1.338306 3.359236)
        (xy 1.26836 3.350808)
        (xy 1.199914 3.361816)
        (xy 1.149047 3.388585)
        (xy 1.128637 3.401803)
        (xy 1.106654 3.399974)
        (xy 1.072826 3.380824)
        (xy 1.052961 3.367308)
        (xy 1.014106 3.338432)
        (xy 0.990038 3.316786)
        (xy 0.986176 3.310589)
        (xy 1.002079 3.278519)
        (xy 1.049065 3.240219)
        (xy 1.069473 3.227297)
        (xy 1.128143 3.205041)
        (xy 1.207212 3.192432)
        (xy 1.295041 3.1896)
        (xy 1.379992 3.196673)
      )

      (stroke (width 0.01) (type solid)) (fill solid) (layer "F.Mask"))
    (fp_poly
      (pts
        (xy -1.839543 3.198184)
        (xy -1.76093 3.21916)
        (xy -1.701084 3.25718)
        (xy -1.658853 3.306978)
        (xy -1.645725 3.32823)
        (xy -1.636032 3.350492)
        (xy -1.629256 3.37897)
        (xy -1.624877 3.418871)
        (xy -1.622376 3.475401)
        (xy -1.621232 3.553767)
        (xy -1.620928 3.659176)
        (xy -1.620922 3.687142)
        (xy -1.620922 4.010526)
        (xy -1.701132 4.010526)
        (xy -1.752294 4.006943)
        (xy -1.790123 3.997866)
        (xy -1.799601 3.992268)
        (xy -1.825512 3.982606)
        (xy -1.851976 3.992268)
        (xy -1.895548 4.00433)
        (xy -1.95884 4.009185)
        (xy -2.02899 4.007078)
        (xy -2.09314 3.998256)
        (xy -2.130593 3.986937)
        (xy -2.203067 3.940412)
        (xy -2.24836 3.875846)
        (xy -2.268722 3.79)
        (xy -2.268912 3.787796)
        (xy -2.267125 3.749713)
        (xy -2.105527 3.749713)
        (xy -2.091399 3.79303)
        (xy -2.068388 3.817408)
        (xy -2.022196 3.835845)
        (xy -1.961225 3.843205)
        (xy -1.899051 3.839583)
        (xy -1.849249 3.825074)
        (xy -1.835297 3.815765)
        (xy -1.810915 3.772753)
        (xy -1.804737 3.723857)
        (xy -1.804737 3.659605)
        (xy -1.897182 3.659605)
        (xy -1.985005 3.666366)
        (xy -2.051582 3.68552)
        (xy -2.092998 3.715376)
        (xy -2.105527 3.749713)
        (xy -2.267125 3.749713)
        (xy -2.26451 3.694004)
        (xy -2.233576 3.619847)
        (xy -2.175419 3.563767)
        (xy -2.16738 3.558665)
        (xy -2.132837 3.542055)
        (xy -2.090082 3.531996)
        (xy -2.030314 3.527107)
        (xy -1.95931 3.525983)
        (xy -1.804737 3.525921)
        (xy -1.804737 3.461125)
        (xy -1.811294 3.41085)
        (xy -1.828025 3.377169)
        (xy -1.829984 3.375376)
        (xy -1.867217 3.360642)
        (xy -1.92342 3.354931)
        (xy -1.985533 3.357737)
        (xy -2.04049 3.368556)
        (xy -2.073101 3.384782)
        (xy -2.090772 3.39778)
        (xy -2.109431 3.400262)
        (xy -2.135181 3.389613)
        (xy -2.174127 3.363218)
        (xy -2.23237 3.318465)
        (xy -2.237716 3.314273)
        (xy -2.234977 3.29876)
        (xy -2.212124 3.27296)
        (xy -2.177391 3.244289)
        (xy -2.13901 3.220166)
        (xy -2.126952 3.21447)
        (xy -2.082966 3.203103)
        (xy -2.018513 3.194995)
        (xy -1.946503 3.191743)
        (xy -1.943136 3.191736)
        (xy -1.839543 3.198184)
      )

      (stroke (width 0.01) (type solid)) (fill solid) (layer "F.Mask"))
    (fp_poly
      (pts
        (xy -2.53664 1.952468)
        (xy -2.501408 1.969874)
        (xy -2.45796 2.000206)
        (xy -2.426294 2.033283)
        (xy -2.404606 2.074817)
        (xy -2.391097 2.130522)
        (xy -2.383962 2.206111)
        (xy -2.3814 2.307296)
        (xy -2.38125 2.350797)
        (xy -2.381688 2.446135)
        (xy -2.383504 2.514271)
        (xy -2.387455 2.561418)
        (xy -2.394298 2.59379)
        (xy -2.404789 2.6176)
        (xy -2.415704 2.633843)
        (xy -2.485381 2.702952)
        (xy -2.567434 2.744521)
        (xy -2.65595 2.757023)
        (xy -2.745019 2.738934)
        (xy -2.773237 2.726142)
        (xy -2.84079 2.690931)
        (xy -2.84079 3.2427)
        (xy -2.791488 3.217205)
        (xy -2.726527 3.19748)
        (xy -2.64668 3.192427)
        (xy -2.566948 3.201756)
        (xy -2.506735 3.222714)
        (xy -2.456792 3.262627)
        (xy -2.414119 3.319741)
        (xy -2.41091 3.325605)
        (xy -2.397378 3.353227)
        (xy -2.387495 3.381068)
        (xy -2.380691 3.414794)
        (xy -2.376399 3.460071)
        (xy -2.374049 3.522562)
        (xy -2.373072 3.607935)
        (xy -2.372895 3.70401)
        (xy -2.372895 4.010526)
        (xy -2.556711 4.010526)
        (xy -2.556711 3.445339)
        (xy -2.608125 3.402077)
        (xy -2.661534 3.367472)
        (xy -2.712112 3.36118)
        (xy -2.76297 3.377372)
        (xy -2.790075 3.393227)
        (xy -2.810249 3.41581)
        (xy -2.824597 3.44994)
        (xy -2.834224 3.500434)
        (xy -2.840237 3.572111)
        (xy -2.84374 3.669788)
        (xy -2.844974 3.734802)
        (xy -2.849145 4.002171)
        (xy -2.936875 4.007222)
        (xy -3.024606 4.012273)
        (xy -3.024606 2.353101)
        (xy -2.84079 2.353101)
        (xy -2.836104 2.4456)
        (xy -2.820312 2.509809)
        (xy -2.790817 2.549759)
        (xy -2.74502 2.56948)
        (xy -2.69875 2.573421)
        (xy -2.646372 2.568892)
        (xy -2.61161 2.551069)
        (xy -2.589872 2.527519)
        (xy -2.57276 2.502189)
        (xy -2.562573 2.473969)
        (xy -2.55804 2.434431)
        (xy -2.557891 2.375142)
        (xy -2.559416 2.325498)
        (xy -2.562919 2.25071)
        (xy -2.568133 2.201611)
        (xy -2.576913 2.170467)
        (xy -2.591114 2.149545)
        (xy -2.604516 2.137452)
        (xy -2.660513 2.111081)
        (xy -2.726789 2.106822)
        (xy -2.764844 2.115906)
        (xy -2.802523 2.148196)
        (xy -2.827481 2.211006)
        (xy -2.839578 2.303894)
        (xy -2.84079 2.353101)
        (xy -3.024606 2.353101)
        (xy -3.024606 1.938421)
        (xy -2.932698 1.938421)
        (xy -2.877517 1.940603)
        (xy -2.849048 1.948351)
        (xy -2.840794 1.963468)
        (xy -2.84079 1.963916)
        (xy -2.83696 1.97872)
        (xy -2.820067 1.977039)
        (xy -2.786481 1.960772)
        (xy -2.708222 1.935887)
        (xy -2.620173 1.933271)
        (xy -2.53664 1.952468)
      )

      (stroke (width 0.01) (type solid)) (fill solid) (layer "F.Mask"))
    (fp_poly
      (pts
        (xy 0.500964 -3.601424)
        (xy 0.576513 -3.200678)
        (xy 1.134041 -2.970846)
        (xy 1.468465 -3.198252)
        (xy 1.562122 -3.261569)
        (xy 1.646782 -3.318104)
        (xy 1.718495 -3.365273)
        (xy 1.773311 -3.400498)
        (xy 1.80728 -3.421195)
        (xy 1.81653 -3.425658)
        (xy 1.833195 -3.41418)
        (xy 1.868806 -3.382449)
        (xy 1.919371 -3.334517)
        (xy 1.9809 -3.274438)
        (xy 2.049399 -3.206267)
        (xy 2.120879 -3.134055)
        (xy 2.191347 -3.061858)
        (xy 2.256811 -2.993727)
        (xy 2.31328 -2.933717)
        (xy 2.356763 -2.885881)
        (xy 2.383268 -2.854273)
        (xy 2.389605 -2.843695)
        (xy 2.380486 -2.824194)
        (xy 2.35492 -2.781469)
        (xy 2.315597 -2.719702)
        (xy 2.265203 -2.643069)
        (xy 2.206427 -2.555752)
        (xy 2.172368 -2.505948)
        (xy 2.110289 -2.415007)
        (xy 2.055126 -2.332941)
        (xy 2.009554 -2.263837)
        (xy 1.97625 -2.211778)
        (xy 1.95789 -2.18085)
        (xy 1.955131 -2.17435)
        (xy 1.961385 -2.155879)
        (xy 1.978434 -2.112828)
        (xy 2.003703 -2.051251)
        (xy 2.034622 -1.977201)
        (xy 2.068618 -1.89673)
        (xy 2.103118 -1.815893)
        (xy 2.135551 -1.740742)
        (xy 2.163343 -1.677329)
        (xy 2.183923 -1.631707)
        (xy 2.194719 -1.609931)
        (xy 2.195356 -1.609074)
        (xy 2.212307 -1.604916)
        (xy 2.257451 -1.595639)
        (xy 2.32611 -1.582156)
        (xy 2.413602 -1.565379)
        (xy 2.51525 -1.546219)
        (xy 2.574556 -1.53517)
        (xy 2.683172 -1.51449)
        (xy 2.781277 -1.494811)
        (xy 2.863909 -1.477211)
        (xy 2.926104 -1.462767)
        (xy 2.962899 -1.452554)
        (xy 2.970296 -1.449314)
        (xy 2.97754 -1.427383)
        (xy 2.983385 -1.377853)
        (xy 2.987835 -1.306515)
        (xy 2.990893 -1.219161)
        (xy 2.992565 -1.121583)
        (xy 2.992853 -1.019574)
        (xy 2.991761 -0.918925)
        (xy 2.989294 -0.825428)
        (xy 2.985456 -0.744875)
        (xy 2.98025 -0.683058)
        (xy 2.973681 -0.64577)
        (xy 2.969741 -0.638007)
        (xy 2.946188 -0.628702)
        (xy 2.896282 -0.6154)
        (xy 2.826623 -0.599663)
        (xy 2.743813 -0.583054)
        (xy 2.714905 -0.577681)
        (xy 2.575531 -0.552152)
        (xy 2.465436 -0.531592)
        (xy 2.380982 -0.515185)
        (xy 2.31853 -0.502113)
        (xy 2.274444 -0.491559)
        (xy 2.245085 -0.482706)
        (xy 2.226815 -0.474737)
        (xy 2.215998 -0.466835)
        (xy 2.214485 -0.465273)
        (xy 2.199377 -0.440114)
        (xy 2.176329 -0.39115)
        (xy 2.147644 -0.324379)
        (xy 2.115622 -0.245795)
        (xy 2.082565 -0.161393)
        (xy 2.050773 -0.07717)
        (xy 2.022549 0.000879)
        (xy 2.000193 0.066759)
        (xy 1.986007 0.114473)
        (xy 1.982293 0.138027)
        (xy 1.982602 0.138852)
        (xy 1.995189 0.158104)
        (xy 2.023744 0.200463)
        (xy 2.065267 0.261521)
        (xy 2.116756 0.336868)
        (xy 2.175211 0.422096)
        (xy 2.191858 0.446315)
        (xy 2.251215 0.534123)
        (xy 2.303447 0.614238)
        (xy 2.345708 0.682062)
        (xy 2.375153 0.732993)
        (xy 2.388937 0.762431)
        (xy 2.389605 0.766048)
        (xy 2.378024 0.785057)
        (xy 2.346024 0.822714)
        (xy 2.297718 0.874973)
        (xy 2.23722 0.937786)
        (xy 2.168644 1.007106)
        (xy 2.096104 1.078885)
        (xy 2.023712 1.149077)
        (xy 1.955584 1.213635)
        (xy 1.895832 1.26851)
        (xy 1.848571 1.309656)
        (xy 1.817913 1.333026)
        (xy 1.809432 1.336842)
        (xy 1.789691 1.327855)
        (xy 1.749274 1.303616)
        (xy 1.694763 1.268209)
        (xy 1.652823 1.239711)
        (xy 1.576829 1.187418)
        (xy 1.486834 1.125845)
        (xy 1.396564 1.06437)
        (xy 1.348032 1.031469)
        (xy 1.183762 0.920359)
        (xy 1.045869 0.994916)
        (xy 0.983049 1.027578)
        (xy 0.929629 1.052966)
        (xy 0.893484 1.067446)
        (xy 0.884284 1.06946)
        (xy 0.873221 1.054584)
        (xy 0.851394 1.012547)
        (xy 0.820434 0.947227)
        (xy 0.78197 0.8625)
        (xy 0.737632 0.762245)
        (xy 0.689047 0.650339)
        (xy 0.637846 0.530659)
        (xy 0.585659 0.407084)
        (xy 0.534113 0.283491)
        (xy 0.48484 0.163757)
        (xy 0.439467 0.051759)
        (xy 0.399625 -0.048623)
        (xy 0.366942 -0.133514)
        (xy 0.343049 -0.199035)
        (xy 0.329574 -0.24131)
        (xy 0.327406 -0.255828)
        (xy 0.344583 -0.274347)
        (xy 0.38219 -0.30441)
        (xy 0.432366 -0.339768)
        (xy 0.436578 -0.342566)
        (xy 0.566264 -0.446375)
        (xy 0.670834 -0.567485)
        (xy 0.749381 -0.702024)
        (xy 0.800999 -0.846118)
        (xy 0.824782 -0.995895)
        (xy 0.819823 -1.147483)
        (xy 0.785217 -1.297008)
        (xy 0.720057 -1.4406)
        (xy 0.700886 -1.472016)
        (xy 0.601174 -1.598875)
        (xy 0.483377 -1.700745)
        (xy 0.351571 -1.777096)
        (xy 0.209833 -1.827398)
        (xy 0.062242 -1.851121)
        (xy -0.087127 -1.847735)
        (xy -0.234197 -1.816712)
        (xy -0.374889 -1.75752)
        (xy -0.505127 -1.669631)
        (xy -0.545414 -1.633958)
        (xy -0.647945 -1.522294)
        (xy -0.722659 -1.404743)
        (xy -0.77391 -1.27298)
        (xy -0.802454 -1.142493)
        (xy -0.8095 -0.995784)
        (xy -0.786004 -0.848347)
        (xy -0.734351 -0.705166)
        (xy -0.656929 -0.571223)
        (xy -0.556125 -0.451502)
        (xy -0.434324 -0.350986)
        (xy -0.418316 -0.340391)
        (xy -0.367602 -0.305694)
        (xy -0.32905 -0.27563)
        (xy -0.310619 -0.256435)
        (xy -0.310351 -0.255828)
        (xy -0.314308 -0.235064)
        (xy -0.329993 -0.187938)
        (xy -0.355778 -0.118327)
        (xy -0.390031 -0.030107)
        (xy -0.431123 0.072844)
        (xy -0.477424 0.18665)
        (xy -0.527304 0.307435)
        (xy -0.579133 0.431321)
        (xy -0.631281 0.554432)
        (xy -0.682118 0.672891)
        (xy -0.730013 0.782823)
        (xy -0.773338 0.880349)
        (xy -0.810462 0.961593)
        (xy -0.839756 1.022679)
        (xy -0.859588 1.05973)
        (xy -0.867574 1.06946)
        (xy -0.891979 1.061883)
        (xy -0.937642 1.04156)
        (xy -0.99669 1.012125)
        (xy -1.02916 0.994916)
        (xy -1.167053 0.920359)
        (xy -1.331323 1.031469)
        (xy -1.415179 1.08839)
        (xy -1.506987 1.15103)
        (xy -1.59302 1.210011)
        (xy -1.636113 1.239711)
        (xy -1.696723 1.28041)
        (xy -1.748045 1.312663)
        (xy -1.783385 1.332384)
        (xy -1.794863 1.336554)
        (xy -1.81157 1.325307)
        (xy -1.848546 1.293911)
        (xy -1.902205 1.245624)
        (xy -1.968962 1.183708)
        (xy -2.045234 1.111421)
        (xy -2.093473 1.065008)
        (xy -2.177867 0.982087)
        (xy -2.250803 0.90792)
        (xy -2.309331 0.84568)
        (xy -2.350503 0.798541)
        (xy -2.371372 0.769673)
        (xy -2.373374 0.763815)
        (xy -2.364083 0.741532)
        (xy -2.338409 0.696477)
        (xy -2.2992 0.633211)
        (xy -2.249303 0.556295)
        (xy -2.191567 0.470292)
        (xy -2.175149 0.446315)
        (xy -2.115323 0.35917)
        (xy -2.06165 0.28071)
        (xy -2.01713 0.215345)
        (xy -1.984765 0.167484)
        (xy -1.967555 0.141535)
        (xy -1.965893 0.138852)
        (xy -1.968379 0.118172)
        (xy -1.981577 0.072704)
        (xy -2.003186 0.008444)
        (xy -2.030904 -0.068613)
        (xy -2.06243 -0.152471)
        (xy -2.095463 -0.237134)
        (xy -2.127701 -0.316608)
        (xy -2.156843 -0.384896)
        (xy -2.180588 -0.436003)
        (xy -2.196635 -0.463933)
        (xy -2.197775 -0.465273)
        (xy -2.207588 -0.473255)
        (xy -2.224161 -0.481149)
        (xy -2.251132 -0.489771)
        (xy -2.292139 -0.499938)
        (xy -2.35082 -0.512469)
        (xy -2.430813 -0.528179)
        (xy -2.535755 -0.547887)
        (xy -2.669285 -0.572408)
        (xy -2.698196 -0.577681)
        (xy -2.783882 -0.594236)
        (xy -2.858582 -0.610431)
        (xy -2.915694 -0.624704)
        (xy -2.948617 -0.635492)
        (xy -2.953031 -0.638007)
        (xy -2.960306 -0.660304)
        (xy -2.966219 -0.710131)
        (xy -2.970766 -0.781696)
        (xy -2.973945 -0.869207)
        (xy -2.975749 -0.966872)
        (xy -2.976177 -1.068899)
        (xy -2.975223 -1.169497)
        (xy -2.972884 -1.262873)
        (xy -2.969156 -1.343235)
        (xy -2.964034 -1.404791)
        (xy -2.957516 -1.44175)
        (xy -2.953586 -1.449314)
        (xy -2.931708 -1.456944)
        (xy -2.881891 -1.469358)
        (xy -2.809097 -1.485478)
        (xy -2.718289 -1.504227)
        (xy -2.614431 -1.524529)
        (xy -2.557846 -1.53517)
        (xy -2.450486 -1.55524)
        (xy -2.354746 -1.57342)
        (xy -2.275306 -1.588801)
        (xy -2.216846 -1.600469)
        (xy -2.184045 -1.607512)
        (xy -2.178646 -1.609074)
        (xy -2.169522 -1.626678)
        (xy -2.150235 -1.669082)
        (xy -2.123355 -1.730228)
        (xy -2.091454 -1.804057)
        (xy -2.057102 -1.884511)
        (xy -2.022871 -1.965532)
        (xy -1.991331 -2.041063)
        (xy -1.965054 -2.105045)
        (xy -1.946611 -2.15142)
        (xy -1.938571 -2.174131)
        (xy -1.938422 -2.175124)
        (xy -1.947535 -2.193039)
        (xy -1.973086 -2.234267)
        (xy -2.012388 -2.294709)
        (xy -2.062757 -2.370269)
        (xy -2.121506 -2.456848)
        (xy -2.155658 -2.506579)
        (xy -2.21789 -2.597764)
        (xy -2.273164 -2.680551)
        (xy -2.318782 -2.750751)
        (xy -2.352048 -2.804176)
        (xy -2.370264 -2.836639)
        (xy -2.372895 -2.843917)
        (xy -2.361586 -2.860855)
        (xy -2.330319 -2.897022)
        (xy -2.28309 -2.948365)
        (xy -2.223892 -3.010833)
        (xy -2.156719 -3.080374)
        (xy -2.085566 -3.152935)
        (xy -2.014426 -3.224465)
        (xy -1.947293 -3.290913)
        (xy -1.888161 -3.348226)
        (xy -1.841025 -3.392353)
        (xy -1.809877 -3.419241)
        (xy -1.799457 -3.425658)
        (xy -1.782491 -3.416635)
        (xy -1.741911 -3.391285)
        (xy -1.681663 -3.35219)
        (xy -1.605693 -3.301929)
        (xy -1.517946 -3.243083)
        (xy -1.451756 -3.198252)
        (xy -1.117332 -2.970846)
        (xy -0.838567 -3.085762)
        (xy -0.559803 -3.200678)
        (xy -0.484254 -3.601424)
        (xy -0.408706 -4.002171)
        (xy 0.425415 -4.002171)
        (xy 0.500964 -3.601424)
      )

      (stroke (width 0.01) (type solid)) (fill solid) (layer "F.Mask"))
  )

  (footprint "antmicro-footprints:C_0402_1005Metric" (layer "F.Cu")
    (at 139.3 114.3 180)
    (descr "Capacitor SMD 0402")
    (tags "capacitor SMD 0402")
    (property "Author" "Antmicro")
    (property "Dielectric" "X5R")
    (property "License" "Apache-2.0")
    (property "MPN" "GRM155R61H104KE14D")
    (property "Manufacturer" "Murata")
    (property "Public" "False")
    (property "Sheetfile" "channel1.kicad_sch")
    (property "Sheetname" "Channel 1")
    (property "Val" "100n")
    (property "Voltage" "50V")
    (property "ki_description" "SMD Multilayer Ceramic Capacitor, 0.1 µF, 50 V, 0402 [1005 Metric], ± 10%, X5R, GRM Series")
    (property "ki_keywords" "0402, SMT, CAPACITOR, PASSIVE, CERAMIC, MLCC")
    (attr smd)
    (fp_text reference "C27" (at 1.8 -5.6) (layer "F.SilkS")
        (effects (font (size 0.65 0.65) (thickness 0.13)) (justify right bottom))
    )
    (fp_text value "C_100n_0402" (at 0 1.4) (layer "F.Fab")
        (effects (font (size 0.65 0.65) (thickness 0.13)) (justify right bottom))
    )
    (fp_text user "${REFERENCE}" (at -0.932 3.168) (layer "F.Fab") hide
        (effects (font (size 0.7 0.7) (thickness 0.15)) (justify right bottom))
    )
    (fp_text user "License: Apache-2.0" (at -0.932 5.17) (layer "F.Fab") hide
        (effects (font (size 0.7 0.7) (thickness 0.15)) (justify right bottom))
    )
    (fp_text user "Author: Antmicro" (at -0.932 4.17) (layer "F.Fab") hide
        (effects (font (size 0.7 0.7) (thickness 0.15)) (justify right bottom))
    )
    (fp_rect (start -0.925 -0.47) (end 0.925 0.47)
      (stroke (width 0.05) (type default)) (fill none) (layer "F.CrtYd"))
    (fp_line (start -0.494 -0.25) (end 0.504 -0.25)
      (stroke (width 0.15) (type solid)) (layer "F.Fab"))
    (fp_line (start -0.494 0.248) (end -0.494 -0.25)
      (stroke (width 0.15) (type solid)) (layer "F.Fab"))
    (fp_line (start 0.504 -0.25) (end 0.504 0.248)
      (stroke (width 0.15) (type solid)) (layer "F.Fab"))
    (fp_line (start 0.504 0.248) (end -0.494 0.248)
      (stroke (width 0.15) (type solid)) (layer "F.Fab"))
    (pad "1" smd roundrect (at -0.48 0 180) (size 0.59 0.64) (layers "F.Cu" "F.Paste" "F.Mask") (roundrect_rratio 0.25)
      (net 2 "GND") (pintype "passive"))
    (pad "2" smd roundrect (at 0.48 0 180) (size 0.59 0.64) (layers "F.Cu" "F.Paste" "F.Mask") (roundrect_rratio 0.25)
      (net 19 "Net-(C27-Pad2)") (pintype "passive"))
  )

  (footprint "antmicro-footprints:C_0402_1005Metric" (layer "F.Cu")
    (at 123 105.4 -90)
    (descr "Capacitor SMD 0402")
    (tags "capacitor SMD 0402")
    (property "Author" "Antmicro")
    (property "Dielectric" "C0G")
    (property "License" "Apache-2.0")
    (property "MPN" "C0402C470J5GACTU")
    (property "Manufacturer" "KEMET")
    (property "Public" "False")
    (property "Sheetfile" "channel1.kicad_sch")
    (property "Sheetname" "Channel 1")
    (property "Val" "47p")
    (property "Voltage" "")
    (property "ki_description" "SMD Multilayer Ceramic Capacitor, 47 pF, 50 V, 0402 [1005 Metric], ± 5%, C0G / NP0, C Series KEMET")
    (property "ki_keywords" "0402, SMT, CAPACITOR, PASSIVE, CERAMIC, MLCC")
    (attr smd)
    (fp_text reference "C13" (at -3 -0.3 90) (layer "F.SilkS")
        (effects (font (size 0.65 0.65) (thickness 0.13)) (justify right bottom))
    )
    (fp_text value "C_47p_0402" (at 0 1.4 90) (layer "F.Fab")
        (effects (font (size 0.65 0.65) (thickness 0.13)) (justify right bottom))
    )
    (fp_text user "Author: Antmicro" (at -0.932 4.17 90) (layer "F.Fab") hide
        (effects (font (size 0.7 0.7) (thickness 0.15)) (justify right bottom))
    )
    (fp_text user "${REFERENCE}" (at -0.932 3.168 90) (layer "F.Fab") hide
        (effects (font (size 0.7 0.7) (thickness 0.15)) (justify right bottom))
    )
    (fp_text user "License: Apache-2.0" (at -0.932 5.17 90) (layer "F.Fab") hide
        (effects (font (size 0.7 0.7) (thickness 0.15)) (justify right bottom))
    )
    (fp_rect (start -0.925 -0.47) (end 0.925 0.47)
      (stroke (width 0.05) (type default)) (fill none) (layer "F.CrtYd"))
    (fp_line (start -0.494 -0.25) (end 0.504 -0.25)
      (stroke (width 0.15) (type solid)) (layer "F.Fab"))
    (fp_line (start -0.494 0.248) (end -0.494 -0.25)
      (stroke (width 0.15) (type solid)) (layer "F.Fab"))
    (fp_line (start 0.504 -0.25) (end 0.504 0.248)
      (stroke (width 0.15) (type solid)) (layer "F.Fab"))
    (fp_line (start 0.504 0.248) (end -0.494 0.248)
      (stroke (width 0.15) (type solid)) (layer "F.Fab"))
    (pad "1" smd roundrect (at -0.48 0 270) (size 0.59 0.64) (layers "F.Cu" "F.Paste" "F.Mask") (roundrect_rratio 0.25)
      (net 2 "GND") (pintype "passive"))
    (pad "2" smd roundrect (at 0.48 0 270) (size 0.59 0.64) (layers "F.Cu" "F.Paste" "F.Mask") (roundrect_rratio 0.25)
      (net 9 "+3V3") (pintype "passive"))
  )

  (footprint "antmicro-footprints:FB_0805_2012Metric" (layer "F.Cu")
    (at 129.4 105.4 180)
    (descr "FERRITE BEAD 0805")
    (tags "FERRITE BEAD 0805")
    (property "Author" "Antmicro")
    (property "Current" "")
    (property "License" "Apache-2.0")
    (property "MPN" "742792096")
    (property "Manufacturer" "Würth Elektronik")
    (property "Public" "False")
    (property "Sheetfile" "channel1.kicad_sch")
    (property "Sheetname" "Channel 1")
    (property "Val" "1kZ/0.8A")
    (property "ki_description" "Ferrite Beads WE-CBF 0805 100MHz 1kOhm 1A, High Current")
    (property "ki_keywords" "FERRITE BEAD, PASSIVE")
    (attr smd)
    (fp_text reference "FB5" (at -0.5 1) (layer "F.SilkS")
        (effects (font (size 0.65 0.65) (thickness 0.13)) (justify right bottom))
    )
    (fp_text value "FB_1kZ_0.8A_WE-CBF_0805" (at 0 1.8) (layer "F.Fab")
        (effects (font (size 0.65 0.65) (thickness 0.13)) (justify right bottom))
    )
    (fp_text user "License: Apache-2.0" (at -1.9 5.75) (layer "F.Fab") hide
        (effects (font (size 0.7 0.7) (thickness 0.15)) (justify right bottom))
    )
    (fp_text user "Author: Antmicro" (at -1.9 4.4) (layer "F.Fab") hide
        (effects (font (size 0.7 0.7) (thickness 0.15)) (justify right bottom))
    )
    (fp_text user "${REFERENCE}" (at -1.9 3.1) (layer "F.Fab") hide
        (effects (font (size 0.7 0.7) (thickness 0.15)) (justify right bottom))
    )
    (fp_line (start -0.319 0.698) (end 0.281 0.698)
      (stroke (width 0.15) (type solid)) (layer "F.SilkS"))
    (fp_line (start -0.299 -0.698) (end 0.299 -0.698)
      (stroke (width 0.15) (type solid)) (layer "F.SilkS"))
    (fp_rect (start 1.95 -0.9) (end -1.95 0.9)
      (stroke (width 0.05) (type default)) (fill none) (layer "F.CrtYd"))
    (fp_line (start -0.948 -0.681) (end 0.948 -0.681)
      (stroke (width 0.15) (type solid)) (layer "F.Fab"))
    (fp_line (start -0.948 -0.676) (end -0.948 0.676)
      (stroke (width 0.15) (type solid)) (layer "F.Fab"))
    (fp_line (start -0.948 0.681) (end 0.948 0.681)
      (stroke (width 0.15) (type solid)) (layer "F.Fab"))
    (fp_line (start 0.948 -0.676) (end 0.948 0.676)
      (stroke (width 0.15) (type solid)) (layer "F.Fab"))
    (pad "1" smd roundrect (at -1.1 0 180) (size 1.2 1.3) (layers "F.Cu" "F.Paste" "F.Mask") (roundrect_rratio 0.25)
      (net 8 "Net-(U1B-VDDC1)") (pintype "passive"))
    (pad "2" smd roundrect (at 1.1 0 180) (size 1.2 1.3) (layers "F.Cu" "F.Paste" "F.Mask") (roundrect_rratio 0.25)
      (net 12 "CH1_1V2") (pintype "passive"))
  )

  (footprint "antmicro-footprints:SOT-23-5" (layer "F.Cu")
    (at 168.15 119.1 90)
    (property "Author" "Antmicro")
    (property "License" "Apache-2.0")
    (property "MPN" "TLV73312PDBVT")
    (property "Manufacturer" "Texas Instruments")
    (property "Sheetfile" "channel2.kicad_sch")
    (property "Sheetname" "Channel 2")
    (property "ki_description" "Fixed LDO Voltage Regulator, 1.4V to 5.5V, 122mV Dropout, 1.2Vout, 300mAout, SOT-23-5")
    (property "ki_keywords" "SMT, PMIC, IC, LDO, LINEAR, VOLTAGE, REGULATOR")
    (attr smd)
    (fp_text reference "IC4" (at -3.02 -0.93 180) (layer "F.SilkS")
        (effects (font (size 0.65 0.65) (thickness 0.13)) (justify left bottom))
    )
    (fp_text value "TLV73312PDBVT" (at 0.002 2.799 90) (layer "F.Fab")
        (effects (font (size 0.65 0.65) (thickness 0.13)) (justify left bottom))
    )
    (fp_text user "License: Apache-2.0" (at -1.898 6.7 90) (layer "F.Fab") hide
        (effects (font (size 0.7 0.7) (thickness 0.15)) (justify left bottom))
    )
    (fp_text user "Author: Antmicro" (at -1.898 5.499 90) (layer "F.Fab") hide
        (effects (font (size 0.7 0.7) (thickness 0.15)) (justify left bottom))
    )
    (fp_text user "${REFERENCE}" (at -1.898 4.299 90) (layer "F.Fab") hide
        (effects (font (size 0.7 0.7) (thickness 0.15)) (justify left bottom))
    )
    (fp_line (start -0.85 1.6) (end -0.85 1.301)
      (stroke (width 0.15) (type solid)) (layer "F.SilkS"))
    (fp_line (start -0.8 -1.6) (end -0.8 -1.3)
      (stroke (width 0.15) (type solid)) (layer "F.SilkS"))
    (fp_line (start -0.8 -1.6) (end -0.5 -1.6)
      (stroke (width 0.15) (type solid)) (layer "F.SilkS"))
    (fp_line (start -0.55 1.6) (end -0.85 1.6)
      (stroke (width 0.15) (type solid)) (layer "F.SilkS"))
    (fp_line (start 0.8 -1.6) (end 0.5 -1.6)
      (stroke (width 0.15) (type solid)) (layer "F.SilkS"))
    (fp_line (start 0.8 -1.3) (end 0.8 -1.6)
      (stroke (width 0.15) (type solid)) (layer "F.SilkS"))
    (fp_line (start 0.8 0.55) (end 0.8 -0.55)
      (stroke (width 0.15) (type solid)) (layer "F.SilkS"))
    (fp_line (start 0.8 1.3) (end 0.8 1.599)
      (stroke (width 0.15) (type solid)) (layer "F.SilkS"))
    (fp_line (start 0.8 1.599) (end 0.549 1.599)
      (stroke (width 0.15) (type solid)) (layer "F.SilkS"))
    (fp_circle (center -1.25 -1.5) (end -1.2 -1.5)
      (stroke (width 0.15) (type solid)) (fill solid) (layer "F.SilkS"))
    (fp_rect (start 1.9 -1.76) (end -1.9 1.75)
      (stroke (width 0.05) (type solid)) (fill none) (layer "F.CrtYd"))
    (fp_line (start -0.398 -1.526) (end -0.874 -1.05)
      (stroke (width 0.15) (type solid)) (layer "F.Fab"))
    (fp_rect (start 0.874 1.523) (end -0.873 -1.525)
      (stroke (width 0.15) (type solid)) (fill none) (layer "F.Fab"))
    (pad "1" smd rect (at -1.351 -0.951) (size 0.55 1) (layers "F.Cu" "F.Paste" "F.Mask")
      (net 9 "+3V3") (pinfunction "VIN") (pintype "power_in"))
    (pad "2" smd rect (at -1.351 0) (size 0.55 1) (layers "F.Cu" "F.Paste" "F.Mask")
      (net 2 "GND") (pinfunction "GND") (pintype "power_in"))
    (pad "3" smd rect (at -1.351 0.949) (size 0.55 1) (layers "F.Cu" "F.Paste" "F.Mask")
      (net 9 "+3V3") (pinfunction "EN") (pintype "input"))
    (pad "4" smd rect (at 1.35 0.949) (size 0.55 1) (layers "F.Cu" "F.Paste" "F.Mask")
      (net 103 "unconnected-(IC4-NC-Pad4)") (pinfunction "NC") (pintype "no_connect"))
    (pad "5" smd rect (at 1.35 -0.951) (size 0.55 1) (layers "F.Cu" "F.Paste" "F.Mask")
      (net 25 "CH2_1V2") (pinfunction "VOUT") (pintype "power_out"))
  )

  (footprint "antmicro-footprints:FB_0805_2012Metric" (layer "F.Cu")
    (at 142.6 112.6 -90)
    (descr "FERRITE BEAD 0805")
    (tags "FERRITE BEAD 0805")
    (property "Author" "Antmicro")
    (property "Current" "")
    (property "License" "Apache-2.0")
    (property "MPN" "742792096")
    (property "Manufacturer" "Würth Elektronik")
    (property "Public" "False")
    (property "Sheetfile" "channel1.kicad_sch")
    (property "Sheetname" "Channel 1")
    (property "Val" "1kZ/0.8A")
    (property "ki_description" "Ferrite Beads WE-CBF 0805 100MHz 1kOhm 1A, High Current")
    (property "ki_keywords" "FERRITE BEAD, PASSIVE")
    (attr smd)
    (fp_text reference "FB2" (at -0.98 -1.79 90) (layer "F.SilkS")
        (effects (font (size 0.65 0.65) (thickness 0.13)) (justify right bottom))
    )
    (fp_text value "FB_1kZ_0.8A_WE-CBF_0805" (at 0 1.8 90) (layer "F.Fab")
        (effects (font (size 0.65 0.65) (thickness 0.13)) (justify right bottom))
    )
    (fp_text user "License: Apache-2.0" (at -1.9 5.75 90) (layer "F.Fab") hide
        (effects (font (size 0.7 0.7) (thickness 0.15)) (justify right bottom))
    )
    (fp_text user "Author: Antmicro" (at -1.9 4.4 90) (layer "F.Fab") hide
        (effects (font (size 0.7 0.7) (thickness 0.15)) (justify right bottom))
    )
    (fp_text user "${REFERENCE}" (at -1.9 3.1 90) (layer "F.Fab") hide
        (effects (font (size 0.7 0.7) (thickness 0.15)) (justify right bottom))
    )
    (fp_line (start -0.319 0.698) (end 0.281 0.698)
      (stroke (width 0.15) (type solid)) (layer "F.SilkS"))
    (fp_line (start -0.299 -0.698) (end 0.299 -0.698)
      (stroke (width 0.15) (type solid)) (layer "F.SilkS"))
    (fp_rect (start 1.95 -0.9) (end -1.95 0.9)
      (stroke (width 0.05) (type default)) (fill none) (layer "F.CrtYd"))
    (fp_line (start -0.948 -0.681) (end 0.948 -0.681)
      (stroke (width 0.15) (type solid)) (layer "F.Fab"))
    (fp_line (start -0.948 -0.676) (end -0.948 0.676)
      (stroke (width 0.15) (type solid)) (layer "F.Fab"))
    (fp_line (start -0.948 0.681) (end 0.948 0.681)
      (stroke (width 0.15) (type solid)) (layer "F.Fab"))
    (fp_line (start 0.948 -0.676) (end 0.948 0.676)
      (stroke (width 0.15) (type solid)) (layer "F.Fab"))
    (pad "1" smd roundrect (at -1.1 0 270) (size 1.2 1.3) (layers "F.Cu" "F.Paste" "F.Mask") (roundrect_rratio 0.25)
      (net 5 "Net-(U1B-AVDD25)") (pintype "passive"))
    (pad "2" smd roundrect (at 1.1 0 270) (size 1.2 1.3) (layers "F.Cu" "F.Paste" "F.Mask") (roundrect_rratio 0.25)
      (net 11 "CH1_2V5") (pintype "passive"))
  )

  (footprint "antmicro-footprints:C_0402_1005Metric" (layer "F.Cu")
    (at 124 110.2 90)
    (descr "Capacitor SMD 0402")
    (tags "capacitor SMD 0402")
    (property "Author" "Antmicro")
    (property "Dielectric" "C0G")
    (property "License" "Apache-2.0")
    (property "MPN" "C0402C470J5GACTU")
    (property "Manufacturer" "KEMET")
    (property "Public" "False")
    (property "Sheetfile" "channel1.kicad_sch")
    (property "Sheetname" "Channel 1")
    (property "Val" "47p")
    (property "Voltage" "")
    (property "ki_description" "SMD Multilayer Ceramic Capacitor, 47 pF, 50 V, 0402 [1005 Metric], ± 5%, C0G / NP0, C Series KEMET")
    (property "ki_keywords" "0402, SMT, CAPACITOR, PASSIVE, CERAMIC, MLCC")
    (attr smd)
    (fp_text reference "C16" (at -3.2 0.4 90) (layer "F.SilkS")
        (effects (font (size 0.65 0.65) (thickness 0.13)) (justify left bottom))
    )
    (fp_text value "C_47p_0402" (at 0 1.4 90) (layer "F.Fab")
        (effects (font (size 0.65 0.65) (thickness 0.13)) (justify left bottom))
    )
    (fp_text user "Author: Antmicro" (at -0.932 4.17 90) (layer "F.Fab") hide
        (effects (font (size 0.7 0.7) (thickness 0.15)) (justify left bottom))
    )
    (fp_text user "${REFERENCE}" (at -0.932 3.168 90) (layer "F.Fab") hide
        (effects (font (size 0.7 0.7) (thickness 0.15)) (justify left bottom))
    )
    (fp_text user "License: Apache-2.0" (at -0.932 5.17 90) (layer "F.Fab") hide
        (effects (font (size 0.7 0.7) (thickness 0.15)) (justify left bottom))
    )
    (fp_rect (start -0.925 -0.47) (end 0.925 0.47)
      (stroke (width 0.05) (type default)) (fill none) (layer "F.CrtYd"))
    (fp_line (start -0.494 -0.25) (end 0.504 -0.25)
      (stroke (width 0.15) (type solid)) (layer "F.Fab"))
    (fp_line (start -0.494 0.248) (end -0.494 -0.25)
      (stroke (width 0.15) (type solid)) (layer "F.Fab"))
    (fp_line (start 0.504 -0.25) (end 0.504 0.248)
      (stroke (width 0.15) (type solid)) (layer "F.Fab"))
    (fp_line (start 0.504 0.248) (end -0.494 0.248)
      (stroke (width 0.15) (type solid)) (layer "F.Fab"))
    (pad "1" smd roundrect (at -0.48 0 90) (size 0.59 0.64) (layers "F.Cu" "F.Paste" "F.Mask") (roundrect_rratio 0.25)
      (net 2 "GND") (pintype "passive"))
    (pad "2" smd roundrect (at 0.48 0 90) (size 0.59 0.64) (layers "F.Cu" "F.Paste" "F.Mask") (roundrect_rratio 0.25)
      (net 10 "Net-(Y1-EN)") (pintype "passive"))
  )

  (footprint "antmicro-footprints:C_0402_1005Metric" (layer "F.Cu")
    (at 163.295 114.35 180)
    (descr "Capacitor SMD 0402")
    (tags "capacitor SMD 0402")
    (property "Author" "Antmicro")
    (property "Dielectric" "X5R")
    (property "License" "Apache-2.0")
    (property "MPN" "GRM155R61H104KE14D")
    (property "Manufacturer" "Murata")
    (property "Public" "False")
    (property "Sheetfile" "channel2.kicad_sch")
    (property "Sheetname" "Channel 2")
    (property "Val" "100n")
    (property "Voltage" "50V")
    (property "ki_description" "SMD Multilayer Ceramic Capacitor, 0.1 µF, 50 V, 0402 [1005 Metric], ± 10%, X5R, GRM Series")
    (property "ki_keywords" "0402, SMT, CAPACITOR, PASSIVE, CERAMIC, MLCC")
    (attr smd)
    (fp_text reference "C31" (at 1.695 -6.65) (layer "F.SilkS")
        (effects (font (size 0.65 0.65) (thickness 0.13)) (justify right bottom))
    )
    (fp_text value "C_100n_0402" (at 0 1.4) (layer "F.Fab")
        (effects (font (size 0.65 0.65) (thickness 0.13)) (justify right bottom))
    )
    (fp_text user "License: Apache-2.0" (at -0.932 5.17) (layer "F.Fab") hide
        (effects (font (size 0.7 0.7) (thickness 0.15)) (justify right bottom))
    )
    (fp_text user "Author: Antmicro" (at -0.932 4.17) (layer "F.Fab") hide
        (effects (font (size 0.7 0.7) (thickness 0.15)) (justify right bottom))
    )
    (fp_text user "${REFERENCE}" (at -0.932 3.168) (layer "F.Fab") hide
        (effects (font (size 0.7 0.7) (thickness 0.15)) (justify right bottom))
    )
    (fp_rect (start -0.925 -0.47) (end 0.925 0.47)
      (stroke (width 0.05) (type default)) (fill none) (layer "F.CrtYd"))
    (fp_line (start -0.494 -0.25) (end 0.504 -0.25)
      (stroke (width 0.15) (type solid)) (layer "F.Fab"))
    (fp_line (start -0.494 0.248) (end -0.494 -0.25)
      (stroke (width 0.15) (type solid)) (layer "F.Fab"))
    (fp_line (start 0.504 -0.25) (end 0.504 0.248)
      (stroke (width 0.15) (type solid)) (layer "F.Fab"))
    (fp_line (start 0.504 0.248) (end -0.494 0.248)
      (stroke (width 0.15) (type solid)) (layer "F.Fab"))
    (pad "1" smd roundrect (at -0.48 0 180) (size 0.59 0.64) (layers "F.Cu" "F.Paste" "F.Mask") (roundrect_rratio 0.25)
      (net 2 "GND") (pintype "passive"))
    (pad "2" smd roundrect (at 0.48 0 180) (size 0.59 0.64) (layers "F.Cu" "F.Paste" "F.Mask") (roundrect_rratio 0.25)
      (net 22 "Net-(C31-Pad2)") (pintype "passive"))
  )

  (footprint "antmicro-footprints:R_0603_1608Metric" (layer "F.Cu")
    (at 163.79 116.15 -90)
    (descr "Resistor SMD 0603")
    (tags "resistor SMD 0603")
    (property "Author" "Antmicro")
    (property "Current" "1A")
    (property "License" "Apache-2.0")
    (property "MPN" "CR0603-J/-000ELF")
    (property "Manufacturer" "Bourns")
    (property "Public" "False")
    (property "Sheetfile" "channel2.kicad_sch")
    (property "Sheetname" "Channel 2")
    (property "Tolerance" "")
    (property "Val" "0R")
    (property "ki_description" "Zero Ohm Resistor, Jumper, 0603 [1608 Metric], Thick Film, 100 mW, 1 A, Surface Mount Device, CR")
    (property "ki_keywords" "0603, SMT, RESISTOR, PASSIVE")
    (attr smd)
    (fp_text reference "R18" (at 3.35 -0.21 -90) (layer "F.SilkS")
        (effects (font (size 0.7 0.7) (thickness 0.15)) (justify left bottom))
    )
    (fp_text value "R_0R_0603" (at 0 1.6 -90) (layer "F.Fab")
        (effects (font (size 0.7 0.7) (thickness 0.15)) (justify left bottom))
    )
    (fp_text user "License: Apache-2.0" (at -1.25 5.9 -90) (layer "F.Fab") hide
        (effects (font (size 0.7 0.7) (thickness 0.15)) (justify left bottom))
    )
    (fp_text user "Author: Antmicro" (at -1.25 4.9 -90) (layer "F.Fab") hide
        (effects (font (size 0.7 0.7) (thickness 0.15)) (justify left bottom))
    )
    (fp_text user "${REFERENCE}" (at -1.25 3.898 -90) (layer "F.Fab") hide
        (effects (font (size 0.7 0.7) (thickness 0.15)) (justify left bottom))
    )
    (fp_line (start -0.15 -0.4) (end 0.15 -0.4)
      (stroke (width 0.15) (type solid)) (layer "F.SilkS"))
    (fp_line (start -0.15 0.4) (end 0.15 0.4)
      (stroke (width 0.15) (type solid)) (layer "F.SilkS"))
    (fp_rect (start -1.25 -0.65) (end 1.25 0.65)
      (stroke (width 0.05) (type solid)) (fill none) (layer "F.CrtYd"))
    (fp_rect (start -0.8 -0.4) (end 0.8 0.4)
      (stroke (width 0.15) (type solid)) (fill none) (layer "F.Fab"))
    (pad "1" smd roundrect (at -0.7 0 270) (size 0.8 1) (layers "F.Cu" "F.Paste" "F.Mask") (roundrect_rratio 0.2)
      (net 22 "Net-(C31-Pad2)") (pintype "passive"))
    (pad "2" smd roundrect (at 0.7 0 270) (size 0.8 1) (layers "F.Cu" "F.Paste" "F.Mask") (roundrect_rratio 0.2)
      (net 33 "Net-(U4B-VDDC1)") (pintype "passive"))
  )

  (footprint "antmicro-footprints:C_0603_1608Metric" (layer "F.Cu")
    (at 139.96 106.97 180)
    (descr "Capacitor SMD 0603")
    (tags "capacitor 0603")
    (property "Author" "Antmicro")
    (property "Dielectric" "")
    (property "License" "Apache-2.0")
    (property "MPN" "C1608X5R1V475M080AC")
    (property "Manufacturer" "TDK")
    (property "Public" "False")
    (property "Sheetfile" "channel1.kicad_sch")
    (property "Sheetname" "Channel 1")
    (property "Val" "4u7")
    (property "Voltage" "")
    (property "ki_description" "SMD Multilayer Ceramic Capacitor, 4.7 µF, 35 V, 0603 [1608 Metric], ± 20%, X5R, C")
    (property "ki_keywords" "0603, SMT, CAPACITOR, PASSIVE, CERAMIC, MLCC")
    (attr smd)
    (fp_text reference "C9" (at 1.32 -0.12) (layer "F.SilkS")
        (effects (font (size 0.65 0.65) (thickness 0.13)) (justify right bottom))
    )
    (fp_text value "C_4u7_0603" (at 0 1.6) (layer "F.Fab")
        (effects (font (size 0.65 0.65) (thickness 0.13)) (justify right bottom))
    )
    (fp_text user "Author: Antmicro" (at -1.682 4.894) (layer "F.Fab") hide
        (effects (font (size 0.7 0.7) (thickness 0.15)) (justify right bottom))
    )
    (fp_text user "License: Apache-2.0" (at -1.682 5.895) (layer "F.Fab") hide
        (effects (font (size 0.7 0.7) (thickness 0.15)) (justify right bottom))
    )
    (fp_text user "${REFERENCE}" (at -1.682 3.895) (layer "F.Fab") hide
        (effects (font (size 0.7 0.7) (thickness 0.15)) (justify right bottom))
    )
    (fp_line (start -0.15 -0.4) (end 0.15 -0.4)
      (stroke (width 0.15) (type solid)) (layer "F.SilkS"))
    (fp_line (start -0.15 0.4) (end 0.15 0.4)
      (stroke (width 0.15) (type solid)) (layer "F.SilkS"))
    (fp_rect (start -1.25 -0.65) (end 1.25 0.65)
      (stroke (width 0.05) (type solid)) (fill none) (layer "F.CrtYd"))
    (fp_rect (start -0.8 -0.4) (end 0.8 0.4)
      (stroke (width 0.15) (type solid)) (fill none) (layer "F.Fab"))
    (pad "1" smd roundrect (at -0.7 0 180) (size 0.8 1) (layers "F.Cu" "F.Paste" "F.Mask") (roundrect_rratio 0.2)
      (net 2 "GND") (pintype "passive"))
    (pad "2" smd roundrect (at 0.7 0 180) (size 0.8 1) (layers "F.Cu" "F.Paste" "F.Mask") (roundrect_rratio 0.2)
      (net 6 "Net-(C5-Pad1)") (pintype "passive"))
  )

  (footprint "antmicro-footprints:FB_0805_2012Metric" (layer "F.Cu")
    (at 166.5 115.55)
    (descr "FERRITE BEAD 0805")
    (tags "FERRITE BEAD 0805")
    (property "Author" "Antmicro")
    (property "Current" "")
    (property "License" "Apache-2.0")
    (property "MPN" "742792096")
    (property "Manufacturer" "Würth Elektronik")
    (property "Public" "False")
    (property "Sheetfile" "channel2.kicad_sch")
    (property "Sheetname" "Channel 2")
    (property "Val" "1kZ/0.8A")
    (property "ki_description" "Ferrite Beads WE-CBF 0805 100MHz 1kOhm 1A, High Current")
    (property "ki_keywords" "FERRITE BEAD, PASSIVE")
    (attr smd)
    (fp_text reference "FB10" (at -1.41 1.61) (layer "F.SilkS")
        (effects (font (size 0.65 0.65) (thickness 0.13)) (justify left bottom))
    )
    (fp_text value "FB_1kZ_0.8A_WE-CBF_0805" (at 0 1.8) (layer "F.Fab")
        (effects (font (size 0.65 0.65) (thickness 0.13)) (justify left bottom))
    )
    (fp_text user "${REFERENCE}" (at -1.9 3.1) (layer "F.Fab") hide
        (effects (font (size 0.7 0.7) (thickness 0.15)) (justify left bottom))
    )
    (fp_text user "Author: Antmicro" (at -1.9 4.4) (layer "F.Fab") hide
        (effects (font (size 0.7 0.7) (thickness 0.15)) (justify left bottom))
    )
    (fp_text user "License: Apache-2.0" (at -1.9 5.75) (layer "F.Fab") hide
        (effects (font (size 0.7 0.7) (thickness 0.15)) (justify left bottom))
    )
    (fp_line (start -0.319 0.698) (end 0.281 0.698)
      (stroke (width 0.15) (type solid)) (layer "F.SilkS"))
    (fp_line (start -0.299 -0.698) (end 0.299 -0.698)
      (stroke (width 0.15) (type solid)) (layer "F.SilkS"))
    (fp_rect (start 1.95 -0.9) (end -1.95 0.9)
      (stroke (width 0.05) (type default)) (fill none) (layer "F.CrtYd"))
    (fp_line (start -0.948 -0.681) (end 0.948 -0.681)
      (stroke (width 0.15) (type solid)) (layer "F.Fab"))
    (fp_line (start -0.948 -0.676) (end -0.948 0.676)
      (stroke (width 0.15) (type solid)) (layer "F.Fab"))
    (fp_line (start -0.948 0.681) (end 0.948 0.681)
      (stroke (width 0.15) (type solid)) (layer "F.Fab"))
    (fp_line (start 0.948 -0.676) (end 0.948 0.676)
      (stroke (width 0.15) (type solid)) (layer "F.Fab"))
    (pad "1" smd roundrect (at -1.1 0) (size 1.2 1.3) (layers "F.Cu" "F.Paste" "F.Mask") (roundrect_rratio 0.25)
      (net 110 "Net-(C49-Pad1)") (pintype "passive"))
    (pad "2" smd roundrect (at 1.1 0) (size 1.2 1.3) (layers "F.Cu" "F.Paste" "F.Mask") (roundrect_rratio 0.25)
      (net 25 "CH2_1V2") (pintype "passive"))
  )

  (footprint "antmicro-footprints:FB_0805_2012Metric" (layer "F.Cu")
    (at 166.6 112.65 -90)
    (descr "FERRITE BEAD 0805")
    (tags "FERRITE BEAD 0805")
    (property "Author" "Antmicro")
    (property "Current" "")
    (property "License" "Apache-2.0")
    (property "MPN" "742792096")
    (property "Manufacturer" "Würth Elektronik")
    (property "Public" "False")
    (property "Sheetfile" "channel2.kicad_sch")
    (property "Sheetname" "Channel 2")
    (property "Val" "1kZ/0.8A")
    (property "ki_description" "Ferrite Beads WE-CBF 0805 100MHz 1kOhm 1A, High Current")
    (property "ki_keywords" "FERRITE BEAD, PASSIVE")
    (attr smd)
    (fp_text reference "FB8" (at 1.05 -1.79 -90) (layer "F.SilkS")
        (effects (font (size 0.65 0.65) (thickness 0.13)) (justify left bottom))
    )
    (fp_text value "FB_1kZ_0.8A_WE-CBF_0805" (at 0 1.8 -90) (layer "F.Fab")
        (effects (font (size 0.65 0.65) (thickness 0.13)) (justify left bottom))
    )
    (fp_text user "${REFERENCE}" (at -1.9 3.1 -90) (layer "F.Fab") hide
        (effects (font (size 0.7 0.7) (thickness 0.15)) (justify left bottom))
    )
    (fp_text user "Author: Antmicro" (at -1.9 4.4 -90) (layer "F.Fab") hide
        (effects (font (size 0.7 0.7) (thickness 0.15)) (justify left bottom))
    )
    (fp_text user "License: Apache-2.0" (at -1.9 5.75 -90) (layer "F.Fab") hide
        (effects (font (size 0.7 0.7) (thickness 0.15)) (justify left bottom))
    )
    (fp_line (start -0.319 0.698) (end 0.281 0.698)
      (stroke (width 0.15) (type solid)) (layer "F.SilkS"))
    (fp_line (start -0.299 -0.698) (end 0.299 -0.698)
      (stroke (width 0.15) (type solid)) (layer "F.SilkS"))
    (fp_rect (start 1.95 -0.9) (end -1.95 0.9)
      (stroke (width 0.05) (type default)) (fill none) (layer "F.CrtYd"))
    (fp_line (start -0.948 -0.681) (end 0.948 -0.681)
      (stroke (width 0.15) (type solid)) (layer "F.Fab"))
    (fp_line (start -0.948 -0.676) (end -0.948 0.676)
      (stroke (width 0.15) (type solid)) (layer "F.Fab"))
    (fp_line (start -0.948 0.681) (end 0.948 0.681)
      (stroke (width 0.15) (type solid)) (layer "F.Fab"))
    (fp_line (start 0.948 -0.676) (end 0.948 0.676)
      (stroke (width 0.15) (type solid)) (layer "F.Fab"))
    (pad "1" smd roundrect (at -1.1 0 270) (size 1.2 1.3) (layers "F.Cu" "F.Paste" "F.Mask") (roundrect_rratio 0.25)
      (net 32 "Net-(U4B-AVDD25)") (pintype "passive"))
    (pad "2" smd roundrect (at 1.1 0 270) (size 1.2 1.3) (layers "F.Cu" "F.Paste" "F.Mask") (roundrect_rratio 0.25)
      (net 24 "CH2_2V5") (pintype "passive"))
  )

  (footprint "antmicro-footprints:C_0402_1005Metric" (layer "F.Cu")
    (at 143.84 106.25)
    (descr "Capacitor SMD 0402")
    (tags "capacitor SMD 0402")
    (property "Author" "Antmicro")
    (property "Dielectric" "X5R")
    (property "License" "Apache-2.0")
    (property "MPN" "GRM155R61H104KE14D")
    (property "Manufacturer" "Murata")
    (property "Public" "False")
    (property "Sheetfile" "channel1.kicad_sch")
    (property "Sheetname" "Channel 1")
    (property "Val" "100n")
    (property "Voltage" "50V")
    (property "ki_description" "SMD Multilayer Ceramic Capacitor, 0.1 µF, 50 V, 0402 [1005 Metric], ± 10%, X5R, GRM Series")
    (property "ki_keywords" "0402, SMT, CAPACITOR, PASSIVE, CERAMIC, MLCC")
    (attr smd)
    (fp_text reference "C14" (at -0.84 -0.45) (layer "F.SilkS")
        (effects (font (size 0.65 0.65) (thickness 0.13)) (justify left bottom))
    )
    (fp_text value "C_100n_0402" (at 0 1.4) (layer "F.Fab")
        (effects (font (size 0.65 0.65) (thickness 0.13)) (justify left bottom))
    )
    (fp_text user "License: Apache-2.0" (at -0.932 5.17) (layer "F.Fab") hide
        (effects (font (size 0.7 0.7) (thickness 0.15)) (justify left bottom))
    )
    (fp_text user "${REFERENCE}" (at -0.932 3.168) (layer "F.Fab") hide
        (effects (font (size 0.7 0.7) (thickness 0.15)) (justify left bottom))
    )
    (fp_text user "Author: Antmicro" (at -0.932 4.17) (layer "F.Fab") hide
        (effects (font (size 0.7 0.7) (thickness 0.15)) (justify left bottom))
    )
    (fp_rect (start -0.925 -0.47) (end 0.925 0.47)
      (stroke (width 0.05) (type default)) (fill none) (layer "F.CrtYd"))
    (fp_line (start -0.494 -0.25) (end 0.504 -0.25)
      (stroke (width 0.15) (type solid)) (layer "F.Fab"))
    (fp_line (start -0.494 0.248) (end -0.494 -0.25)
      (stroke (width 0.15) (type solid)) (layer "F.Fab"))
    (fp_line (start 0.504 -0.25) (end 0.504 0.248)
      (stroke (width 0.15) (type solid)) (layer "F.Fab"))
    (fp_line (start 0.504 0.248) (end -0.494 0.248)
      (stroke (width 0.15) (type solid)) (layer "F.Fab"))
    (pad "1" smd roundrect (at -0.48 0) (size 0.59 0.64) (layers "F.Cu" "F.Paste" "F.Mask") (roundrect_rratio 0.25)
      (net 9 "+3V3") (pintype "passive"))
    (pad "2" smd roundrect (at 0.48 0) (size 0.59 0.64) (layers "F.Cu" "F.Paste" "F.Mask") (roundrect_rratio 0.25)
      (net 2 "GND") (pintype "passive"))
  )

  (footprint "antmicro-footprints:C_0402_1005Metric" (layer "F.Cu")
    (at 154.985 113.45)
    (descr "Capacitor SMD 0402")
    (tags "capacitor SMD 0402")
    (property "Author" "Antmicro")
    (property "Dielectric" "X5R")
    (property "License" "Apache-2.0")
    (property "MPN" "GRM155R61H104KE14D")
    (property "Manufacturer" "Murata")
    (property "Public" "False")
    (property "Sheetfile" "channel2.kicad_sch")
    (property "Sheetname" "Channel 2")
    (property "Val" "100n")
    (property "Voltage" "50V")
    (property "ki_description" "SMD Multilayer Ceramic Capacitor, 0.1 µF, 50 V, 0402 [1005 Metric], ± 10%, X5R, GRM Series")
    (property "ki_keywords" "0402, SMT, CAPACITOR, PASSIVE, CERAMIC, MLCC")
    (attr smd)
    (fp_text reference "C33" (at -1.545 7.62) (layer "F.SilkS")
        (effects (font (size 0.65 0.65) (thickness 0.13)) (justify left bottom))
    )
    (fp_text value "C_100n_0402" (at 0 1.4) (layer "F.Fab")
        (effects (font (size 0.65 0.65) (thickness 0.13)) (justify left bottom))
    )
    (fp_text user "License: Apache-2.0" (at -0.932 5.17) (layer "F.Fab") hide
        (effects (font (size 0.7 0.7) (thickness 0.15)) (justify left bottom))
    )
    (fp_text user "Author: Antmicro" (at -0.932 4.17) (layer "F.Fab") hide
        (effects (font (size 0.7 0.7) (thickness 0.15)) (justify left bottom))
    )
    (fp_text user "${REFERENCE}" (at -0.932 3.168) (layer "F.Fab") hide
        (effects (font (size 0.7 0.7) (thickness 0.15)) (justify left bottom))
    )
    (fp_rect (start -0.925 -0.47) (end 0.925 0.47)
      (stroke (width 0.05) (type default)) (fill none) (layer "F.CrtYd"))
    (fp_line (start -0.494 -0.25) (end 0.504 -0.25)
      (stroke (width 0.15) (type solid)) (layer "F.Fab"))
    (fp_line (start -0.494 0.248) (end -0.494 -0.25)
      (stroke (width 0.15) (type solid)) (layer "F.Fab"))
    (fp_line (start 0.504 -0.25) (end 0.504 0.248)
      (stroke (width 0.15) (type solid)) (layer "F.Fab"))
    (fp_line (start 0.504 0.248) (end -0.494 0.248)
      (stroke (width 0.15) (type solid)) (layer "F.Fab"))
    (pad "1" smd roundrect (at -0.48 0) (size 0.59 0.64) (layers "F.Cu" "F.Paste" "F.Mask") (roundrect_rratio 0.25)
      (net 2 "GND") (pintype "passive"))
    (pad "2" smd roundrect (at 0.48 0) (size 0.59 0.64) (layers "F.Cu" "F.Paste" "F.Mask") (roundrect_rratio 0.25)
      (net 26 "Net-(U4B-VDDIO2)") (pintype "passive"))
  )

  (footprint "antmicro-footprints:C_0402_1005Metric" (layer "F.Cu")
    (at 129.53 111.8 90)
    (descr "Capacitor SMD 0402")
    (tags "capacitor SMD 0402")
    (property "Author" "Antmicro")
    (property "Dielectric" "C0G")
    (property "License" "Apache-2.0")
    (property "MPN" "C0402C470J5GACTU")
    (property "Manufacturer" "KEMET")
    (property "Public" "False")
    (property "Sheetfile" "channel1.kicad_sch")
    (property "Sheetname" "Channel 1")
    (property "Val" "47p")
    (property "Voltage" "")
    (property "ki_description" "SMD Multilayer Ceramic Capacitor, 47 pF, 50 V, 0402 [1005 Metric], ± 5%, C0G / NP0, C Series KEMET")
    (property "ki_keywords" "0402, SMT, CAPACITOR, PASSIVE, CERAMIC, MLCC")
    (attr smd)
    (fp_text reference "C21" (at 0.9 0.27 90) (layer "F.SilkS")
        (effects (font (size 0.65 0.65) (thickness 0.13)) (justify left bottom))
    )
    (fp_text value "C_47p_0402" (at 0 1.4 90) (layer "F.Fab")
        (effects (font (size 0.65 0.65) (thickness 0.13)) (justify left bottom))
    )
    (fp_text user "License: Apache-2.0" (at -0.932 5.17 90) (layer "F.Fab") hide
        (effects (font (size 0.7 0.7) (thickness 0.15)) (justify left bottom))
    )
    (fp_text user "${REFERENCE}" (at -0.932 3.168 90) (layer "F.Fab") hide
        (effects (font (size 0.7 0.7) (thickness 0.15)) (justify left bottom))
    )
    (fp_text user "Author: Antmicro" (at -0.932 4.17 90) (layer "F.Fab") hide
        (effects (font (size 0.7 0.7) (thickness 0.15)) (justify left bottom))
    )
    (fp_rect (start -0.925 -0.47) (end 0.925 0.47)
      (stroke (width 0.05) (type default)) (fill none) (layer "F.CrtYd"))
    (fp_line (start -0.494 -0.25) (end 0.504 -0.25)
      (stroke (width 0.15) (type solid)) (layer "F.Fab"))
    (fp_line (start -0.494 0.248) (end -0.494 -0.25)
      (stroke (width 0.15) (type solid)) (layer "F.Fab"))
    (fp_line (start 0.504 -0.25) (end 0.504 0.248)
      (stroke (width 0.15) (type solid)) (layer "F.Fab"))
    (fp_line (start 0.504 0.248) (end -0.494 0.248)
      (stroke (width 0.15) (type solid)) (layer "F.Fab"))
    (pad "1" smd roundrect (at -0.48 0 90) (size 0.59 0.64) (layers "F.Cu" "F.Paste" "F.Mask") (roundrect_rratio 0.25)
      (net 2 "GND") (pintype "passive"))
    (pad "2" smd roundrect (at 0.48 0 90) (size 0.59 0.64) (layers "F.Cu" "F.Paste" "F.Mask") (roundrect_rratio 0.25)
      (net 13 "Net-(Y1-OUT)") (pintype "passive"))
  )

  (footprint "antmicro-footprints:R_0402_1005Metric" (layer "F.Cu")
    (at 139.28 102.21 -90)
    (descr "Resistor SMD 0402")
    (tags "resistor SMD 0402")
    (property "Author" "Antmicro")
    (property "License" "Apache-2.0")
    (property "MPN" "CR0402-FX-1002GLF")
    (property "Manufacturer" "Bourns")
    (property "Public" "False")
    (property "Sheetfile" "channel1.kicad_sch")
    (property "Sheetname" "Channel 1")
    (property "Tolerance" "1%")
    (property "Val" "10k")
    (property "ki_description" "SMD Chip Resistor, 10 kohm, ± 1%, 62.5 mW, 0402 [1005 Metric], Thick Film, General Purpose")
    (property "ki_keywords" "0402, SMT, RESISTOR, PASSIVE")
    (attr smd)
    (fp_text reference "R11" (at -3.25 11.64 -90) (layer "F.SilkS")
        (effects (font (size 0.65 0.65) (thickness 0.13)) (justify left bottom))
    )
    (fp_text value "R_10k_0402" (at 0 1.4 -90) (layer "F.Fab")
        (effects (font (size 0.65 0.65) (thickness 0.13)) (justify left bottom))
    )
    (fp_text user "License: Apache-2.0" (at -0.95 5.169 -90) (layer "F.Fab") hide
        (effects (font (size 0.7 0.7) (thickness 0.15)) (justify left bottom))
    )
    (fp_text user "${REFERENCE}" (at -0.95 3.168 -90) (layer "F.Fab") hide
        (effects (font (size 0.7 0.7) (thickness 0.15)) (justify left bottom))
    )
    (fp_text user "Author: Antmicro" (at -0.95 4.169 -90) (layer "F.Fab") hide
        (effects (font (size 0.7 0.7) (thickness 0.15)) (justify left bottom))
    )
    (fp_rect (start -0.925 -0.47) (end 0.925 0.47)
      (stroke (width 0.05) (type default)) (fill none) (layer "F.CrtYd"))
    (fp_rect (start -0.5 -0.25) (end 0.5 0.25)
      (stroke (width 0.15) (type solid)) (fill none) (layer "F.Fab"))
    (pad "1" smd roundrect (at -0.48 0 270) (size 0.59 0.64) (layers "F.Cu" "F.Paste" "F.Mask") (roundrect_rratio 0.25)
      (net 84 "/Channel 1/HDMI1_DDC_SCL") (pintype "passive"))
    (pad "2" smd roundrect (at 0.48 0 270) (size 0.59 0.64) (layers "F.Cu" "F.Paste" "F.Mask") (roundrect_rratio 0.25)
      (net 14 "+5V") (pintype "passive"))
  )

  (footprint "antmicro-footprints:C_0402_1005Metric" (layer "F.Cu")
    (at 163.79 108.21)
    (descr "Capacitor SMD 0402")
    (tags "capacitor SMD 0402")
    (property "Author" "Antmicro")
    (property "Dielectric" "")
    (property "License" "Apache-2.0")
    (property "MPN" "0402B471K250CT")
    (property "Manufacturer" "Walsin")
    (property "Public" "False")
    (property "Sheetfile" "channel2.kicad_sch")
    (property "Sheetname" "Channel 2")
    (property "Val" "470p")
    (property "Voltage" "")
    (property "ki_description" "SMD Multilayer Ceramic Capacitor, General Purpose, 470 pF, 25 V, 0402 [1005 Metric], ± 10%, X7R")
    (property "ki_keywords" "0402, SMT, CAPACITOR, PASSIVE, MLCC")
    (attr smd)
    (fp_text reference "C48" (at -3.69 7.06) (layer "F.SilkS")
        (effects (font (size 0.65 0.65) (thickness 0.13)) (justify left bottom))
    )
    (fp_text value "C_470p_0402" (at 0 1.4) (layer "F.Fab")
        (effects (font (size 0.65 0.65) (thickness 0.13)) (justify left bottom))
    )
    (fp_text user "Author: Antmicro" (at -0.932 4.17) (layer "F.Fab") hide
        (effects (font (size 0.7 0.7) (thickness 0.15)) (justify left bottom))
    )
    (fp_text user "License: Apache-2.0" (at -0.932 5.17) (layer "F.Fab") hide
        (effects (font (size 0.7 0.7) (thickness 0.15)) (justify left bottom))
    )
    (fp_text user "${REFERENCE}" (at -0.932 3.168) (layer "F.Fab") hide
        (effects (font (size 0.7 0.7) (thickness 0.15)) (justify left bottom))
    )
    (fp_rect (start -0.925 -0.47) (end 0.925 0.47)
      (stroke (width 0.05) (type default)) (fill none) (layer "F.CrtYd"))
    (fp_line (start -0.494 -0.25) (end 0.504 -0.25)
      (stroke (width 0.15) (type solid)) (layer "F.Fab"))
    (fp_line (start -0.494 0.248) (end -0.494 -0.25)
      (stroke (width 0.15) (type solid)) (layer "F.Fab"))
    (fp_line (start 0.504 -0.25) (end 0.504 0.248)
      (stroke (width 0.15) (type solid)) (layer "F.Fab"))
    (fp_line (start 0.504 0.248) (end -0.494 0.248)
      (stroke (width 0.15) (type solid)) (layer "F.Fab"))
    (pad "1" smd roundrect (at -0.48 0) (size 0.59 0.64) (layers "F.Cu" "F.Paste" "F.Mask") (roundrect_rratio 0.25)
      (net 109 "Net-(C48-Pad1)") (pintype "passive"))
    (pad "2" smd roundrect (at 0.48 0) (size 0.59 0.64) (layers "F.Cu" "F.Paste" "F.Mask") (roundrect_rratio 0.25)
      (net 2 "GND") (pintype "passive"))
  )

  (footprint "antmicro-footprints:FB_0805_2012Metric" (layer "F.Cu")
    (at 166.6 108.75 90)
    (descr "FERRITE BEAD 0805")
    (tags "FERRITE BEAD 0805")
    (property "Author" "Antmicro")
    (property "Current" "")
    (property "License" "Apache-2.0")
    (property "MPN" "742792096")
    (property "Manufacturer" "Würth Elektronik")
    (property "Public" "False")
    (property "Sheetfile" "channel2.kicad_sch")
    (property "Sheetname" "Channel 2")
    (property "Val" "1kZ/0.8A")
    (property "ki_description" "Ferrite Beads WE-CBF 0805 100MHz 1kOhm 1A, High Current")
    (property "ki_keywords" "FERRITE BEAD, PASSIVE")
    (attr smd)
    (fp_text reference "FB9" (at -2.32 1.77 90) (layer "F.SilkS")
        (effects (font (size 0.65 0.65) (thickness 0.13)) (justify left bottom))
    )
    (fp_text value "FB_1kZ_0.8A_WE-CBF_0805" (at 0 1.8 90) (layer "F.Fab")
        (effects (font (size 0.65 0.65) (thickness 0.13)) (justify left bottom))
    )
    (fp_text user "${REFERENCE}" (at -1.9 3.1 90) (layer "F.Fab") hide
        (effects (font (size 0.7 0.7) (thickness 0.15)) (justify left bottom))
    )
    (fp_text user "Author: Antmicro" (at -1.9 4.4 90) (layer "F.Fab") hide
        (effects (font (size 0.7 0.7) (thickness 0.15)) (justify left bottom))
    )
    (fp_text user "License: Apache-2.0" (at -1.9 5.75 90) (layer "F.Fab") hide
        (effects (font (size 0.7 0.7) (thickness 0.15)) (justify left bottom))
    )
    (fp_line (start -0.319 0.698) (end 0.281 0.698)
      (stroke (width 0.15) (type solid)) (layer "F.SilkS"))
    (fp_line (start -0.299 -0.698) (end 0.299 -0.698)
      (stroke (width 0.15) (type solid)) (layer "F.SilkS"))
    (fp_rect (start 1.95 -0.9) (end -1.95 0.9)
      (stroke (width 0.05) (type default)) (fill none) (layer "F.CrtYd"))
    (fp_line (start -0.948 -0.681) (end 0.948 -0.681)
      (stroke (width 0.15) (type solid)) (layer "F.Fab"))
    (fp_line (start -0.948 -0.676) (end -0.948 0.676)
      (stroke (width 0.15) (type solid)) (layer "F.Fab"))
    (fp_line (start -0.948 0.681) (end 0.948 0.681)
      (stroke (width 0.15) (type solid)) (layer "F.Fab"))
    (fp_line (start 0.948 -0.676) (end 0.948 0.676)
      (stroke (width 0.15) (type solid)) (layer "F.Fab"))
    (pad "1" smd roundrect (at -1.1 0 90) (size 1.2 1.3) (layers "F.Cu" "F.Paste" "F.Mask") (roundrect_rratio 0.25)
      (net 109 "Net-(C48-Pad1)") (pintype "passive"))
    (pad "2" smd roundrect (at 1.1 0 90) (size 1.2 1.3) (layers "F.Cu" "F.Paste" "F.Mask") (roundrect_rratio 0.25)
      (net 25 "CH2_1V2") (pintype "passive"))
  )

  (footprint "antmicro-footprints:C_0603_1608Metric" (layer "F.Cu")
    (at 140.15 109.48 180)
    (descr "Capacitor SMD 0603")
    (tags "capacitor 0603")
    (property "Author" "Antmicro")
    (property "Dielectric" "")
    (property "License" "Apache-2.0")
    (property "MPN" "C1608X5R1V475M080AC")
    (property "Manufacturer" "TDK")
    (property "Public" "False")
    (property "Sheetfile" "channel1.kicad_sch")
    (property "Sheetname" "Channel 1")
    (property "Val" "4u7")
    (property "Voltage" "")
    (property "ki_description" "SMD Multilayer Ceramic Capacitor, 4.7 µF, 35 V, 0603 [1608 Metric], ± 20%, X5R, C")
    (property "ki_keywords" "0603, SMT, CAPACITOR, PASSIVE, CERAMIC, MLCC")
    (attr smd)
    (fp_text reference "C8" (at 2.6 -5.8) (layer "F.SilkS")
        (effects (font (size 0.65 0.65) (thickness 0.13)) (justify right bottom))
    )
    (fp_text value "C_4u7_0603" (at 0 1.6) (layer "F.Fab")
        (effects (font (size 0.65 0.65) (thickness 0.13)) (justify right bottom))
    )
    (fp_text user "${REFERENCE}" (at -1.682 3.895) (layer "F.Fab") hide
        (effects (font (size 0.7 0.7) (thickness 0.15)) (justify right bottom))
    )
    (fp_text user "License: Apache-2.0" (at -1.682 5.895) (layer "F.Fab") hide
        (effects (font (size 0.7 0.7) (thickness 0.15)) (justify right bottom))
    )
    (fp_text user "Author: Antmicro" (at -1.682 4.894) (layer "F.Fab") hide
        (effects (font (size 0.7 0.7) (thickness 0.15)) (justify right bottom))
    )
    (fp_line (start -0.15 -0.4) (end 0.15 -0.4)
      (stroke (width 0.15) (type solid)) (layer "F.SilkS"))
    (fp_line (start -0.15 0.4) (end 0.15 0.4)
      (stroke (width 0.15) (type solid)) (layer "F.SilkS"))
    (fp_rect (start -1.25 -0.65) (end 1.25 0.65)
      (stroke (width 0.05) (type solid)) (fill none) (layer "F.CrtYd"))
    (fp_rect (start -0.8 -0.4) (end 0.8 0.4)
      (stroke (width 0.15) (type solid)) (fill none) (layer "F.Fab"))
    (pad "1" smd roundrect (at -0.7 0 180) (size 0.8 1) (layers "F.Cu" "F.Paste" "F.Mask") (roundrect_rratio 0.2)
      (net 2 "GND") (pintype "passive"))
    (pad "2" smd roundrect (at 0.7 0 180) (size 0.8 1) (layers "F.Cu" "F.Paste" "F.Mask") (roundrect_rratio 0.2)
      (net 5 "Net-(U1B-AVDD25)") (pintype "passive"))
  )

  (footprint "antmicro-footprints:FB_0603_1608Metric" (layer "F.Cu")
    (at 147.81 107.86 -90)
    (property "Author" "Antmicro")
    (property "Current" "")
    (property "License" "Apache-2.0")
    (property "MPN" "BLM18AG601SN1D")
    (property "Manufacturer" "Murata")
    (property "Public" "False")
    (property "Sheetfile" "channel2.kicad_sch")
    (property "Sheetname" "Channel 2")
    (property "Val" "600Z/0.5A")
    (property "ki_description" "Ferrite Bead, 0603 [1608 Metric], 600 ohm, 500 mA, BLM18A, 0.38 ohm, ± 25%, General use")
    (property "ki_keywords" "0603, SMT, FERRITE BEAD, PASSIVE")
    (attr smd)
    (fp_text reference "FB12" (at 1.54 0.61 -90) (layer "F.SilkS")
        (effects (font (size 0.65 0.65) (thickness 0.13)) (justify left bottom))
    )
    (fp_text value "FB_600Z_0.5A_Murata-BLM18AG_0603" (at 0 1.5 -90) (layer "F.Fab")
        (effects (font (size 0.65 0.65) (thickness 0.13)) (justify left bottom))
    )
    (fp_text user "${REFERENCE}" (at -1.653 4.6 -90) (layer "F.Fab") hide
        (effects (font (size 0.7 0.7) (thickness 0.15)) (justify left bottom))
    )
    (fp_text user "Author: Antmicro" (at -1.653 3.162 -90) (layer "F.Fab") hide
        (effects (font (size 0.7 0.7) (thickness 0.15)) (justify left bottom))
    )
    (fp_text user "License: Apache-2.0" (at -1.653 5.9 -90) (layer "F.Fab") hide
        (effects (font (size 0.7 0.7) (thickness 0.15)) (justify left bottom))
    )
    (fp_line (start -0.15 -0.4) (end 0.15 -0.4)
      (stroke (width 0.15) (type solid)) (layer "F.SilkS"))
    (fp_line (start -0.15 0.4) (end 0.15 0.4)
      (stroke (width 0.15) (type solid)) (layer "F.SilkS"))
    (fp_rect (start -1.25 -0.65) (end 1.25 0.65)
      (stroke (width 0.05) (type solid)) (fill none) (layer "F.CrtYd"))
    (fp_line (start -0.803 0.406) (end -0.803 -0.408)
      (stroke (width 0.15) (type solid)) (layer "F.Fab"))
    (fp_line (start 0.8 -0.408) (end -0.803 -0.408)
      (stroke (width 0.15) (type solid)) (layer "F.Fab"))
    (fp_line (start 0.8 -0.408) (end 0.8 0.406)
      (stroke (width 0.15) (type solid)) (layer "F.Fab"))
    (fp_line (start 0.8 0.406) (end -0.803 0.406)
      (stroke (width 0.15) (type solid)) (layer "F.Fab"))
    (pad "1" smd roundrect (at -0.7 0 270) (size 0.8 1) (layers "F.Cu" "F.Paste" "F.Mask") (roundrect_rratio 0.2)
      (net 9 "+3V3") (pintype "passive"))
    (pad "2" smd roundrect (at 0.7 0 270) (size 0.8 1) (layers "F.Cu" "F.Paste" "F.Mask") (roundrect_rratio 0.2)
      (net 30 "Net-(Y2-EN)") (pintype "passive"))
  )

  (footprint "antmicro-footprints:C_0402_1005Metric" (layer "F.Cu")
    (at 163.39 104.21 90)
    (descr "Capacitor SMD 0402")
    (tags "capacitor SMD 0402")
    (property "Author" "Antmicro")
    (property "Dielectric" "X5R")
    (property "License" "Apache-2.0")
    (property "MPN" "GRM155R61H104KE14D")
    (property "Manufacturer" "Murata")
    (property "Public" "False")
    (property "Sheetfile" "channel2.kicad_sch")
    (property "Sheetname" "Channel 2")
    (property "Val" "100n")
    (property "Voltage" "50V")
    (property "ki_description" "SMD Multilayer Ceramic Capacitor, 0.1 µF, 50 V, 0402 [1005 Metric], ± 10%, X5R, GRM Series")
    (property "ki_keywords" "0402, SMT, CAPACITOR, PASSIVE, CERAMIC, MLCC")
    (attr smd)
    (fp_text reference "C45" (at 5.16 -11.68 90) (layer "F.SilkS")
        (effects (font (size 0.65 0.65) (thickness 0.13)) (justify right bottom))
    )
    (fp_text value "C_100n_0402" (at 0 1.4 90) (layer "F.Fab")
        (effects (font (size 0.65 0.65) (thickness 0.13)) (justify left bottom))
    )
    (fp_text user "License: Apache-2.0" (at -0.932 5.17 90) (layer "F.Fab") hide
        (effects (font (size 0.7 0.7) (thickness 0.15)) (justify left bottom))
    )
    (fp_text user "${REFERENCE}" (at -0.932 3.168 90) (layer "F.Fab") hide
        (effects (font (size 0.7 0.7) (thickness 0.15)) (justify left bottom))
    )
    (fp_text user "Author: Antmicro" (at -0.932 4.17 90) (layer "F.Fab") hide
        (effects (font (size 0.7 0.7) (thickness 0.15)) (justify left bottom))
    )
    (fp_rect (start -0.925 -0.47) (end 0.925 0.47)
      (stroke (width 0.05) (type default)) (fill none) (layer "F.CrtYd"))
    (fp_line (start -0.494 -0.25) (end 0.504 -0.25)
      (stroke (width 0.15) (type solid)) (layer "F.Fab"))
    (fp_line (start -0.494 0.248) (end -0.494 -0.25)
      (stroke (width 0.15) (type solid)) (layer "F.Fab"))
    (fp_line (start 0.504 -0.25) (end 0.504 0.248)
      (stroke (width 0.15) (type solid)) (layer "F.Fab"))
    (fp_line (start 0.504 0.248) (end -0.494 0.248)
      (stroke (width 0.15) (type solid)) (layer "F.Fab"))
    (pad "1" smd roundrect (at -0.48 0 90) (size 0.59 0.64) (layers "F.Cu" "F.Paste" "F.Mask") (roundrect_rratio 0.25)
      (net 2 "GND") (pintype "passive"))
    (pad "2" smd roundrect (at 0.48 0 90) (size 0.59 0.64) (layers "F.Cu" "F.Paste" "F.Mask") (roundrect_rratio 0.25)
      (net 14 "+5V") (pintype "passive"))
  )

  (footprint "antmicro-footprints:SOT-23-5" (layer "F.Cu")
    (at 172.25 115.95 90)
    (property "Author" "Antmicro")
    (property "License" "Apache-2.0")
    (property "MPN" "TLV73325PDBVT")
    (property "Manufacturer" "Texas Instruments")
    (property "Sheetfile" "channel2.kicad_sch")
    (property "Sheetname" "Channel 2")
    (property "ki_description" "Linear voltage regulator")
    (property "ki_keywords" "SMT, PMIC, IC, LDO, LINEAR, VOLTAGE, REGULATOR")
    (attr smd)
    (fp_text reference "IC3" (at -1.1 2.72 90) (layer "F.SilkS")
        (effects (font (size 0.65 0.65) (thickness 0.13)) (justify left bottom))
    )
    (fp_text value "TLV73325PDBVT" (at 0.002 2.799 90) (layer "F.Fab")
        (effects (font (size 0.65 0.65) (thickness 0.13)) (justify left bottom))
    )
    (fp_text user "${REFERENCE}" (at -1.898 4.299 90) (layer "F.Fab") hide
        (effects (font (size 0.7 0.7) (thickness 0.15)) (justify left bottom))
    )
    (fp_text user "License: Apache-2.0" (at -1.898 6.7 90) (layer "F.Fab") hide
        (effects (font (size 0.7 0.7) (thickness 0.15)) (justify left bottom))
    )
    (fp_text user "Author: Antmicro" (at -1.898 5.499 90) (layer "F.Fab") hide
        (effects (font (size 0.7 0.7) (thickness 0.15)) (justify left bottom))
    )
    (fp_line (start -0.85 1.6) (end -0.85 1.301)
      (stroke (width 0.15) (type solid)) (layer "F.SilkS"))
    (fp_line (start -0.8 -1.6) (end -0.8 -1.3)
      (stroke (width 0.15) (type solid)) (layer "F.SilkS"))
    (fp_line (start -0.8 -1.6) (end -0.5 -1.6)
      (stroke (width 0.15) (type solid)) (layer "F.SilkS"))
    (fp_line (start -0.55 1.6) (end -0.85 1.6)
      (stroke (width 0.15) (type solid)) (layer "F.SilkS"))
    (fp_line (start 0.8 -1.6) (end 0.5 -1.6)
      (stroke (width 0.15) (type solid)) (layer "F.SilkS"))
    (fp_line (start 0.8 -1.3) (end 0.8 -1.6)
      (stroke (width 0.15) (type solid)) (layer "F.SilkS"))
    (fp_line (start 0.8 0.55) (end 0.8 -0.55)
      (stroke (width 0.15) (type solid)) (layer "F.SilkS"))
    (fp_line (start 0.8 1.3) (end 0.8 1.599)
      (stroke (width 0.15) (type solid)) (layer "F.SilkS"))
    (fp_line (start 0.8 1.599) (end 0.549 1.599)
      (stroke (width 0.15) (type solid)) (layer "F.SilkS"))
    (fp_circle (center -1.25 -1.5) (end -1.2 -1.5)
      (stroke (width 0.15) (type solid)) (fill solid) (layer "F.SilkS"))
    (fp_rect (start 1.9 -1.76) (end -1.9 1.75)
      (stroke (width 0.05) (type solid)) (fill none) (layer "F.CrtYd"))
    (fp_line (start -0.398 -1.526) (end -0.874 -1.05)
      (stroke (width 0.15) (type solid)) (layer "F.Fab"))
    (fp_rect (start 0.874 1.523) (end -0.873 -1.525)
      (stroke (width 0.15) (type solid)) (fill none) (layer "F.Fab"))
    (pad "1" smd rect (at -1.351 -0.951) (size 0.55 1) (layers "F.Cu" "F.Paste" "F.Mask")
      (net 9 "+3V3") (pinfunction "VIN") (pintype "power_in"))
    (pad "2" smd rect (at -1.351 0) (size 0.55 1) (layers "F.Cu" "F.Paste" "F.Mask")
      (net 2 "GND") (pinfunction "GND") (pintype "power_in"))
    (pad "3" smd rect (at -1.351 0.949) (size 0.55 1) (layers "F.Cu" "F.Paste" "F.Mask")
      (net 9 "+3V3") (pinfunction "EN") (pintype "input"))
    (pad "4" smd rect (at 1.35 0.949) (size 0.55 1) (layers "F.Cu" "F.Paste" "F.Mask")
      (net 102 "unconnected-(IC3-NC-Pad4)") (pinfunction "NC") (pintype "no_connect"))
    (pad "5" smd rect (at 1.35 -0.951) (size 0.55 1) (layers "F.Cu" "F.Paste" "F.Mask")
      (net 24 "CH2_2V5") (pinfunction "VOUT") (pintype "power_out"))
  )

  (footprint "antmicro-footprints:C_0603_1608Metric" (layer "F.Cu")
    (at 171.65 113.05 180)
    (descr "Capacitor SMD 0603")
    (tags "capacitor 0603")
    (property "Author" "Antmicro")
    (property "Dielectric" "template_dielectric")
    (property "License" "Apache-2.0")
    (property "MPN" "GRM188R61A106KE69D")
    (property "Manufacturer" "Murata")
    (property "Public" "False")
    (property "Sheetfile" "channel2.kicad_sch")
    (property "Sheetname" "Channel 2")
    (property "Val" "10u")
    (property "Voltage" "")
    (property "ki_description" "SMD Multilayer Ceramic Capacitor, 10 µF, 10 V, 0603 [1608 Metric], ± 10%, X5R, GRM Series")
    (property "ki_keywords" "0603, SMT, CAPACITOR, PASSIVE, CERAMIC, MLCC")
    (attr smd)
    (fp_text reference "C42" (at -0.95 0.65) (layer "F.SilkS")
        (effects (font (size 0.65 0.65) (thickness 0.13)) (justify right bottom))
    )
    (fp_text value "C_10u_0603" (at 0 1.6) (layer "F.Fab")
        (effects (font (size 0.65 0.65) (thickness 0.13)) (justify right bottom))
    )
    (fp_text user "${REFERENCE}" (at -1.682 3.895) (layer "F.Fab") hide
        (effects (font (size 0.7 0.7) (thickness 0.15)) (justify right bottom))
    )
    (fp_text user "Author: Antmicro" (at -1.682 4.894) (layer "F.Fab") hide
        (effects (font (size 0.7 0.7) (thickness 0.15)) (justify right bottom))
    )
    (fp_text user "License: Apache-2.0" (at -1.682 5.895) (layer "F.Fab") hide
        (effects (font (size 0.7 0.7) (thickness 0.15)) (justify right bottom))
    )
    (fp_line (start -0.15 -0.4) (end 0.15 -0.4)
      (stroke (width 0.15) (type solid)) (layer "F.SilkS"))
    (fp_line (start -0.15 0.4) (end 0.15 0.4)
      (stroke (width 0.15) (type solid)) (layer "F.SilkS"))
    (fp_rect (start -1.25 -0.65) (end 1.25 0.65)
      (stroke (width 0.05) (type solid)) (fill none) (layer "F.CrtYd"))
    (fp_rect (start -0.8 -0.4) (end 0.8 0.4)
      (stroke (width 0.15) (type solid)) (fill none) (layer "F.Fab"))
    (pad "1" smd roundrect (at -0.7 0 180) (size 0.8 1) (layers "F.Cu" "F.Paste" "F.Mask") (roundrect_rratio 0.2)
      (net 2 "GND") (pintype "passive"))
    (pad "2" smd roundrect (at 0.7 0 180) (size 0.8 1) (layers "F.Cu" "F.Paste" "F.Mask") (roundrect_rratio 0.2)
      (net 24 "CH2_2V5") (pintype "passive"))
  )

  (footprint "antmicro-footprints:SOT1069-2" (layer "F.Cu")
    (at 141.6 103.8)
    (property "Author" "Antmicro")
    (property "License" "Apache-2.0")
    (property "MPN" "PCA9517ATP")
    (property "Manufacturer" "NXP")
    (property "Sheetfile" "channel1.kicad_sch")
    (property "Sheetname" "Channel 1")
    (property "ki_description" "Level Translating I2C-Bus Repeater, 2 Inputs, 0.9 V to 5.5 V Supply, 50 mA Out, HWSON-8")
    (property "ki_keywords" "SMT, LEVEL-SHIFTER, IC, I2C")
    (attr smd)
    (fp_text reference "U3" (at 0.06 -2.33 180) (layer "F.SilkS")
        (effects (font (size 0.7 0.7) (thickness 0.15)) (justify left bottom))
    )
    (fp_text value "PCA9517ATP" (at -2.54 3.4544) (layer "F.Fab")
        (effects (font (size 0.7 0.7) (thickness 0.15)) (justify left bottom))
    )
    (fp_text user "." (at -3.101 -1.101 unlocked) (layer "F.SilkS") hide
        (effects (font (size 0.7 0.7) (thickness 0.15)) (justify left bottom))
    )
    (fp_text user "Author: Antmicro" (at -4.375 4.7) (layer "F.Fab") hide
        (effects (font (size 0.7 0.7) (thickness 0.15)) (justify left bottom))
    )
    (fp_text user "${REFERENCE}" (at -4.375 3.499) (layer "F.Fab") hide
        (effects (font (size 0.7 0.7) (thickness 0.15)) (justify left bottom))
    )
    (fp_text user "License: Apache-2.0" (at -4.375 5.9) (layer "F.Fab") hide
        (effects (font (size 0.7 0.7) (thickness 0.15)) (justify left bottom))
    )
    (fp_line (start -1.375 -2.226) (end 1.375 -2.226)
      (stroke (width 0.15) (type solid)) (layer "F.SilkS"))
    (fp_line (start -1.375 1.425) (end -1.375 -2.226)
      (stroke (width 0.15) (type solid)) (layer "F.SilkS"))
    (fp_line (start -0.577 2.224) (end -1.375 1.425)
      (stroke (width 0.15) (type solid)) (layer "F.SilkS"))
    (fp_line (start 1.375 -2.226) (end 1.375 2.224)
      (stroke (width 0.15) (type solid)) (layer "F.SilkS"))
    (fp_line (start 1.375 2.224) (end -0.577 2.224)
      (stroke (width 0.15) (type solid)) (layer "F.SilkS"))
    (fp_circle (center -1.3208 2.0836) (end -1.2708 2.0836)
      (stroke (width 0.15) (type solid)) (fill solid) (layer "F.SilkS"))
    (fp_line (start -1.13 -2) (end 1.12 -2)
      (stroke (width 0.05) (type solid)) (layer "F.CrtYd"))
    (fp_line (start -1.13 1.98) (end -1.13 -2)
      (stroke (width 0.05) (type solid)) (layer "F.CrtYd"))
    (fp_line (start 1.12 -2) (end 1.12 1.98)
      (stroke (width 0.05) (type solid)) (layer "F.CrtYd"))
    (fp_line (start 1.12 1.98) (end -1.13 1.98)
      (stroke (width 0.05) (type solid)) (layer "F.CrtYd"))
    (pad "1" smd rect (at -0.75 1.411) (size 0.25 0.625) (layers "F.Cu" "F.Paste" "F.Mask")
      (net 9 "+3V3") (pinfunction "Vref1") (pintype "power_in"))
    (pad "2" smd rect (at -0.25 1.411) (size 0.25 0.625) (layers "F.Cu" "F.Paste" "F.Mask")
      (net 105 "/Channel 1/HDMI1_DDC_SCL_3V3") (pinfunction "SCL1") (pintype "input"))
    (pad "3" smd rect (at 0.25 1.411) (size 0.25 0.625) (layers "F.Cu" "F.Paste" "F.Mask")
      (net 104 "/Channel 1/HDMI1_DDC_SDA_3V3") (pinfunction "SDA1") (pintype "bidirectional"))
    (pad "4" smd rect (at 0.75 1.411) (size 0.25 0.625) (layers "F.Cu" "F.Paste" "F.Mask")
      (net 2 "GND") (pinfunction "GND") (pintype "power_in"))
    (pad "5" smd rect (at 0.75 -1.414) (size 0.25 0.625) (layers "F.Cu" "F.Paste" "F.Mask")
      (net 118 "Net-(U3-EN)") (pinfunction "EN") (pintype "input"))
    (pad "6" smd rect (at 0.25 -1.414) (size 0.25 0.625) (layers "F.Cu" "F.Paste" "F.Mask")
      (net 85 "/Channel 1/HDMI1_DDC_SDA") (pinfunction "SDA2") (pintype "bidirectional"))
    (pad "7" smd rect (at -0.25 -1.414) (size 0.25 0.625) (layers "F.Cu" "F.Paste" "F.Mask")
      (net 84 "/Channel 1/HDMI1_DDC_SCL") (pinfunction "SCL2") (pintype "input"))
    (pad "8" smd rect (at -0.75 -1.414) (size 0.25 0.625) (layers "F.Cu" "F.Paste" "F.Mask")
      (net 14 "+5V") (pinfunction "Vref2") (pintype "power_in"))
    (pad "9" smd roundrect (at 0 0) (size 1.6 1.6) (layers "F.Cu" "F.Paste" "F.Mask") (roundrect_rratio 0.05)
      (net 2 "GND") (pinfunction "GND") (pintype "passive") (solder_paste_margin -0.05))
  )

  (footprint "antmicro-footprints:C_0402_1005Metric" (layer "F.Cu")
    (at 123 110.2 90)
    (descr "Capacitor SMD 0402")
    (tags "capacitor SMD 0402")
    (property "Author" "Antmicro")
    (property "Dielectric" "X5R")
    (property "License" "Apache-2.0")
    (property "MPN" "GRM155R61H104KE14D")
    (property "Manufacturer" "Murata")
    (property "Public" "False")
    (property "Sheetfile" "channel1.kicad_sch")
    (property "Sheetname" "Channel 1")
    (property "Val" "100n")
    (property "Voltage" "50V")
    (property "ki_description" "SMD Multilayer Ceramic Capacitor, 0.1 µF, 50 V, 0402 [1005 Metric], ± 10%, X5R, GRM Series")
    (property "ki_keywords" "0402, SMT, CAPACITOR, PASSIVE, CERAMIC, MLCC")
    (attr smd)
    (fp_text reference "C15" (at -3.2 0.3 90) (layer "F.SilkS")
        (effects (font (size 0.65 0.65) (thickness 0.13)) (justify left bottom))
    )
    (fp_text value "C_100n_0402" (at 0 1.4 90) (layer "F.Fab")
        (effects (font (size 0.65 0.65) (thickness 0.13)) (justify left bottom))
    )
    (fp_text user "License: Apache-2.0" (at -0.932 5.17 90) (layer "F.Fab") hide
        (effects (font (size 0.7 0.7) (thickness 0.15)) (justify left bottom))
    )
    (fp_text user "Author: Antmicro" (at -0.932 4.17 90) (layer "F.Fab") hide
        (effects (font (size 0.7 0.7) (thickness 0.15)) (justify left bottom))
    )
    (fp_text user "${REFERENCE}" (at -0.932 3.168 90) (layer "F.Fab") hide
        (effects (font (size 0.7 0.7) (thickness 0.15)) (justify left bottom))
    )
    (fp_rect (start -0.925 -0.47) (end 0.925 0.47)
      (stroke (width 0.05) (type default)) (fill none) (layer "F.CrtYd"))
    (fp_line (start -0.494 -0.25) (end 0.504 -0.25)
      (stroke (width 0.15) (type solid)) (layer "F.Fab"))
    (fp_line (start -0.494 0.248) (end -0.494 -0.25)
      (stroke (width 0.15) (type solid)) (layer "F.Fab"))
    (fp_line (start 0.504 -0.25) (end 0.504 0.248)
      (stroke (width 0.15) (type solid)) (layer "F.Fab"))
    (fp_line (start 0.504 0.248) (end -0.494 0.248)
      (stroke (width 0.15) (type solid)) (layer "F.Fab"))
    (pad "1" smd roundrect (at -0.48 0 90) (size 0.59 0.64) (layers "F.Cu" "F.Paste" "F.Mask") (roundrect_rratio 0.25)
      (net 2 "GND") (pintype "passive"))
    (pad "2" smd roundrect (at 0.48 0 90) (size 0.59 0.64) (layers "F.Cu" "F.Paste" "F.Mask") (roundrect_rratio 0.25)
      (net 10 "Net-(Y1-EN)") (pintype "passive"))
  )

  (footprint "antmicro-footprints:R_0402_1005Metric" (layer "F.Cu")
    (at 139.26 105.79 180)
    (descr "Resistor SMD 0402")
    (tags "resistor SMD 0402")
    (property "Author" "Antmicro")
    (property "License" "Apache-2.0")
    (property "MPN" "CR0402-FX-2001GLF")
    (property "Manufacturer" "Bourns")
    (property "Public" "False")
    (property "Sheetfile" "channel1.kicad_sch")
    (property "Sheetname" "Channel 1")
    (property "Tolerance" "1%")
    (property "Val" "2k")
    (property "ki_description" "SMD Chip Resistor, 2 kohm, ± 1%, 62.5 mW, 0402 [1005 Metric], Thick Film, General Purpose")
    (property "ki_keywords" "0402, SMT, RESISTOR, PASSIVE")
    (attr smd)
    (fp_text reference "R4" (at 2.33 -0.39 180) (layer "F.SilkS")
        (effects (font (size 0.65 0.65) (thickness 0.13)) (justify left bottom))
    )
    (fp_text value "R_2k_0402" (at 0 1.4 180) (layer "F.Fab")
        (effects (font (size 0.65 0.65) (thickness 0.13)) (justify left bottom))
    )
    (fp_text user "Author: Antmicro" (at -0.95 4.169 180) (layer "F.Fab") hide
        (effects (font (size 0.7 0.7) (thickness 0.15)) (justify left bottom))
    )
    (fp_text user "${REFERENCE}" (at -0.95 3.168 180) (layer "F.Fab") hide
        (effects (font (size 0.7 0.7) (thickness 0.15)) (justify left bottom))
    )
    (fp_text user "License: Apache-2.0" (at -0.95 5.169 180) (layer "F.Fab") hide
        (effects (font (size 0.7 0.7) (thickness 0.15)) (justify left bottom))
    )
    (fp_rect (start -0.925 -0.47) (end 0.925 0.47)
      (stroke (width 0.05) (type default)) (fill none) (layer "F.CrtYd"))
    (fp_rect (start -0.5 -0.25) (end 0.5 0.25)
      (stroke (width 0.15) (type solid)) (fill none) (layer "F.Fab"))
    (pad "1" smd roundrect (at -0.48 0 180) (size 0.59 0.64) (layers "F.Cu" "F.Paste" "F.Mask") (roundrect_rratio 0.25)
      (net 113 "Net-(U1B-REXT)") (pintype "passive"))
    (pad "2" smd roundrect (at 0.48 0 180) (size 0.59 0.64) (layers "F.Cu" "F.Paste" "F.Mask") (roundrect_rratio 0.25)
      (net 100 "/Channel 1/CH1_AVDD33") (pintype "passive"))
  )

  (footprint "antmicro-footprints:R_0603_1608Metric" (layer "F.Cu")
    (at 144.9 103.35)
    (descr "Resistor SMD 0603")
    (tags "resistor SMD 0603")
    (property "Author" "Antmicro")
    (property "Current" "1A")
    (property "License" "Apache-2.0")
    (property "MPN" "CR0603-J/-000ELF")
    (property "Manufacturer" "Bourns")
    (property "Public" "False")
    (property "Sheetfile" "channel1.kicad_sch")
    (property "Sheetname" "Channel 1")
    (property "Tolerance" "")
    (property "Val" "0R")
    (property "ki_description" "Zero Ohm Resistor, Jumper, 0603 [1608 Metric], Thick Film, 100 mW, 1 A, Surface Mount Device, CR")
    (property "ki_keywords" "0603, SMT, RESISTOR, PASSIVE")
    (attr smd)
    (fp_text reference "R2" (at 1.1 0.4) (layer "F.SilkS")
        (effects (font (size 0.7 0.7) (thickness 0.15)) (justify left bottom))
    )
    (fp_text value "R_0R_0603" (at 0 1.6) (layer "F.Fab")
        (effects (font (size 0.7 0.7) (thickness 0.15)) (justify left bottom))
    )
    (fp_text user "License: Apache-2.0" (at -1.25 5.9) (layer "F.Fab") hide
        (effects (font (size 0.7 0.7) (thickness 0.15)) (justify left bottom))
    )
    (fp_text user "${REFERENCE}" (at -1.25 3.898) (layer "F.Fab") hide
        (effects (font (size 0.7 0.7) (thickness 0.15)) (justify left bottom))
    )
    (fp_text user "Author: Antmicro" (at -1.25 4.9) (layer "F.Fab") hide
        (effects (font (size 0.7 0.7) (thickness 0.15)) (justify left bottom))
    )
    (fp_line (start -0.15 -0.4) (end 0.15 -0.4)
      (stroke (width 0.15) (type solid)) (layer "F.SilkS"))
    (fp_line (start -0.15 0.4) (end 0.15 0.4)
      (stroke (width 0.15) (type solid)) (layer "F.SilkS"))
    (fp_rect (start -1.25 -0.65) (end 1.25 0.65)
      (stroke (width 0.05) (type solid)) (fill none) (layer "F.CrtYd"))
    (fp_rect (start -0.8 -0.4) (end 0.8 0.4)
      (stroke (width 0.15) (type solid)) (fill none) (layer "F.Fab"))
    (pad "1" smd roundrect (at -0.7 0) (size 0.8 1) (layers "F.Cu" "F.Paste" "F.Mask") (roundrect_rratio 0.2)
      (net 86 "/Channel 1/HDMI1_POWER") (pintype "passive"))
    (pad "2" smd roundrect (at 0.7 0) (size 0.8 1) (layers "F.Cu" "F.Paste" "F.Mask") (roundrect_rratio 0.2)
      (net 97 "/Channel 1/HDMI1_HPDI") (pintype "passive"))
  )

  (footprint "antmicro-footprints:R_0402_1005Metric" (layer "F.Cu")
    (at 143.87 104.59)
    (descr "Resistor SMD 0402")
    (tags "resistor SMD 0402")
    (property "Author" "Antmicro")
    (property "License" "Apache-2.0")
    (property "MPN" "CR0402-FX-1002GLF")
    (property "Manufacturer" "Bourns")
    (property "Public" "False")
    (property "Sheetfile" "channel1.kicad_sch")
    (property "Sheetname" "Channel 1")
    (property "Tolerance" "1%")
    (property "Val" "10k")
    (property "ki_description" "SMD Chip Resistor, 10 kohm, ± 1%, 62.5 mW, 0402 [1005 Metric], Thick Film, General Purpose")
    (property "ki_keywords" "0402, SMT, RESISTOR, PASSIVE")
    (attr smd)
    (fp_text reference "R12" (at 0.73 0.16) (layer "F.SilkS")
        (effects (font (size 0.65 0.65) (thickness 0.13)) (justify left bottom))
    )
    (fp_text value "R_10k_0402" (at 0 1.4) (layer "F.Fab")
        (effects (font (size 0.65 0.65) (thickness 0.13)) (justify left bottom))
    )
    (fp_text user "Author: Antmicro" (at -0.95 4.169) (layer "F.Fab") hide
        (effects (font (size 0.7 0.7) (thickness 0.15)) (justify left bottom))
    )
    (fp_text user "${REFERENCE}" (at -0.95 3.168) (layer "F.Fab") hide
        (effects (font (size 0.7 0.7) (thickness 0.15)) (justify left bottom))
    )
    (fp_text user "License: Apache-2.0" (at -0.95 5.169) (layer "F.Fab") hide
        (effects (font (size 0.7 0.7) (thickness 0.15)) (justify left bottom))
    )
    (fp_rect (start -0.925 -0.47) (end 0.925 0.47)
      (stroke (width 0.05) (type default)) (fill none) (layer "F.CrtYd"))
    (fp_rect (start -0.5 -0.25) (end 0.5 0.25)
      (stroke (width 0.15) (type solid)) (fill none) (layer "F.Fab"))
    (pad "1" smd roundrect (at -0.48 0) (size 0.59 0.64) (layers "F.Cu" "F.Paste" "F.Mask") (roundrect_rratio 0.25)
      (net 85 "/Channel 1/HDMI1_DDC_SDA") (pintype "passive"))
    (pad "2" smd roundrect (at 0.48 0) (size 0.59 0.64) (layers "F.Cu" "F.Paste" "F.Mask") (roundrect_rratio 0.25)
      (net 14 "+5V") (pintype "passive"))
  )

  (footprint "antmicro-footprints:C_0402_1005Metric" (layer "F.Cu")
    (at 139.64 108.15)
    (descr "Capacitor SMD 0402")
    (tags "capacitor SMD 0402")
    (property "Author" "Antmicro")
    (property "Dielectric" "")
    (property "License" "Apache-2.0")
    (property "MPN" "0402B471K250CT")
    (property "Manufacturer" "Walsin")
    (property "Public" "False")
    (property "Sheetfile" "channel1.kicad_sch")
    (property "Sheetname" "Channel 1")
    (property "Val" "470p")
    (property "Voltage" "")
    (property "ki_description" "SMD Multilayer Ceramic Capacitor, General Purpose, 470 pF, 25 V, 0402 [1005 Metric], ± 10%, X7R")
    (property "ki_keywords" "0402, SMT, CAPACITOR, PASSIVE, MLCC")
    (attr smd)
    (fp_text reference "C5" (at 0.78 0.39) (layer "F.SilkS")
        (effects (font (size 0.65 0.65) (thickness 0.13)) (justify left bottom))
    )
    (fp_text value "C_470p_0402" (at 0 1.4) (layer "F.Fab")
        (effects (font (size 0.65 0.65) (thickness 0.13)) (justify left bottom))
    )
    (fp_text user "License: Apache-2.0" (at -0.932 5.17) (layer "F.Fab") hide
        (effects (font (size 0.7 0.7) (thickness 0.15)) (justify left bottom))
    )
    (fp_text user "${REFERENCE}" (at -0.932 3.168) (layer "F.Fab") hide
        (effects (font (size 0.7 0.7) (thickness 0.15)) (justify left bottom))
    )
    (fp_text user "Author: Antmicro" (at -0.932 4.17) (layer "F.Fab") hide
        (effects (font (size 0.7 0.7) (thickness 0.15)) (justify left bottom))
    )
    (fp_rect (start -0.925 -0.47) (end 0.925 0.47)
      (stroke (width 0.05) (type default)) (fill none) (layer "F.CrtYd"))
    (fp_line (start -0.494 -0.25) (end 0.504 -0.25)
      (stroke (width 0.15) (type solid)) (layer "F.Fab"))
    (fp_line (start -0.494 0.248) (end -0.494 -0.25)
      (stroke (width 0.15) (type solid)) (layer "F.Fab"))
    (fp_line (start 0.504 -0.25) (end 0.504 0.248)
      (stroke (width 0.15) (type solid)) (layer "F.Fab"))
    (fp_line (start 0.504 0.248) (end -0.494 0.248)
      (stroke (width 0.15) (type solid)) (layer "F.Fab"))
    (pad "1" smd roundrect (at -0.48 0) (size 0.59 0.64) (layers "F.Cu" "F.Paste" "F.Mask") (roundrect_rratio 0.25)
      (net 6 "Net-(C5-Pad1)") (pintype "passive"))
    (pad "2" smd roundrect (at 0.48 0) (size 0.59 0.64) (layers "F.Cu" "F.Paste" "F.Mask") (roundrect_rratio 0.25)
      (net 2 "GND") (pintype "passive"))
  )

  (footprint "antmicro-footprints:C_0402_1005Metric" (layer "F.Cu")
    (at 155.01 108.45 180)
    (descr "Capacitor SMD 0402")
    (tags "capacitor SMD 0402")
    (property "Author" "Antmicro")
    (property "Dielectric" "")
    (property "License" "Apache-2.0")
    (property "MPN" "0402B471K250CT")
    (property "Manufacturer" "Walsin")
    (property "Public" "False")
    (property "Sheetfile" "channel2.kicad_sch")
    (property "Sheetname" "Channel 2")
    (property "Val" "470p")
    (property "Voltage" "")
    (property "ki_description" "SMD Multilayer Ceramic Capacitor, General Purpose, 470 pF, 25 V, 0402 [1005 Metric], ± 10%, X7R")
    (property "ki_keywords" "0402, SMT, CAPACITOR, PASSIVE, MLCC")
    (attr smd)
    (fp_text reference "C50" (at -0.62 -7.52) (layer "F.SilkS")
        (effects (font (size 0.65 0.65) (thickness 0.13)) (justify right bottom))
    )
    (fp_text value "C_470p_0402" (at 0 1.4) (layer "F.Fab")
        (effects (font (size 0.65 0.65) (thickness 0.13)) (justify right bottom))
    )
    (fp_text user "${REFERENCE}" (at -0.932 3.168) (layer "F.Fab") hide
        (effects (font (size 0.7 0.7) (thickness 0.15)) (justify right bottom))
    )
    (fp_text user "License: Apache-2.0" (at -0.932 5.17) (layer "F.Fab") hide
        (effects (font (size 0.7 0.7) (thickness 0.15)) (justify right bottom))
    )
    (fp_text user "Author: Antmicro" (at -0.932 4.17) (layer "F.Fab") hide
        (effects (font (size 0.7 0.7) (thickness 0.15)) (justify right bottom))
    )
    (fp_rect (start -0.925 -0.47) (end 0.925 0.47)
      (stroke (width 0.05) (type default)) (fill none) (layer "F.CrtYd"))
    (fp_line (start -0.494 -0.25) (end 0.504 -0.25)
      (stroke (width 0.15) (type solid)) (layer "F.Fab"))
    (fp_line (start -0.494 0.248) (end -0.494 -0.25)
      (stroke (width 0.15) (type solid)) (layer "F.Fab"))
    (fp_line (start 0.504 -0.25) (end 0.504 0.248)
      (stroke (width 0.15) (type solid)) (layer "F.Fab"))
    (fp_line (start 0.504 0.248) (end -0.494 0.248)
      (stroke (width 0.15) (type solid)) (layer "F.Fab"))
    (pad "1" smd roundrect (at -0.48 0 180) (size 0.59 0.64) (layers "F.Cu" "F.Paste" "F.Mask") (roundrect_rratio 0.25)
      (net 33 "Net-(U4B-VDDC1)") (pintype "passive"))
    (pad "2" smd roundrect (at 0.48 0 180) (size 0.59 0.64) (layers "F.Cu" "F.Paste" "F.Mask") (roundrect_rratio 0.25)
      (net 2 "GND") (pintype "passive"))
  )

  (footprint "antmicro-footprints:C_0402_1005Metric" (layer "F.Cu")
    (at 155.07 112.45)
    (descr "Capacitor SMD 0402")
    (tags "capacitor SMD 0402")
    (property "Author" "Antmicro")
    (property "Dielectric" "C0G")
    (property "License" "Apache-2.0")
    (property "MPN" "C0402C470J5GACTU")
    (property "Manufacturer" "KEMET")
    (property "Public" "False")
    (property "Sheetfile" "channel2.kicad_sch")
    (property "Sheetname" "Channel 2")
    (property "Val" "47p")
    (property "Voltage" "")
    (property "ki_description" "SMD Multilayer Ceramic Capacitor, 47 pF, 50 V, 0402 [1005 Metric], ± 5%, C0G / NP0, C Series KEMET")
    (property "ki_keywords" "0402, SMT, CAPACITOR, PASSIVE, CERAMIC, MLCC")
    (attr smd)
    (fp_text reference "C46" (at -1.56 7.52) (layer "F.SilkS")
        (effects (font (size 0.65 0.65) (thickness 0.13)) (justify left bottom))
    )
    (fp_text value "C_47p_0402" (at 0 1.4) (layer "F.Fab")
        (effects (font (size 0.65 0.65) (thickness 0.13)) (justify left bottom))
    )
    (fp_text user "Author: Antmicro" (at -0.932 4.17) (layer "F.Fab") hide
        (effects (font (size 0.7 0.7) (thickness 0.15)) (justify left bottom))
    )
    (fp_text user "License: Apache-2.0" (at -0.932 5.17) (layer "F.Fab") hide
        (effects (font (size 0.7 0.7) (thickness 0.15)) (justify left bottom))
    )
    (fp_text user "${REFERENCE}" (at -0.932 3.168) (layer "F.Fab") hide
        (effects (font (size 0.7 0.7) (thickness 0.15)) (justify left bottom))
    )
    (fp_rect (start -0.925 -0.47) (end 0.925 0.47)
      (stroke (width 0.05) (type default)) (fill none) (layer "F.CrtYd"))
    (fp_line (start -0.494 -0.25) (end 0.504 -0.25)
      (stroke (width 0.15) (type solid)) (layer "F.Fab"))
    (fp_line (start -0.494 0.248) (end -0.494 -0.25)
      (stroke (width 0.15) (type solid)) (layer "F.Fab"))
    (fp_line (start 0.504 -0.25) (end 0.504 0.248)
      (stroke (width 0.15) (type solid)) (layer "F.Fab"))
    (fp_line (start 0.504 0.248) (end -0.494 0.248)
      (stroke (width 0.15) (type solid)) (layer "F.Fab"))
    (pad "1" smd roundrect (at -0.48 0) (size 0.59 0.64) (layers "F.Cu" "F.Paste" "F.Mask") (roundrect_rratio 0.25)
      (net 2 "GND") (pintype "passive"))
    (pad "2" smd roundrect (at 0.48 0) (size 0.59 0.64) (layers "F.Cu" "F.Paste" "F.Mask") (roundrect_rratio 0.25)
      (net 27 "/Channel 2/CH2_REFCLK") (pintype "passive"))
  )

  (footprint "antmicro-footprints:C_0402_1005Metric" (layer "F.Cu")
    (at 131 112.4)
    (descr "Capacitor SMD 0402")
    (tags "capacitor SMD 0402")
    (property "Author" "Antmicro")
    (property "Dielectric" "C0G")
    (property "License" "Apache-2.0")
    (property "MPN" "C0402C470J5GACTU")
    (property "Manufacturer" "KEMET")
    (property "Public" "False")
    (property "Sheetfile" "channel1.kicad_sch")
    (property "Sheetname" "Channel 1")
    (property "Val" "47p")
    (property "Voltage" "")
    (property "ki_description" "SMD Multilayer Ceramic Capacitor, 47 pF, 50 V, 0402 [1005 Metric], ± 5%, C0G / NP0, C Series KEMET")
    (property "ki_keywords" "0402, SMT, CAPACITOR, PASSIVE, CERAMIC, MLCC")
    (attr smd)
    (fp_text reference "C23" (at -1.6 7.6) (layer "F.SilkS")
        (effects (font (size 0.65 0.65) (thickness 0.13)) (justify left bottom))
    )
    (fp_text value "C_47p_0402" (at 0 1.4) (layer "F.Fab")
        (effects (font (size 0.65 0.65) (thickness 0.13)) (justify left bottom))
    )
    (fp_text user "License: Apache-2.0" (at -0.932 5.17) (layer "F.Fab") hide
        (effects (font (size 0.7 0.7) (thickness 0.15)) (justify left bottom))
    )
    (fp_text user "${REFERENCE}" (at -0.932 3.168) (layer "F.Fab") hide
        (effects (font (size 0.7 0.7) (thickness 0.15)) (justify left bottom))
    )
    (fp_text user "Author: Antmicro" (at -0.932 4.17) (layer "F.Fab") hide
        (effects (font (size 0.7 0.7) (thickness 0.15)) (justify left bottom))
    )
    (fp_rect (start -0.925 -0.47) (end 0.925 0.47)
      (stroke (width 0.05) (type default)) (fill none) (layer "F.CrtYd"))
    (fp_line (start -0.494 -0.25) (end 0.504 -0.25)
      (stroke (width 0.15) (type solid)) (layer "F.Fab"))
    (fp_line (start -0.494 0.248) (end -0.494 -0.25)
      (stroke (width 0.15) (type solid)) (layer "F.Fab"))
    (fp_line (start 0.504 -0.25) (end 0.504 0.248)
      (stroke (width 0.15) (type solid)) (layer "F.Fab"))
    (fp_line (start 0.504 0.248) (end -0.494 0.248)
      (stroke (width 0.15) (type solid)) (layer "F.Fab"))
    (pad "1" smd roundrect (at -0.48 0) (size 0.59 0.64) (layers "F.Cu" "F.Paste" "F.Mask") (roundrect_rratio 0.25)
      (net 2 "GND") (pintype "passive"))
    (pad "2" smd roundrect (at 0.48 0) (size 0.59 0.64) (layers "F.Cu" "F.Paste" "F.Mask") (roundrect_rratio 0.25)
      (net 15 "/Channel 1/CH1_REFCLK") (pintype "passive"))
  )

  (footprint "antmicro-footprints:C_0402_1005Metric" (layer "F.Cu")
    (at 163.79 110.85)
    (descr "Capacitor SMD 0402")
    (tags "capacitor SMD 0402")
    (property "Author" "Antmicro")
    (property "Dielectric" "")
    (property "License" "Apache-2.0")
    (property "MPN" "0402B471K250CT")
    (property "Manufacturer" "Walsin")
    (property "Public" "False")
    (property "Sheetfile" "channel2.kicad_sch")
    (property "Sheetname" "Channel 2")
    (property "Val" "470p")
    (property "Voltage" "")
    (property "ki_description" "SMD Multilayer Ceramic Capacitor, General Purpose, 470 pF, 25 V, 0402 [1005 Metric], ± 10%, X7R")
    (property "ki_keywords" "0402, SMT, CAPACITOR, PASSIVE, MLCC")
    (attr smd)
    (fp_text reference "C47" (at -3.69 6.85) (layer "F.SilkS")
        (effects (font (size 0.65 0.65) (thickness 0.13)) (justify left bottom))
    )
    (fp_text value "C_470p_0402" (at 0 1.4) (layer "F.Fab")
        (effects (font (size 0.65 0.65) (thickness 0.13)) (justify left bottom))
    )
    (fp_text user "License: Apache-2.0" (at -0.932 5.17) (layer "F.Fab") hide
        (effects (font (size 0.7 0.7) (thickness 0.15)) (justify left bottom))
    )
    (fp_text user "${REFERENCE}" (at -0.932 3.168) (layer "F.Fab") hide
        (effects (font (size 0.7 0.7) (thickness 0.15)) (justify left bottom))
    )
    (fp_text user "Author: Antmicro" (at -0.932 4.17) (layer "F.Fab") hide
        (effects (font (size 0.7 0.7) (thickness 0.15)) (justify left bottom))
    )
    (fp_rect (start -0.925 -0.47) (end 0.925 0.47)
      (stroke (width 0.05) (type default)) (fill none) (layer "F.CrtYd"))
    (fp_line (start -0.494 -0.25) (end 0.504 -0.25)
      (stroke (width 0.15) (type solid)) (layer "F.Fab"))
    (fp_line (start -0.494 0.248) (end -0.494 -0.25)
      (stroke (width 0.15) (type solid)) (layer "F.Fab"))
    (fp_line (start 0.504 -0.25) (end 0.504 0.248)
      (stroke (width 0.15) (type solid)) (layer "F.Fab"))
    (fp_line (start 0.504 0.248) (end -0.494 0.248)
      (stroke (width 0.15) (type solid)) (layer "F.Fab"))
    (pad "1" smd roundrect (at -0.48 0) (size 0.59 0.64) (layers "F.Cu" "F.Paste" "F.Mask") (roundrect_rratio 0.25)
      (net 32 "Net-(U4B-AVDD25)") (pintype "passive"))
    (pad "2" smd roundrect (at 0.48 0) (size 0.59 0.64) (layers "F.Cu" "F.Paste" "F.Mask") (roundrect_rratio 0.25)
      (net 2 "GND") (pintype "passive"))
  )

  (footprint "antmicro-footprints:Oscillator_SMD_TXC_7C_5x3.2x1.2mm" (layer "F.Cu")
    (at 126.79 110.01)
    (property "Author" "Antmicro")
    (property "License" "Apache-2.0")
    (property "MPN" "7C-27.000MBB-T")
    (property "Manufacturer" "TXC")
    (property "Public" "False")
    (property "Sheetfile" "channel1.kicad_sch")
    (property "Sheetname" "Channel 1")
    (property "Val" "27 MHz")
    (property "ki_description" "Oscillator, 27 MHz, 50 ppm, SMT, 5mm x 3.2mm, 3.3 V, 7C Series")
    (property "ki_keywords" "OSCILLATOR")
    (attr smd)
    (fp_text reference "Y1" (at 0.66 3.75 180) (layer "F.SilkS")
        (effects (font (size 0.65 0.65) (thickness 0.13)) (justify right bottom))
    )
    (fp_text value "Oscillator_27MHz_TXC_7C" (at -4.1148 3.4544) (layer "F.Fab")
        (effects (font (size 0.65 0.65) (thickness 0.13)) (justify left bottom))
    )
    (fp_text user "${REFERENCE}" (at -2.668 5.573) (layer "F.Fab") hide
        (effects (font (size 0.7 0.7) (thickness 0.15)) (justify left bottom))
    )
    (fp_text user "License: Apache-2.0" (at -2.668 7.972) (layer "F.Fab") hide
        (effects (font (size 0.7 0.7) (thickness 0.15)) (justify left bottom))
    )
    (fp_text user "Author: Antmicro" (at -2.668 6.773) (layer "F.Fab") hide
        (effects (font (size 0.7 0.7) (thickness 0.15)) (justify left bottom))
    )
    (fp_line (start -1.7 1.1) (end -1.7 -1.1)
      (stroke (width 0.12) (type solid)) (layer "F.SilkS"))
    (fp_line (start -0.4 -2.6) (end 0.4 -2.6)
      (stroke (width 0.12) (type solid)) (layer "F.SilkS"))
    (fp_line (start -0.4 2.6) (end 0.4 2.6)
      (stroke (width 0.12) (type solid)) (layer "F.SilkS"))
    (fp_line (start 1.7 1.1) (end 1.7 -1.1)
      (stroke (width 0.12) (type solid)) (layer "F.SilkS"))
    (fp_circle (center -1.8438 -2.2532) (end -1.8438 -2.2032)
      (stroke (width 0.15) (type solid)) (fill solid) (layer "F.SilkS"))
    (fp_rect (start -1.9 -2.85) (end 1.9 2.8)
      (stroke (width 0.05) (type solid)) (fill none) (layer "F.CrtYd"))
    (pad "1" smd rect (at -1.099 -1.9 270) (size 1.4 1.2) (layers "F.Cu" "F.Paste" "F.Mask")
      (net 10 "Net-(Y1-EN)") (pinfunction "EN") (pintype "input"))
    (pad "2" smd rect (at -1.1 1.9 270) (size 1.4 1.2) (layers "F.Cu" "F.Paste" "F.Mask")
      (net 2 "GND") (pinfunction "GND") (pintype "power_in"))
    (pad "3" smd rect (at 1.099 1.9 270) (size 1.4 1.2) (layers "F.Cu" "F.Paste" "F.Mask")
      (net 13 "Net-(Y1-OUT)") (pinfunction "OUT") (pintype "output"))
    (pad "4" smd rect (at 1.1 -1.9 270) (size 1.4 1.2) (layers "F.Cu" "F.Paste" "F.Mask")
      (net 10 "Net-(Y1-EN)") (pinfunction "VDD") (pintype "power_in"))
  )

  (footprint "antmicro-footprints:R_0402_1005Metric" (layer "F.Cu")
    (at 145.1 108.085 -90)
    (descr "Resistor SMD 0402")
    (tags "resistor SMD 0402")
    (property "Author" "Antmicro")
    (property "License" "Apache-2.0")
    (property "MPN" "CR0402-FX-1002GLF")
    (property "Manufacturer" "Bourns")
    (property "Public" "False")
    (property "Sheetfile" "channel1.kicad_sch")
    (property "Sheetname" "Channel 1")
    (property "Tolerance" "1%")
    (property "Val" "10k")
    (property "ki_description" "SMD Chip Resistor, 10 kohm, ± 1%, 62.5 mW, 0402 [1005 Metric], Thick Film, General Purpose")
    (property "ki_keywords" "0402, SMT, RESISTOR, PASSIVE")
    (attr smd)
    (fp_text reference "R9" (at -1.035 -1.5 -90) (layer "F.SilkS")
        (effects (font (size 0.65 0.65) (thickness 0.13)) (justify left bottom))
    )
    (fp_text value "R_10k_0402" (at 0 1.4 -90) (layer "F.Fab")
        (effects (font (size 0.65 0.65) (thickness 0.13)) (justify left bottom))
    )
    (fp_text user "${REFERENCE}" (at -0.95 3.168 -90) (layer "F.Fab") hide
        (effects (font (size 0.7 0.7) (thickness 0.15)) (justify left bottom))
    )
    (fp_text user "License: Apache-2.0" (at -0.95 5.169 -90) (layer "F.Fab") hide
        (effects (font (size 0.7 0.7) (thickness 0.15)) (justify left bottom))
    )
    (fp_text user "Author: Antmicro" (at -0.95 4.169 -90) (layer "F.Fab") hide
        (effects (font (size 0.7 0.7) (thickness 0.15)) (justify left bottom))
    )
    (fp_rect (start -0.925 -0.47) (end 0.925 0.47)
      (stroke (width 0.05) (type default)) (fill none) (layer "F.CrtYd"))
    (fp_rect (start -0.5 -0.25) (end 0.5 0.25)
      (stroke (width 0.15) (type solid)) (fill none) (layer "F.Fab"))
    (pad "1" smd roundrect (at -0.48 0 270) (size 0.59 0.64) (layers "F.Cu" "F.Paste" "F.Mask") (roundrect_rratio 0.25)
      (net 104 "/Channel 1/HDMI1_DDC_SDA_3V3") (pintype "passive"))
    (pad "2" smd roundrect (at 0.48 0 270) (size 0.59 0.64) (layers "F.Cu" "F.Paste" "F.Mask") (roundrect_rratio 0.25)
      (net 9 "+3V3") (pintype "passive"))
  )

  (footprint "antmicro-footprints:R_0402_1005Metric" (layer "F.Cu")
    (at 131 111.4)
    (descr "Resistor SMD 0402")
    (tags "resistor SMD 0402")
    (property "Author" "Antmicro")
    (property "License" "Apache-2.0")
    (property "MPN" "CR0402-FX-22R0GLF")
    (property "Manufacturer" "Bourns")
    (property "Public" "False")
    (property "Sheetfile" "channel1.kicad_sch")
    (property "Sheetname" "Channel 1")
    (property "Tolerance" "1%")
    (property "Val" "22R")
    (property "ki_description" "SMD Chip Resistor, 22 ohm, ± 1%, 62.5 mW, 0402 [1005 Metric], Thick Film, General Purpose")
    (property "ki_keywords" "0402, SMT, RESISTOR, PASSIVE")
    (attr smd)
    (fp_text reference "R13" (at -1.6 7.6) (layer "F.SilkS")
        (effects (font (size 0.65 0.65) (thickness 0.13)) (justify left bottom))
    )
    (fp_text value "R_22R_0402" (at 0 1.4) (layer "F.Fab")
        (effects (font (size 0.65 0.65) (thickness 0.13)) (justify left bottom))
    )
    (fp_text user "License: Apache-2.0" (at -0.95 5.169) (layer "F.Fab") hide
        (effects (font (size 0.7 0.7) (thickness 0.15)) (justify left bottom))
    )
    (fp_text user "Author: Antmicro" (at -0.95 4.169) (layer "F.Fab") hide
        (effects (font (size 0.7 0.7) (thickness 0.15)) (justify left bottom))
    )
    (fp_text user "${REFERENCE}" (at -0.95 3.168) (layer "F.Fab") hide
        (effects (font (size 0.7 0.7) (thickness 0.15)) (justify left bottom))
    )
    (fp_rect (start -0.925 -0.47) (end 0.925 0.47)
      (stroke (width 0.05) (type default)) (fill none) (layer "F.CrtYd"))
    (fp_rect (start -0.5 -0.25) (end 0.5 0.25)
      (stroke (width 0.15) (type solid)) (fill none) (layer "F.Fab"))
    (pad "1" smd roundrect (at -0.48 0) (size 0.59 0.64) (layers "F.Cu" "F.Paste" "F.Mask") (roundrect_rratio 0.25)
      (net 13 "Net-(Y1-OUT)") (pintype "passive"))
    (pad "2" smd roundrect (at 0.48 0) (size 0.59 0.64) (layers "F.Cu" "F.Paste" "F.Mask") (roundrect_rratio 0.25)
      (net 15 "/Channel 1/CH1_REFCLK") (pintype "passive"))
  )

  (footprint "antmicro-footprints:antmicro-logo_scaled_20mm_mask" (layer "F.Cu")
    (at 178.6 108.3 -90)
    (descr "Antmicro Logo scaled 20mm F.Mask")
    (tags "Antmicro Logo scaled 20mm F.Mask")
    (property "Author" "Antmicro")
    (property "License" "Apache-2.0")
    (property "MPN" "")
    (property "Manufacturer" "")
    (property "Public" "False")
    (property "Sheetfile" "antmicro-hdmi-mipi-bridge-hw.kicad_sch")
    (property "Sheetname" "")
    (property "exclude_from_bom" "")
    (property "ki_description" "Mechanical part")
    (attr through_hole exclude_from_pos_files exclude_from_bom)
    (fp_text reference "N1" (at 0.05 -5.5 90) (layer "F.SilkS") hide
        (effects (font (size 0.7 0.7) (thickness 0.15)) (justify right bottom))
    )
    (fp_text value "antmicro_logo" (at -0.101 5.099 90) (layer "F.SilkS") hide
        (effects (font (size 0.7 0.7) (thickness 0.15)) (justify right bottom))
    )
    (fp_text user "${REFERENCE}" (at -9.998 7.099 90) (layer "F.Fab") hide
        (effects (font (size 0.7 0.7) (thickness 0.15)) (justify right bottom))
    )
    (fp_text user "License: Apache-2.0" (at -9.998 9.099 90) (layer "F.Fab") hide
        (effects (font (size 0.7 0.7) (thickness 0.15)) (justify right bottom))
    )
    (fp_text user "Author: Antmicro" (at -9.998 8.099 90) (layer "F.Fab") hide
        (effects (font (size 0.7 0.7) (thickness 0.15)) (justify right bottom))
    )
    (fp_poly
      (pts
        (xy 5.212 0.944)
        (xy 4.834 0.944)
        (xy 4.834 -1.292)
        (xy 5.212 -1.292)
        (xy 5.212 0.944)
      )

      (stroke (width 0.00186) (type solid)) (fill solid) (layer "F.Mask"))
    (fp_poly
      (pts
        (xy 8.164 -1.321)
        (xy 8.193 -1.317)
        (xy 8.204 -1.31)
        (xy 8.204 -1.308)
        (xy 8.2 -1.285)
        (xy 8.188 -1.24)
        (xy 8.171 -1.181)
        (xy 8.163 -1.156)
        (xy 8.142 -1.092)
        (xy 8.126 -1.053)
        (xy 8.112 -1.034)
        (xy 8.097 -1.031)
        (xy 8.094 -1.032)
        (xy 7.996 -1.053)
        (xy 7.886 -1.06)
        (xy 7.778 -1.053)
        (xy 7.683 -1.032)
        (xy 7.665 -1.026)
        (xy 7.622 -1.009)
        (xy 7.622 0.944)
        (xy 7.244 0.944)
        (xy 7.244 -1.178)
        (xy 7.358 -1.219)
        (xy 7.457 -1.253)
        (xy 7.548 -1.277)
        (xy 7.639 -1.295)
        (xy 7.738 -1.307)
        (xy 7.856 -1.315)
        (xy 7.94 -1.319)
        (xy 8.042 -1.322)
        (xy 8.115 -1.322)
        (xy 8.164 -1.321)
      )

      (stroke (width 0.00186) (type solid)) (fill solid) (layer "F.Mask"))
    (fp_poly
      (pts
        (xy 0.795 -1.891)
        (xy 0.798 -1.849)
        (xy 0.8 -1.786)
        (xy 0.802 -1.705)
        (xy 0.803 -1.612)
        (xy 0.803 -1.599)
        (xy 0.803 -1.292)
        (xy 1.181 -1.292)
        (xy 1.181 -1.04)
        (xy 0.803 -1.04)
        (xy 0.803 0.498)
        (xy 0.838 0.566)
        (xy 0.885 0.631)
        (xy 0.944 0.671)
        (xy 1.021 0.688)
        (xy 1.082 0.689)
        (xy 1.181 0.685)
        (xy 1.181 0.806)
        (xy 1.178 0.88)
        (xy 1.17 0.926)
        (xy 1.161 0.939)
        (xy 1.138 0.945)
        (xy 1.09 0.95)
        (xy 1.028 0.954)
        (xy 0.984 0.956)
        (xy 0.897 0.957)
        (xy 0.832 0.953)
        (xy 0.778 0.942)
        (xy 0.743 0.931)
        (xy 0.647 0.886)
        (xy 0.571 0.823)
        (xy 0.508 0.737)
        (xy 0.488 0.701)
        (xy 0.433 0.593)
        (xy 0.428 -0.223)
        (xy 0.424 -1.04)
        (xy 0.173 -1.04)
        (xy 0.173 -1.292)
        (xy 0.425 -1.292)
        (xy 0.425 -1.795)
        (xy 0.603 -1.85)
        (xy 0.673 -1.872)
        (xy 0.733 -1.89)
        (xy 0.774 -1.902)
        (xy 0.792 -1.906)
        (xy 0.795 -1.891)
      )

      (stroke (width 0.00186) (type solid)) (fill solid) (layer "F.Mask"))
    (fp_poly
      (pts
        (xy -0.82 -1.315)
        (xy -0.737 -1.312)
        (xy -0.672 -1.308)
        (xy -0.621 -1.301)
        (xy -0.577 -1.291)
        (xy -0.56 -1.286)
        (xy -0.417 -1.232)
        (xy -0.302 -1.164)
        (xy -0.212 -1.082)
        (xy -0.154 -0.996)
        (xy -0.135 -0.961)
        (xy -0.119 -0.927)
        (xy -0.105 -0.893)
        (xy -0.094 -0.855)
        (xy -0.085 -0.811)
        (xy -0.078 -0.758)
        (xy -0.073 -0.693)
        (xy -0.069 -0.612)
        (xy -0.067 -0.515)
        (xy -0.065 -0.397)
        (xy -0.064 -0.256)
        (xy -0.064 -0.088)
        (xy -0.063 0.105)
        (xy -0.063 0.944)
        (xy -0.441 0.944)
        (xy -0.441 0.113)
        (xy -0.442 -0.083)
        (xy -0.442 -0.25)
        (xy -0.443 -0.391)
        (xy -0.445 -0.508)
        (xy -0.448 -0.604)
        (xy -0.452 -0.682)
        (xy -0.457 -0.744)
        (xy -0.465 -0.794)
        (xy -0.474 -0.833)
        (xy -0.486 -0.864)
        (xy -0.501 -0.89)
        (xy -0.518 -0.913)
        (xy -0.538 -0.937)
        (xy -0.539 -0.939)
        (xy -0.604 -0.997)
        (xy -0.684 -1.039)
        (xy -0.784 -1.066)
        (xy -0.822 -1.072)
        (xy -0.927 -1.078)
        (xy -1.044 -1.073)
        (xy -1.158 -1.056)
        (xy -1.24 -1.034)
        (xy -1.3 -1.013)
        (xy -1.304 -0.034)
        (xy -1.308 0.944)
        (xy -1.686 0.944)
        (xy -1.686 -1.178)
        (xy -1.54 -1.225)
        (xy -1.44 -1.257)
        (xy -1.354 -1.28)
        (xy -1.276 -1.297)
        (xy -1.195 -1.307)
        (xy -1.105 -1.313)
        (xy -0.995 -1.315)
        (xy -0.93 -1.315)
        (xy -0.82 -1.315)
      )

      (stroke (width 0.00186) (type solid)) (fill solid) (layer "F.Mask"))
    (fp_poly
      (pts
        (xy 3.757 -1.312)
        (xy 3.91 -1.278)
        (xy 4.043 -1.223)
        (xy 4.153 -1.146)
        (xy 4.24 -1.047)
        (xy 4.282 -0.977)
        (xy 4.299 -0.943)
        (xy 4.313 -0.91)
        (xy 4.325 -0.876)
        (xy 4.335 -0.837)
        (xy 4.343 -0.791)
        (xy 4.349 -0.734)
        (xy 4.353 -0.665)
        (xy 4.357 -0.581)
        (xy 4.359 -0.478)
        (xy 4.361 -0.354)
        (xy 4.361 -0.206)
        (xy 4.362 -0.031)
        (xy 4.362 0.111)
        (xy 4.362 0.944)
        (xy 3.985 0.944)
        (xy 3.98 0.074)
        (xy 3.976 -0.796)
        (xy 3.93 -0.879)
        (xy 3.867 -0.961)
        (xy 3.786 -1.022)
        (xy 3.691 -1.062)
        (xy 3.586 -1.079)
        (xy 3.476 -1.074)
        (xy 3.366 -1.045)
        (xy 3.26 -0.994)
        (xy 3.185 -0.938)
        (xy 3.118 -0.88)
        (xy 3.118 0.944)
        (xy 2.74 0.944)
        (xy 2.74 0.092)
        (xy 2.739 -0.122)
        (xy 2.739 -0.305)
        (xy 2.737 -0.459)
        (xy 2.735 -0.585)
        (xy 2.732 -0.683)
        (xy 2.729 -0.755)
        (xy 2.725 -0.802)
        (xy 2.722 -0.821)
        (xy 2.679 -0.91)
        (xy 2.613 -0.981)
        (xy 2.523 -1.034)
        (xy 2.413 -1.067)
        (xy 2.284 -1.079)
        (xy 2.154 -1.073)
        (xy 2.082 -1.064)
        (xy 2.031 -1.056)
        (xy 1.989 -1.046)
        (xy 1.944 -1.031)
        (xy 1.917 -1.021)
        (xy 1.874 -1.005)
        (xy 1.874 0.944)
        (xy 1.511 0.944)
        (xy 1.511 -1.18)
        (xy 1.661 -1.228)
        (xy 1.83 -1.276)
        (xy 1.988 -1.306)
        (xy 2.148 -1.319)
        (xy 2.314 -1.319)
        (xy 2.448 -1.311)
        (xy 2.557 -1.297)
        (xy 2.649 -1.272)
        (xy 2.732 -1.237)
        (xy 2.811 -1.189)
        (xy 2.843 -1.165)
        (xy 2.947 -1.087)
        (xy 3.012 -1.14)
        (xy 3.14 -1.224)
        (xy 3.283 -1.283)
        (xy 3.443 -1.315)
        (xy 3.582 -1.323)
        (xy 3.757 -1.312)
      )

      (stroke (width 0.00186) (type solid)) (fill solid) (layer "F.Mask"))
    (fp_poly
      (pts
        (xy 9.278 -1.313)
        (xy 9.419 -1.281)
        (xy 9.543 -1.225)
        (xy 9.656 -1.146)
        (xy 9.708 -1.097)
        (xy 9.808 -0.975)
        (xy 9.887 -0.831)
        (xy 9.945 -0.666)
        (xy 9.984 -0.476)
        (xy 9.998 -0.354)
        (xy 10.005 -0.134)
        (xy 9.992 0.072)
        (xy 9.96 0.262)
        (xy 9.908 0.434)
        (xy 9.837 0.585)
        (xy 9.749 0.714)
        (xy 9.643 0.819)
        (xy 9.578 0.867)
        (xy 9.475 0.918)
        (xy 9.352 0.956)
        (xy 9.219 0.98)
        (xy 9.087 0.986)
        (xy 8.966 0.975)
        (xy 8.81 0.933)
        (xy 8.673 0.864)
        (xy 8.553 0.771)
        (xy 8.452 0.653)
        (xy 8.371 0.511)
        (xy 8.31 0.346)
        (xy 8.277 0.202)
        (xy 8.249 -0.011)
        (xy 8.243 -0.182)
        (xy 8.619 -0.182)
        (xy 8.626 -0.007)
        (xy 8.647 0.163)
        (xy 8.682 0.318)
        (xy 8.73 0.449)
        (xy 8.792 0.552)
        (xy 8.87 0.633)
        (xy 8.961 0.69)
        (xy 9.06 0.721)
        (xy 9.164 0.724)
        (xy 9.268 0.699)
        (xy 9.303 0.683)
        (xy 9.391 0.625)
        (xy 9.465 0.546)
        (xy 9.524 0.443)
        (xy 9.569 0.315)
        (xy 9.601 0.162)
        (xy 9.62 0)
        (xy 9.628 -0.198)
        (xy 9.62 -0.382)
        (xy 9.597 -0.55)
        (xy 9.558 -0.698)
        (xy 9.505 -0.825)
        (xy 9.439 -0.927)
        (xy 9.397 -0.971)
        (xy 9.307 -1.035)
        (xy 9.21 -1.071)
        (xy 9.109 -1.079)
        (xy 9.009 -1.062)
        (xy 8.915 -1.019)
        (xy 8.831 -0.953)
        (xy 8.76 -0.863)
        (xy 8.733 -0.813)
        (xy 8.684 -0.68)
        (xy 8.648 -0.526)
        (xy 8.627 -0.358)
        (xy 8.619 -0.182)
        (xy 8.243 -0.182)
        (xy 8.242 -0.218)
        (xy 8.255 -0.417)
        (xy 8.288 -0.602)
        (xy 8.339 -0.772)
        (xy 8.41 -0.923)
        (xy 8.498 -1.051)
        (xy 8.524 -1.081)
        (xy 8.637 -1.182)
        (xy 8.765 -1.255)
        (xy 8.908 -1.302)
        (xy 9.068 -1.322)
        (xy 9.117 -1.323)
        (xy 9.278 -1.313)
      )

      (stroke (width 0.00186) (type solid)) (fill solid) (layer "F.Mask"))
    (fp_poly
      (pts
        (xy 6.48 -1.32)
        (xy 6.584 -1.31)
        (xy 6.642 -1.3)
        (xy 6.701 -1.282)
        (xy 6.765 -1.259)
        (xy 6.825 -1.233)
        (xy 6.873 -1.209)
        (xy 6.9 -1.189)
        (xy 6.902 -1.186)
        (xy 6.901 -1.166)
        (xy 6.889 -1.128)
        (xy 6.872 -1.079)
        (xy 6.852 -1.03)
        (xy 6.833 -0.989)
        (xy 6.818 -0.966)
        (xy 6.815 -0.963)
        (xy 6.795 -0.969)
        (xy 6.757 -0.985)
        (xy 6.717 -1.002)
        (xy 6.597 -1.044)
        (xy 6.478 -1.06)
        (xy 6.365 -1.05)
        (xy 6.267 -1.016)
        (xy 6.184 -0.957)
        (xy 6.109 -0.87)
        (xy 6.042 -0.76)
        (xy 5.988 -0.629)
        (xy 5.964 -0.554)
        (xy 5.946 -0.461)
        (xy 5.934 -0.347)
        (xy 5.929 -0.22)
        (xy 5.931 -0.091)
        (xy 5.938 0.032)
        (xy 5.953 0.138)
        (xy 5.965 0.191)
        (xy 6.018 0.347)
        (xy 6.085 0.476)
        (xy 6.166 0.576)
        (xy 6.262 0.649)
        (xy 6.269 0.653)
        (xy 6.318 0.678)
        (xy 6.36 0.692)
        (xy 6.409 0.698)
        (xy 6.476 0.7)
        (xy 6.48 0.7)
        (xy 6.551 0.697)
        (xy 6.613 0.686)
        (xy 6.676 0.665)
        (xy 6.75 0.631)
        (xy 6.805 0.602)
        (xy 6.811 0.606)
        (xy 6.823 0.627)
        (xy 6.842 0.667)
        (xy 6.868 0.73)
        (xy 6.904 0.819)
        (xy 6.907 0.827)
        (xy 6.898 0.844)
        (xy 6.866 0.868)
        (xy 6.818 0.895)
        (xy 6.759 0.922)
        (xy 6.697 0.945)
        (xy 6.68 0.95)
        (xy 6.596 0.968)
        (xy 6.494 0.98)
        (xy 6.388 0.984)
        (xy 6.292 0.98)
        (xy 6.251 0.975)
        (xy 6.192 0.96)
        (xy 6.121 0.935)
        (xy 6.055 0.906)
        (xy 5.924 0.825)
        (xy 5.811 0.718)
        (xy 5.717 0.586)
        (xy 5.641 0.431)
        (xy 5.585 0.252)
        (xy 5.566 0.164)
        (xy 5.552 0.061)
        (xy 5.545 -0.061)
        (xy 5.544 -0.193)
        (xy 5.549 -0.327)
        (xy 5.56 -0.453)
        (xy 5.576 -0.563)
        (xy 5.589 -0.623)
        (xy 5.65 -0.797)
        (xy 5.731 -0.949)
        (xy 5.831 -1.077)
        (xy 5.948 -1.181)
        (xy 6.081 -1.259)
        (xy 6.187 -1.298)
        (xy 6.27 -1.314)
        (xy 6.372 -1.322)
        (xy 6.48 -1.32)
      )

      (stroke (width 0.00186) (type solid)) (fill solid) (layer "F.Mask"))
    (fp_poly
      (pts
        (xy -2.763 -1.313)
        (xy -2.663 -1.294)
        (xy -2.55 -1.259)
        (xy -2.459 -1.216)
        (xy -2.38 -1.16)
        (xy -2.341 -1.124)
        (xy -2.284 -1.053)
        (xy -2.232 -0.961)
        (xy -2.192 -0.861)
        (xy -2.174 -0.79)
        (xy -2.17 -0.754)
        (xy -2.167 -0.69)
        (xy -2.164 -0.599)
        (xy -2.162 -0.485)
        (xy -2.16 -0.35)
        (xy -2.159 -0.196)
        (xy -2.158 -0.027)
        (xy -2.158 0.064)
        (xy -2.158 0.833)
        (xy -2.232 0.865)
        (xy -2.364 0.913)
        (xy -2.517 0.949)
        (xy -2.682 0.974)
        (xy -2.85 0.986)
        (xy -3.011 0.983)
        (xy -3.097 0.975)
        (xy -3.264 0.942)
        (xy -3.407 0.889)
        (xy -3.525 0.817)
        (xy -3.618 0.725)
        (xy -3.686 0.616)
        (xy -3.729 0.487)
        (xy -3.746 0.341)
        (xy -3.746 0.268)
        (xy -3.744 0.254)
        (xy -3.383 0.254)
        (xy -3.38 0.384)
        (xy -3.352 0.497)
        (xy -3.298 0.591)
        (xy -3.221 0.665)
        (xy -3.12 0.719)
        (xy -3.072 0.735)
        (xy -3.011 0.745)
        (xy -2.928 0.75)
        (xy -2.835 0.75)
        (xy -2.74 0.744)
        (xy -2.655 0.734)
        (xy -2.589 0.72)
        (xy -2.579 0.716)
        (xy -2.504 0.689)
        (xy -2.504 -0.302)
        (xy -2.595 -0.291)
        (xy -2.653 -0.282)
        (xy -2.728 -0.267)
        (xy -2.806 -0.25)
        (xy -2.831 -0.244)
        (xy -2.992 -0.194)
        (xy -3.125 -0.133)
        (xy -3.229 -0.06)
        (xy -3.306 0.026)
        (xy -3.357 0.125)
        (xy -3.381 0.238)
        (xy -3.383 0.254)
        (xy -3.744 0.254)
        (xy -3.725 0.126)
        (xy -3.678 0)
        (xy -3.602 -0.112)
        (xy -3.559 -0.158)
        (xy -3.465 -0.233)
        (xy -3.343 -0.303)
        (xy -3.198 -0.365)
        (xy -3.034 -0.417)
        (xy -2.856 -0.46)
        (xy -2.666 -0.49)
        (xy -2.663 -0.49)
        (xy -2.5 -0.51)
        (xy -2.51 -0.644)
        (xy -2.528 -0.77)
        (xy -2.564 -0.871)
        (xy -2.62 -0.949)
        (xy -2.697 -1.007)
        (xy -2.797 -1.045)
        (xy -2.845 -1.056)
        (xy -2.975 -1.067)
        (xy -3.12 -1.056)
        (xy -3.272 -1.024)
        (xy -3.426 -0.972)
        (xy -3.439 -0.967)
        (xy -3.488 -0.947)
        (xy -3.523 -0.936)
        (xy -3.537 -0.934)
        (xy -3.545 -0.95)
        (xy -3.56 -0.987)
        (xy -3.579 -1.035)
        (xy -3.598 -1.086)
        (xy -3.613 -1.129)
        (xy -3.622 -1.155)
        (xy -3.623 -1.159)
        (xy -3.609 -1.169)
        (xy -3.575 -1.188)
        (xy -3.537 -1.206)
        (xy -3.395 -1.257)
        (xy -3.239 -1.294)
        (xy -3.075 -1.316)
        (xy -2.914 -1.323)
        (xy -2.763 -1.313)
      )

      (stroke (width 0.00186) (type solid)) (fill solid) (layer "F.Mask"))
    (fp_poly
      (pts
        (xy -7.153 -3.366)
        (xy -7.087 -3.351)
        (xy -7.086 -3.351)
        (xy -7.066 -3.34)
        (xy -7.021 -3.315)
        (xy -6.953 -3.277)
        (xy -6.865 -3.227)
        (xy -6.759 -3.167)
        (xy -6.639 -3.099)
        (xy -6.505 -3.022)
        (xy -6.361 -2.94)
        (xy -6.209 -2.853)
        (xy -6.052 -2.762)
        (xy -5.891 -2.67)
        (xy -5.729 -2.577)
        (xy -5.569 -2.485)
        (xy -5.413 -2.395)
        (xy -5.264 -2.309)
        (xy -5.123 -2.227)
        (xy -4.994 -2.152)
        (xy -4.878 -2.085)
        (xy -4.778 -2.027)
        (xy -4.697 -1.979)
        (xy -4.636 -1.943)
        (xy -4.599 -1.921)
        (xy -4.595 -1.918)
        (xy -4.528 -1.863)
        (xy -4.476 -1.798)
        (xy -4.434 -1.725)
        (xy -4.429 -0.224)
        (xy -4.429 0.063)
        (xy -4.428 0.323)
        (xy -4.429 0.553)
        (xy -4.429 0.755)
        (xy -4.43 0.928)
        (xy -4.432 1.071)
        (xy -4.434 1.184)
        (xy -4.436 1.266)
        (xy -4.439 1.318)
        (xy -4.441 1.337)
        (xy -4.448 1.36)
        (xy -4.454 1.382)
        (xy -4.463 1.403)
        (xy -4.476 1.423)
        (xy -4.494 1.445)
        (xy -4.519 1.47)
        (xy -4.552 1.497)
        (xy -4.596 1.529)
        (xy -4.652 1.567)
        (xy -4.721 1.611)
        (xy -4.805 1.663)
        (xy -4.906 1.723)
        (xy -5.025 1.794)
        (xy -5.165 1.875)
        (xy -5.326 1.969)
        (xy -5.511 2.076)
        (xy -5.72 2.197)
        (xy -5.813 2.251)
        (xy -7.079 2.982)
        (xy -7.197 2.988)
        (xy -7.315 2.994)
        (xy -7.78 2.727)
        (xy -8.064 2.563)
        (xy -8.323 2.415)
        (xy -8.557 2.28)
        (xy -8.767 2.159)
        (xy -8.955 2.051)
        (xy -9.122 1.954)
        (xy -9.27 1.868)
        (xy -9.399 1.792)
        (xy -9.51 1.726)
        (xy -9.606 1.669)
        (xy -9.688 1.619)
        (xy -9.756 1.576)
        (xy -9.812 1.539)
        (xy -9.857 1.507)
        (xy -9.893 1.481)
        (xy -9.92 1.458)
        (xy -9.94 1.437)
        (xy -9.955 1.42)
        (xy -9.965 1.403)
        (xy -9.972 1.387)
        (xy -9.977 1.371)
        (xy -9.981 1.354)
        (xy -9.985 1.337)
        (xy -9.988 1.309)
        (xy -9.991 1.25)
        (xy -9.993 1.161)
        (xy -9.995 1.041)
        (xy -9.996 0.891)
        (xy -9.997 0.712)
        (xy -9.998 0.503)
        (xy -9.998 0.266)
        (xy -9.997 0)
        (xy -9.997 -0.189)
        (xy -9.024 -0.189)
        (xy -9.024 0.015)
        (xy -9.024 0.191)
        (xy -9.023 0.34)
        (xy -9.022 0.464)
        (xy -9.021 0.567)
        (xy -9.018 0.65)
        (xy -9.014 0.717)
        (xy -9.01 0.768)
        (xy -9.003 0.808)
        (xy -8.995 0.837)
        (xy -8.986 0.859)
        (xy -8.974 0.876)
        (xy -8.961 0.891)
        (xy -8.945 0.905)
        (xy -8.943 0.906)
        (xy -8.922 0.921)
        (xy -8.877 0.949)
        (xy -8.81 0.989)
        (xy -8.725 1.039)
        (xy -8.625 1.098)
        (xy -8.512 1.164)
        (xy -8.389 1.235)
        (xy -8.26 1.31)
        (xy -8.128 1.386)
        (xy -7.995 1.463)
        (xy -7.864 1.538)
        (xy -7.739 1.609)
        (xy -7.622 1.676)
        (xy -7.517 1.735)
        (xy -7.425 1.787)
        (xy -7.351 1.828)
        (xy -7.297 1.857)
        (xy -7.266 1.872)
        (xy -7.261 1.874)
        (xy -7.222 1.885)
        (xy -7.195 1.886)
        (xy -7.163 1.875)
        (xy -7.144 1.867)
        (xy -7.117 1.854)
        (xy -7.067 1.827)
        (xy -6.997 1.788)
        (xy -6.909 1.738)
        (xy -6.805 1.679)
        (xy -6.691 1.614)
        (xy -6.567 1.543)
        (xy -6.438 1.469)
        (xy -6.306 1.392)
        (xy -6.174 1.316)
        (xy -6.045 1.241)
        (xy -5.922 1.17)
        (xy -5.809 1.103)
        (xy -5.708 1.044)
        (xy -5.622 0.992)
        (xy -5.553 0.952)
        (xy -5.507 0.923)
        (xy -5.484 0.907)
        (xy -5.483 0.907)
        (xy -5.467 0.892)
        (xy -5.453 0.878)
        (xy -5.441 0.861)
        (xy -5.431 0.839)
        (xy -5.423 0.81)
        (xy -5.417 0.772)
        (xy -5.412 0.721)
        (xy -5.408 0.656)
        (xy -5.406 0.574)
        (xy -5.404 0.473)
        (xy -5.403 0.35)
        (xy -5.402 0.203)
        (xy -5.402 0.03)
        (xy -5.402 -0.172)
        (xy -5.402 -0.189)
        (xy -5.402 -0.395)
        (xy -5.402 -0.572)
        (xy -5.403 -0.721)
        (xy -5.404 -0.847)
        (xy -5.406 -0.95)
        (xy -5.408 -1.034)
        (xy -5.412 -1.101)
        (xy -5.418 -1.153)
        (xy -5.425 -1.193)
        (xy -5.434 -1.223)
        (xy -5.445 -1.245)
        (xy -5.458 -1.262)
        (xy -5.473 -1.276)
        (xy -5.491 -1.29)
        (xy -5.499 -1.295)
        (xy -5.522 -1.31)
        (xy -5.57 -1.339)
        (xy -5.64 -1.381)
        (xy -5.729 -1.433)
        (xy -5.835 -1.496)
        (xy -5.956 -1.566)
        (xy -6.088 -1.643)
        (xy -6.229 -1.725)
        (xy -6.348 -1.793)
        (xy -6.519 -1.891)
        (xy -6.664 -1.974)
        (xy -6.786 -2.044)
        (xy -6.888 -2.101)
        (xy -6.971 -2.147)
        (xy -7.038 -2.183)
        (xy -7.091 -2.21)
        (xy -7.132 -2.229)
        (xy -7.163 -2.242)
        (xy -7.187 -2.249)
        (xy -7.205 -2.252)
        (xy -7.211 -2.252)
        (xy -7.228 -2.251)
        (xy -7.249 -2.246)
        (xy -7.276 -2.236)
        (xy -7.312 -2.219)
        (xy -7.359 -2.196)
        (xy -7.419 -2.165)
        (xy -7.495 -2.123)
        (xy -7.587 -2.072)
        (xy -7.699 -2.008)
        (xy -7.832 -1.932)
        (xy -7.99 -1.842)
        (xy -8.1 -1.778)
        (xy -8.248 -1.693)
        (xy -8.388 -1.611)
        (xy -8.519 -1.535)
        (xy -8.637 -1.466)
        (xy -8.739 -1.406)
        (xy -8.825 -1.355)
        (xy -8.89 -1.316)
        (xy -8.933 -1.29)
        (xy -8.951 -1.278)
        (xy -8.966 -1.265)
        (xy -8.978 -1.251)
        (xy -8.989 -1.234)
        (xy -8.998 -1.212)
        (xy -9.005 -1.182)
        (xy -9.011 -1.141)
        (xy -9.015 -1.087)
        (xy -9.018 -1.019)
        (xy -9.021 -0.933)
        (xy -9.022 -0.827)
        (xy -9.023 -0.699)
        (xy -9.024 -0.546)
        (xy -9.024 -0.366)
        (xy -9.024 -0.189)
        (xy -9.997 -0.189)
        (xy -9.997 -0.224)
        (xy -9.996 -0.479)
        (xy -9.996 -0.705)
        (xy -9.995 -0.903)
        (xy -9.994 -1.075)
        (xy -9.993 -1.223)
        (xy -9.992 -1.35)
        (xy -9.99 -1.456)
        (xy -9.987 -1.545)
        (xy -9.984 -1.617)
        (xy -9.98 -1.675)
        (xy -9.974 -1.721)
        (xy -9.968 -1.757)
        (xy -9.961 -1.784)
        (xy -9.952 -1.805)
        (xy -9.941 -1.821)
        (xy -9.929 -1.834)
        (xy -9.915 -1.847)
        (xy -9.9 -1.86)
        (xy -9.893 -1.866)
        (xy -9.873 -1.88)
        (xy -9.828 -1.909)
        (xy -9.759 -1.951)
        (xy -9.669 -2.005)
        (xy -9.56 -2.07)
        (xy -9.433 -2.145)
        (xy -9.291 -2.228)
        (xy -9.136 -2.319)
        (xy -8.969 -2.416)
        (xy -8.793 -2.518)
        (xy -8.61 -2.624)
        (xy -8.59 -2.635)
        (xy -8.377 -2.759)
        (xy -8.189 -2.867)
        (xy -8.024 -2.962)
        (xy -7.882 -3.044)
        (xy -7.759 -3.114)
        (xy -7.656 -3.173)
        (xy -7.568 -3.221)
        (xy -7.496 -3.261)
        (xy -7.437 -3.293)
        (xy -7.389 -3.317)
        (xy -7.351 -3.336)
        (xy -7.321 -3.349)
        (xy -7.296 -3.357)
        (xy -7.276 -3.363)
        (xy -7.259 -3.366)
        (xy -7.242 -3.367)
        (xy -7.237 -3.368)
        (xy -7.153 -3.366)
      )

      (stroke (width 0.00186) (type solid)) (fill solid) (layer "F.Mask"))
    (fp_poly
      (pts
        (xy -7.128 -1.48)
        (xy -7.114 -1.475)
        (xy -7.042 -1.428)
        (xy -6.989 -1.361)
        (xy -6.96 -1.281)
        (xy -6.957 -1.196)
        (xy -6.961 -1.175)
        (xy -6.992 -1.094)
        (xy -7.046 -1.034)
        (xy -7.101 -1.001)
        (xy -7.166 -0.969)
        (xy -7.166 -0.599)
        (xy -6.891 -0.599)
        (xy -6.778 -0.711)
        (xy -6.665 -0.824)
        (xy -6.673 -0.905)
        (xy -6.673 -0.906)
        (xy -6.566 -0.906)
        (xy -6.549 -0.87)
        (xy -6.512 -0.853)
        (xy -6.467 -0.856)
        (xy -6.435 -0.876)
        (xy -6.412 -0.913)
        (xy -6.42 -0.95)
        (xy -6.441 -0.977)
        (xy -6.471 -1.002)
        (xy -6.496 -1.005)
        (xy -6.53 -0.986)
        (xy -6.532 -0.984)
        (xy -6.56 -0.949)
        (xy -6.566 -0.906)
        (xy -6.673 -0.906)
        (xy -6.676 -0.957)
        (xy -6.669 -0.992)
        (xy -6.648 -1.025)
        (xy -6.639 -1.036)
        (xy -6.582 -1.084)
        (xy -6.519 -1.106)
        (xy -6.456 -1.105)
        (xy -6.397 -1.084)
        (xy -6.349 -1.044)
        (xy -6.316 -0.99)
        (xy -6.304 -0.925)
        (xy -6.315 -0.859)
        (xy -6.351 -0.797)
        (xy -6.408 -0.757)
        (xy -6.484 -0.741)
        (xy -6.497 -0.741)
        (xy -6.529 -0.74)
        (xy -6.557 -0.734)
        (xy -6.585 -0.719)
        (xy -6.619 -0.693)
        (xy -6.667 -0.651)
        (xy -6.705 -0.615)
        (xy -6.84 -0.489)
        (xy -7.166 -0.489)
        (xy -7.166 -0.237)
        (xy -6.568 -0.237)
        (xy -6.545 -0.282)
        (xy -6.502 -0.333)
        (xy -6.443 -0.364)
        (xy -6.377 -0.373)
        (xy -6.311 -0.36)
        (xy -6.255 -0.322)
        (xy -6.249 -0.317)
        (xy -6.209 -0.253)
        (xy -6.195 -0.188)
        (xy -6.205 -0.126)
        (xy -6.234 -0.072)
        (xy -6.28 -0.03)
        (xy -6.337 -0.006)
        (xy -6.402 -0.002)
        (xy -6.472 -0.025)
        (xy -6.486 -0.033)
        (xy -6.523 -0.061)
        (xy -6.545 -0.091)
        (xy -6.547 -0.096)
        (xy -6.552 -0.106)
        (xy -6.561 -0.114)
        (xy -6.58 -0.12)
        (xy -6.613 -0.123)
        (xy -6.664 -0.125)
        (xy -6.737 -0.126)
        (xy -6.836 -0.126)
        (xy -6.861 -0.126)
        (xy -7.166 -0.126)
        (xy -7.166 0.11)
        (xy -6.842 0.11)
        (xy -6.581 0.373)
        (xy -6.507 0.366)
        (xy -6.428 0.372)
        (xy -6.367 0.402)
        (xy -6.325 0.457)
        (xy -6.314 0.486)
        (xy -6.304 0.561)
        (xy -6.322 0.626)
        (xy -6.361 0.678)
        (xy -6.422 0.72)
        (xy -6.487 0.736)
        (xy -6.55 0.727)
        (xy -6.605 0.697)
        (xy -6.648 0.648)
        (xy -6.671 0.583)
        (xy -6.672 0.536)
        (xy -6.564 0.536)
        (xy -6.559 0.575)
        (xy -6.544 0.597)
        (xy -6.508 0.625)
        (xy -6.474 0.623)
        (xy -6.441 0.598)
        (xy -6.414 0.56)
        (xy -6.417 0.525)
        (xy -6.44 0.497)
        (xy -6.48 0.476)
        (xy -6.518 0.48)
        (xy -6.549 0.502)
        (xy -6.564 0.536)
        (xy -6.672 0.536)
        (xy -6.673 0.52)
        (xy -6.664 0.445)
        (xy -6.891 0.22)
        (xy -7.166 0.22)
        (xy -7.166 0.593)
        (xy -7.101 0.622)
        (xy -7.033 0.668)
        (xy -6.986 0.732)
        (xy -6.96 0.805)
        (xy -6.956 0.883)
        (xy -6.973 0.959)
        (xy -7.013 1.026)
        (xy -7.074 1.079)
        (xy -7.088 1.087)
        (xy -7.171 1.112)
        (xy -7.258 1.112)
        (xy -7.34 1.087)
        (xy -7.341 1.086)
        (xy -7.406 1.036)
        (xy -7.448 0.97)
        (xy -7.469 0.895)
        (xy -7.468 0.858)
        (xy -7.361 0.858)
        (xy -7.355 0.905)
        (xy -7.331 0.942)
        (xy -7.31 0.962)
        (xy -7.252 0.999)
        (xy -7.195 1.005)
        (xy -7.137 0.979)
        (xy -7.116 0.962)
        (xy -7.08 0.923)
        (xy -7.066 0.883)
        (xy -7.065 0.858)
        (xy -7.079 0.801)
        (xy -7.116 0.751)
        (xy -7.167 0.718)
        (xy -7.213 0.708)
        (xy -7.27 0.722)
        (xy -7.319 0.76)
        (xy -7.352 0.812)
        (xy -7.361 0.858)
        (xy -7.468 0.858)
        (xy -7.468 0.817)
        (xy -7.445 0.742)
        (xy -7.401 0.677)
        (xy -7.336 0.628)
        (xy -7.325 0.622)
        (xy -7.26 0.593)
        (xy -7.26 0.22)
        (xy -7.535 0.22)
        (xy -7.762 0.445)
        (xy -7.753 0.52)
        (xy -7.757 0.595)
        (xy -7.785 0.658)
        (xy -7.83 0.703)
        (xy -7.887 0.73)
        (xy -7.951 0.735)
        (xy -8.015 0.715)
        (xy -8.065 0.678)
        (xy -8.109 0.617)
        (xy -8.123 0.551)
        (xy -8.12 0.532)
        (xy -8.012 0.532)
        (xy -8.009 0.566)
        (xy -7.985 0.598)
        (xy -7.946 0.625)
        (xy -7.912 0.623)
        (xy -7.883 0.599)
        (xy -7.863 0.558)
        (xy -7.868 0.517)
        (xy -7.896 0.486)
        (xy -7.915 0.478)
        (xy -7.961 0.48)
        (xy -7.985 0.496)
        (xy -8.012 0.532)
        (xy -8.12 0.532)
        (xy -8.112 0.486)
        (xy -8.079 0.422)
        (xy -8.025 0.381)
        (xy -7.953 0.365)
        (xy -7.919 0.366)
        (xy -7.845 0.373)
        (xy -7.584 0.11)
        (xy -7.26 0.11)
        (xy -7.26 -0.126)
        (xy -7.566 -0.126)
        (xy -7.672 -0.126)
        (xy -7.75 -0.126)
        (xy -7.805 -0.124)
        (xy -7.841 -0.121)
        (xy -7.863 -0.116)
        (xy -7.875 -0.108)
        (xy -7.881 -0.098)
        (xy -7.883 -0.094)
        (xy -7.908 -0.058)
        (xy -7.954 -0.026)
        (xy -8.009 -0.005)
        (xy -8.045 -0.001)
        (xy -8.117 -0.014)
        (xy -8.174 -0.049)
        (xy -8.213 -0.102)
        (xy -8.23 -0.164)
        (xy -8.228 -0.186)
        (xy -8.124 -0.186)
        (xy -8.12 -0.163)
        (xy -8.104 -0.143)
        (xy -8.063 -0.115)
        (xy -8.021 -0.117)
        (xy -7.994 -0.135)
        (xy -7.971 -0.176)
        (xy -7.976 -0.202)
        (xy -6.455 -0.202)
        (xy -6.449 -0.158)
        (xy -6.432 -0.135)
        (xy -6.392 -0.113)
        (xy -6.35 -0.121)
        (xy -6.322 -0.143)
        (xy -6.303 -0.169)
        (xy -6.304 -0.193)
        (xy -6.316 -0.218)
        (xy -6.35 -0.254)
        (xy -6.39 -0.265)
        (xy -6.429 -0.247)
        (xy -6.432 -0.244)
        (xy -6.455 -0.202)
        (xy -7.976 -0.202)
        (xy -7.979 -0.218)
        (xy -7.999 -0.244)
        (xy -8.04 -0.265)
        (xy -8.078 -0.255)
        (xy -8.11 -0.218)
        (xy -8.124 -0.186)
        (xy -8.228 -0.186)
        (xy -8.224 -0.232)
        (xy -8.192 -0.297)
        (xy -8.177 -0.317)
        (xy -8.121 -0.358)
        (xy -8.055 -0.374)
        (xy -7.988 -0.365)
        (xy -7.927 -0.333)
        (xy -7.885 -0.284)
        (xy -7.857 -0.237)
        (xy -7.26 -0.237)
        (xy -7.26 -0.489)
        (xy -7.586 -0.489)
        (xy -7.721 -0.615)
        (xy -7.779 -0.669)
        (xy -7.821 -0.704)
        (xy -7.852 -0.726)
        (xy -7.879 -0.737)
        (xy -7.908 -0.74)
        (xy -7.934 -0.741)
        (xy -8.011 -0.752)
        (xy -8.068 -0.787)
        (xy -8.105 -0.846)
        (xy -8.112 -0.866)
        (xy -8.119 -0.923)
        (xy -8.016 -0.923)
        (xy -8.003 -0.887)
        (xy -7.969 -0.862)
        (xy -7.928 -0.852)
        (xy -7.888 -0.861)
        (xy -7.878 -0.87)
        (xy -7.86 -0.907)
        (xy -7.866 -0.949)
        (xy -7.894 -0.984)
        (xy -7.924 -1.002)
        (xy -7.941 -1.008)
        (xy -7.964 -0.997)
        (xy -7.991 -0.969)
        (xy -8.011 -0.939)
        (xy -8.016 -0.923)
        (xy -8.119 -0.923)
        (xy -8.121 -0.94)
        (xy -8.105 -1.004)
        (xy -8.069 -1.055)
        (xy -8.018 -1.091)
        (xy -7.958 -1.108)
        (xy -7.894 -1.104)
        (xy -7.831 -1.076)
        (xy -7.787 -1.036)
        (xy -7.762 -1.001)
        (xy -7.751 -0.968)
        (xy -7.751 -0.923)
        (xy -7.753 -0.905)
        (xy -7.762 -0.824)
        (xy -7.648 -0.711)
        (xy -7.535 -0.599)
        (xy -7.26 -0.599)
        (xy -7.26 -0.971)
        (xy -7.323 -0.998)
        (xy -7.396 -1.046)
        (xy -7.446 -1.114)
        (xy -7.465 -1.166)
        (xy -7.472 -1.24)
        (xy -7.365 -1.24)
        (xy -7.359 -1.204)
        (xy -7.347 -1.177)
        (xy -7.307 -1.123)
        (xy -7.254 -1.093)
        (xy -7.194 -1.09)
        (xy -7.134 -1.116)
        (xy -7.127 -1.121)
        (xy -7.081 -1.171)
        (xy -7.065 -1.225)
        (xy -7.078 -1.283)
        (xy -7.116 -1.342)
        (xy -7.166 -1.375)
        (xy -7.222 -1.384)
        (xy -7.278 -1.368)
        (xy -7.326 -1.326)
        (xy -7.354 -1.278)
        (xy -7.365 -1.24)
        (xy -7.472 -1.24)
        (xy -7.474 -1.25)
        (xy -7.455 -1.328)
        (xy -7.416 -1.396)
        (xy -7.358 -1.449)
        (xy -7.288 -1.484)
        (xy -7.21 -1.495)
        (xy -7.128 -1.48)
      )

      (stroke (width 0.00186) (type solid)) (fill solid) (layer "F.Mask"))
  )

  (footprint "antmicro-footprints:C_0603_1608Metric" (layer "F.Cu")
    (at 171.65 119 180)
    (descr "Capacitor SMD 0603")
    (tags "capacitor 0603")
    (property "Author" "Antmicro")
    (property "Dielectric" "template_dielectric")
    (property "License" "Apache-2.0")
    (property "MPN" "GRM188R61A106KE69D")
    (property "Manufacturer" "Murata")
    (property "Public" "False")
    (property "Sheetfile" "channel2.kicad_sch")
    (property "Sheetname" "Channel 2")
    (property "Val" "10u")
    (property "Voltage" "")
    (property "ki_description" "SMD Multilayer Ceramic Capacitor, 10 µF, 10 V, 0603 [1608 Metric], ± 10%, X5R, GRM Series")
    (property "ki_keywords" "0603, SMT, CAPACITOR, PASSIVE, CERAMIC, MLCC")
    (attr smd)
    (fp_text reference "C40" (at -0.95 -1.5) (layer "F.SilkS")
        (effects (font (size 0.65 0.65) (thickness 0.13)) (justify right bottom))
    )
    (fp_text value "C_10u_0603" (at 0 1.6) (layer "F.Fab")
        (effects (font (size 0.65 0.65) (thickness 0.13)) (justify right bottom))
    )
    (fp_text user "${REFERENCE}" (at -1.682 3.895) (layer "F.Fab") hide
        (effects (font (size 0.7 0.7) (thickness 0.15)) (justify right bottom))
    )
    (fp_text user "Author: Antmicro" (at -1.682 4.894) (layer "F.Fab") hide
        (effects (font (size 0.7 0.7) (thickness 0.15)) (justify right bottom))
    )
    (fp_text user "License: Apache-2.0" (at -1.682 5.895) (layer "F.Fab") hide
        (effects (font (size 0.7 0.7) (thickness 0.15)) (justify right bottom))
    )
    (fp_line (start -0.15 -0.4) (end 0.15 -0.4)
      (stroke (width 0.15) (type solid)) (layer "F.SilkS"))
    (fp_line (start -0.15 0.4) (end 0.15 0.4)
      (stroke (width 0.15) (type solid)) (layer "F.SilkS"))
    (fp_rect (start -1.25 -0.65) (end 1.25 0.65)
      (stroke (width 0.05) (type solid)) (fill none) (layer "F.CrtYd"))
    (fp_rect (start -0.8 -0.4) (end 0.8 0.4)
      (stroke (width 0.15) (type solid)) (fill none) (layer "F.Fab"))
    (pad "1" smd roundrect (at -0.7 0 180) (size 0.8 1) (layers "F.Cu" "F.Paste" "F.Mask") (roundrect_rratio 0.2)
      (net 2 "GND") (pintype "passive"))
    (pad "2" smd roundrect (at 0.7 0 180) (size 0.8 1) (layers "F.Cu" "F.Paste" "F.Mask") (roundrect_rratio 0.2)
      (net 9 "+3V3") (pintype "passive"))
  )

  (footprint "antmicro-footprints:HDMI-A_Receptacle_Molex_471511001" (layer "F.Cu")
    (at 136.999 94.303 180)
    (property "Author" "Antmicro")
    (property "License" "Apache-2.0")
    (property "MPN" "471511001")
    (property "Manufacturer" "Molex")
    (property "Sheetfile" "channel1.kicad_sch")
    (property "Sheetname" "Channel 1")
    (property "ki_description" "HDMI Receptacle Connector 19 Position Surface Mount, Right Angle; Through Hole")
    (property "ki_keywords" "HDMI, CONNECTOR, SMT, HORIZONTAL")
    (attr smd)
    (fp_text reference "J2" (at 10.289 1.563 unlocked) (layer "F.SilkS")
        (effects (font (size 0.7 0.7) (thickness 0.15)) (justify left bottom))
    )
    (fp_text value "HDMI-A_Molex_471511001" (at 0 7.55 180 unlocked) (layer "F.Fab")
        (effects (font (size 0.7 0.7) (thickness 0.15)) (justify left bottom))
    )
    (fp_text user "${REFERENCE}" (at -10.001 12.48 180 unlocked) (layer "F.Fab") hide
        (effects (font (size 0.7 0.7) (thickness 0.15)) (justify left bottom))
    )
    (fp_text user "Author: Antmicro" (at -10.001 13.678 180) (layer "F.Fab") hide
        (effects (font (size 0.7 0.7) (thickness 0.15)) (justify left bottom))
    )
    (fp_text user "License: Apache-2.0" (at -10.001 14.878 180) (layer "F.Fab") hide
        (effects (font (size 0.7 0.7) (thickness 0.15)) (justify left bottom))
    )
    (fp_circle (center 4.948 -5.705) (end 4.998 -5.705)
      (stroke (width 0.15) (type solid)) (fill solid) (layer "F.SilkS"))
    (fp_rect (start -8.0296 -6.5548) (end 8.0296 6.5532)
      (stroke (width 0.05) (type solid)) (fill none) (layer "F.CrtYd"))
    (pad "1" smd rect (at 4.499 -5.056 180) (size 0.3 2.6) (layers "F.Cu" "F.Paste" "F.Mask")
      (net 74 "/Channel 1/HDMI1_D2_P") (pinfunction "D2+") (pintype "bidirectional"))
    (pad "2" smd rect (at 3.999 -5.056 180) (size 0.3 2.6) (layers "F.Cu" "F.Paste" "F.Mask")
      (net 2 "GND") (pinfunction "D2S") (pintype "passive"))
    (pad "3" smd rect (at 3.499 -5.056 180) (size 0.3 2.6) (layers "F.Cu" "F.Paste" "F.Mask")
      (net 75 "/Channel 1/HDMI1_D2_N") (pinfunction "D2-") (pintype "bidirectional"))
    (pad "4" smd rect (at 2.999 -5.056 180) (size 0.3 2.6) (layers "F.Cu" "F.Paste" "F.Mask")
      (net 76 "/Channel 1/HDMI1_D1_P") (pinfunction "D1+") (pintype "bidirectional"))
    (pad "5" smd rect (at 2.499 -5.056 180) (size 0.3 2.6) (layers "F.Cu" "F.Paste" "F.Mask")
      (net 2 "GND") (pinfunction "D1S") (pintype "passive"))
    (pad "6" smd rect (at 1.999 -5.056 180) (size 0.3 2.6) (layers "F.Cu" "F.Paste" "F.Mask")
      (net 77 "/Channel 1/HDMI1_D1_N") (pinfunction "D1-") (pintype "bidirectional"))
    (pad "7" smd rect (at 1.499 -5.056 180) (size 0.3 2.6) (layers "F.Cu" "F.Paste" "F.Mask")
      (net 78 "/Channel 1/HDMI1_D0_P") (pinfunction "D0+") (pintype "bidirectional"))
    (pad "8" smd rect (at 0.998 -5.056 180) (size 0.3 2.6) (layers "F.Cu" "F.Paste" "F.Mask")
      (net 2 "GND") (pinfunction "D0S") (pintype "passive"))
    (pad "9" smd rect (at 0.498 -5.056 180) (size 0.3 2.6) (layers "F.Cu" "F.Paste" "F.Mask")
      (net 79 "/Channel 1/HDMI1_D0_N") (pinfunction "D0-") (pintype "bidirectional"))
    (pad "10" smd rect (at 0 -5.056 180) (size 0.3 2.6) (layers "F.Cu" "F.Paste" "F.Mask")
      (net 80 "/Channel 1/HDMI1_CLK_P") (pinfunction "CK+") (pintype "bidirectional"))
    (pad "11" smd rect (at -0.5 -5.056 180) (size 0.3 2.6) (layers "F.Cu" "F.Paste" "F.Mask")
      (net 2 "GND") (pinfunction "CKS") (pintype "passive"))
    (pad "12" smd rect (at -1.002 -5.056 180) (size 0.3 2.6) (layers "F.Cu" "F.Paste" "F.Mask")
      (net 81 "/Channel 1/HDMI1_CLK_N") (pinfunction "CK-") (pintype "bidirectional"))
    (pad "13" smd rect (at -1.5 -5.056 180) (size 0.3 2.6) (layers "F.Cu" "F.Paste" "F.Mask")
      (net 82 "/Channel 1/HDMI1_CEC") (pinfunction "CEC") (pintype "bidirectional"))
    (pad "14" smd rect (at -2.001 -5.056 180) (size 0.3 2.6) (layers "F.Cu" "F.Paste" "F.Mask")
      (net 83 "/Channel 1/DUMMY1") (pinfunction "UTILITY/HEAC+") (pintype "bidirectional"))
    (pad "15" smd rect (at -2.501 -5.056 180) (size 0.3 2.6) (layers "F.Cu" "F.Paste" "F.Mask")
      (net 84 "/Channel 1/HDMI1_DDC_SCL") (pinfunction "SCL") (pintype "bidirectional"))
    (pad "16" smd rect (at -3 -5.056 180) (size 0.3 2.6) (layers "F.Cu" "F.Paste" "F.Mask")
      (net 85 "/Channel 1/HDMI1_DDC_SDA") (pinfunction "SDA") (pintype "bidirectional"))
    (pad "17" smd rect (at -3.501 -5.056 180) (size 0.3 2.6) (layers "F.Cu" "F.Paste" "F.Mask")
      (net 2 "GND") (pinfunction "GND") (pintype "power_in"))
    (pad "18" smd rect (at -4 -5.056 180) (size 0.3 2.6) (layers "F.Cu" "F.Paste" "F.Mask")
      (net 86 "/Channel 1/HDMI1_POWER") (pinfunction "+5V") (pintype "power_in"))
    (pad "19" smd rect (at -4.502 -5.056 180) (size 0.3 2.6) (layers "F.Cu" "F.Paste" "F.Mask")
      (net 87 "/Channel 1/HDMI1_HPD") (pinfunction "HPD/HEAC-") (pintype "bidirectional"))
    (pad "SH" thru_hole oval (at -7.25 -4.297 180) (size 1.5 3.3) (drill oval 0.9 2.7) (layers "*.Cu" "*.Mask")
      (net 28 "Net-(FB1-Pad2)") (pinfunction "SH") (pintype "passive"))
    (pad "SH" thru_hole oval (at -7.25 1.664 180) (size 1.5 2.3) (drill oval 0.9 1.7) (layers "*.Cu" "*.Mask")
      (net 28 "Net-(FB1-Pad2)") (pinfunction "SH") (pintype "passive"))
    (pad "SH" thru_hole oval (at 7.249 -4.297 180) (size 1.5 3.3) (drill oval 0.9 2.7) (layers "*.Cu" "*.Mask")
      (net 28 "Net-(FB1-Pad2)") (pinfunction "SH") (pintype "passive"))
    (pad "SH" thru_hole oval (at 7.249 1.664 180) (size 1.5 2.3) (drill oval 0.9 1.7) (layers "*.Cu" "*.Mask")
      (net 28 "Net-(FB1-Pad2)") (pinfunction "SH") (pintype "passive"))
  )

  (footprint "antmicro-footprints:FB_0603_1608Metric" (layer "F.Cu")
    (at 123.8 107.8 -90)
    (property "Author" "Antmicro")
    (property "Current" "")
    (property "License" "Apache-2.0")
    (property "MPN" "BLM18AG601SN1D")
    (property "Manufacturer" "Murata")
    (property "Public" "False")
    (property "Sheetfile" "channel1.kicad_sch")
    (property "Sheetname" "Channel 1")
    (property "Val" "600Z/0.5A")
    (property "ki_description" "Ferrite Bead, 0603 [1608 Metric], 600 ohm, 500 mA, BLM18A, 0.38 ohm, ± 25%, General use")
    (property "ki_keywords" "0603, SMT, FERRITE BEAD, PASSIVE")
    (attr smd)
    (fp_text reference "FB6" (at -0.74 0.74 90) (layer "F.SilkS")
        (effects (font (size 0.65 0.65) (thickness 0.13)) (justify right bottom))
    )
    (fp_text value "FB_600Z_0.5A_Murata-BLM18AG_0603" (at 0 1.5 90) (layer "F.Fab")
        (effects (font (size 0.65 0.65) (thickness 0.13)) (justify right bottom))
    )
    (fp_text user "${REFERENCE}" (at -1.653 4.6 90) (layer "F.Fab") hide
        (effects (font (size 0.7 0.7) (thickness 0.15)) (justify right bottom))
    )
    (fp_text user "Author: Antmicro" (at -1.653 3.162 90) (layer "F.Fab") hide
        (effects (font (size 0.7 0.7) (thickness 0.15)) (justify right bottom))
    )
    (fp_text user "License: Apache-2.0" (at -1.653 5.9 90) (layer "F.Fab") hide
        (effects (font (size 0.7 0.7) (thickness 0.15)) (justify right bottom))
    )
    (fp_line (start -0.15 -0.4) (end 0.15 -0.4)
      (stroke (width 0.15) (type solid)) (layer "F.SilkS"))
    (fp_line (start -0.15 0.4) (end 0.15 0.4)
      (stroke (width 0.15) (type solid)) (layer "F.SilkS"))
    (fp_rect (start -1.25 -0.65) (end 1.25 0.65)
      (stroke (width 0.05) (type solid)) (fill none) (layer "F.CrtYd"))
    (fp_line (start -0.803 0.406) (end -0.803 -0.408)
      (stroke (width 0.15) (type solid)) (layer "F.Fab"))
    (fp_line (start 0.8 -0.408) (end -0.803 -0.408)
      (stroke (width 0.15) (type solid)) (layer "F.Fab"))
    (fp_line (start 0.8 -0.408) (end 0.8 0.406)
      (stroke (width 0.15) (type solid)) (layer "F.Fab"))
    (fp_line (start 0.8 0.406) (end -0.803 0.406)
      (stroke (width 0.15) (type solid)) (layer "F.Fab"))
    (pad "1" smd roundrect (at -0.7 0 270) (size 0.8 1) (layers "F.Cu" "F.Paste" "F.Mask") (roundrect_rratio 0.2)
      (net 9 "+3V3") (pintype "passive"))
    (pad "2" smd roundrect (at 0.7 0 270) (size 0.8 1) (layers "F.Cu" "F.Paste" "F.Mask") (roundrect_rratio 0.2)
      (net 10 "Net-(Y1-EN)") (pintype "passive"))
  )

  (footprint "antmicro-footprints:R_0402_1005Metric" (layer "F.Cu")
    (at 155.08 111.45)
    (descr "Resistor SMD 0402")
    (tags "resistor SMD 0402")
    (property "Author" "Antmicro")
    (property "License" "Apache-2.0")
    (property "MPN" "CR0402-FX-22R0GLF")
    (property "Manufacturer" "Bourns")
    (property "Public" "False")
    (property "Sheetfile" "channel2.kicad_sch")
    (property "Sheetname" "Channel 2")
    (property "Tolerance" "1%")
    (property "Val" "22R")
    (property "ki_description" "SMD Chip Resistor, 22 ohm, ± 1%, 62.5 mW, 0402 [1005 Metric], Thick Film, General Purpose")
    (property "ki_keywords" "0402, SMT, RESISTOR, PASSIVE")
    (attr smd)
    (fp_text reference "R26" (at -1.57 7.52) (layer "F.SilkS")
        (effects (font (size 0.65 0.65) (thickness 0.13)) (justify left bottom))
    )
    (fp_text value "R_22R_0402" (at 0 1.4) (layer "F.Fab")
        (effects (font (size 0.65 0.65) (thickness 0.13)) (justify left bottom))
    )
    (fp_text user "License: Apache-2.0" (at -0.95 5.169) (layer "F.Fab") hide
        (effects (font (size 0.7 0.7) (thickness 0.15)) (justify left bottom))
    )
    (fp_text user "${REFERENCE}" (at -0.95 3.168) (layer "F.Fab") hide
        (effects (font (size 0.7 0.7) (thickness 0.15)) (justify left bottom))
    )
    (fp_text user "Author: Antmicro" (at -0.95 4.169) (layer "F.Fab") hide
        (effects (font (size 0.7 0.7) (thickness 0.15)) (justify left bottom))
    )
    (fp_rect (start -0.925 -0.47) (end 0.925 0.47)
      (stroke (width 0.05) (type default)) (fill none) (layer "F.CrtYd"))
    (fp_rect (start -0.5 -0.25) (end 0.5 0.25)
      (stroke (width 0.15) (type solid)) (fill none) (layer "F.Fab"))
    (pad "1" smd roundrect (at -0.48 0) (size 0.59 0.64) (layers "F.Cu" "F.Paste" "F.Mask") (roundrect_rratio 0.25)
      (net 31 "Net-(Y2-OUT)") (pintype "passive"))
    (pad "2" smd roundrect (at 0.48 0) (size 0.59 0.64) (layers "F.Cu" "F.Paste" "F.Mask") (roundrect_rratio 0.25)
      (net 27 "/Channel 2/CH2_REFCLK") (pintype "passive"))
  )

  (footprint "antmicro-footprints:Conn_FFC_WE_68715014x22" (layer "F.Cu")
    (at 149.006 132.275)
    (property "Author" "Antmicro")
    (property "License" "Apache-2.0")
    (property "MPN" "68715014022")
    (property "Manufacturer" "Würth Elektronik")
    (property "Sheetfile" "csi.kicad_sch")
    (property "Sheetname" "CSI")
    (property "ki_description" "FFC connector")
    (property "ki_keywords" "CONNECTOR")
    (attr smd)
    (fp_text reference "J6" (at 0 -3.4) (layer "F.SilkS")
        (effects (font (size 0.7 0.7) (thickness 0.15)) (justify left bottom))
    )
    (fp_text value "Conn_FFC_WE_68715014022" (at 0 4.5) (layer "F.Fab")
        (effects (font (size 0.7 0.7) (thickness 0.15)) (justify left bottom))
    )
    (fp_text user "License: Apache-2.0" (at -16.2 7.9) (layer "F.Fab") hide
        (effects (font (size 0.7 0.7) (thickness 0.15)) (justify left bottom))
    )
    (fp_text user "${REFERENCE}" (at -16.2 5.9) (layer "F.Fab") hide
        (effects (font (size 0.7 0.7) (thickness 0.15)) (justify left bottom))
    )
    (fp_text user "Author: Antmicro" (at -16.2 6.9) (layer "F.Fab") hide
        (effects (font (size 0.7 0.7) (thickness 0.15)) (justify left bottom))
    )
    (fp_line (start -15.85 -2.15) (end -12.5 -2.15)
      (stroke (width 0.15) (type solid)) (layer "F.SilkS"))
    (fp_line (start -15.85 2.7) (end -15.85 -2.15)
      (stroke (width 0.15) (type solid)) (layer "F.SilkS"))
    (fp_line (start -12.5 -2.976) (end 12.499 -2.976)
      (stroke (width 0.15) (type solid)) (layer "F.SilkS"))
    (fp_line (start -12.5 -2.15) (end -12.5 -2.976)
      (stroke (width 0.15) (type solid)) (layer "F.SilkS"))
    (fp_line (start 12.499 -2.15) (end 12.499 -2.976)
      (stroke (width 0.15) (type solid)) (layer "F.SilkS"))
    (fp_line (start 15.85 -2.15) (end 12.499 -2.15)
      (stroke (width 0.15) (type solid)) (layer "F.SilkS"))
    (fp_line (start 15.85 2.7) (end -15.85 2.7)
      (stroke (width 0.15) (type solid)) (layer "F.SilkS"))
    (fp_line (start 15.85 2.7) (end 15.85 -2.15)
      (stroke (width 0.15) (type solid)) (layer "F.SilkS"))
    (fp_circle (center -12.9 -2.9) (end -12.85 -2.85)
      (stroke (width 0.15) (type solid)) (fill solid) (layer "F.SilkS"))
    (fp_rect (start -16.2 -3.25) (end 16.2 3.55)
      (stroke (width 0.05) (type solid)) (fill none) (layer "F.CrtYd"))
    (pad "1" smd roundrect (at -12.25 -2.15) (size 0.3 1.2) (layers "F.Cu" "F.Paste" "F.Mask") (roundrect_rratio 0.25)
      (net 14 "+5V") (pintype "passive"))
    (pad "2" smd roundrect (at -11.75 -2.15) (size 0.3 1.2) (layers "F.Cu" "F.Paste" "F.Mask") (roundrect_rratio 0.25)
      (net 14 "+5V") (pintype "passive"))
    (pad "3" smd roundrect (at -11.25 -2.15) (size 0.3 1.2) (layers "F.Cu" "F.Paste" "F.Mask") (roundrect_rratio 0.25)
      (net 9 "+3V3") (pintype "passive"))
    (pad "4" smd roundrect (at -10.75 -2.15) (size 0.3 1.2) (layers "F.Cu" "F.Paste" "F.Mask") (roundrect_rratio 0.25)
      (net 9 "+3V3") (pintype "passive"))
    (pad "5" smd roundrect (at -10.25 -2.15) (size 0.3 1.2) (layers "F.Cu" "F.Paste" "F.Mask") (roundrect_rratio 0.25)
      (net 73 "/CSI/SPI_CS") (pintype "passive+no_connect"))
    (pad "6" smd roundrect (at -9.75 -2.15) (size 0.3 1.2) (layers "F.Cu" "F.Paste" "F.Mask") (roundrect_rratio 0.25)
      (net 72 "/CSI/SPI_MOSI") (pintype "passive+no_connect"))
    (pad "7" smd roundrect (at -9.25 -2.15) (size 0.3 1.2) (layers "F.Cu" "F.Paste" "F.Mask") (roundrect_rratio 0.25)
      (net 71 "/CSI/SPI_MISO") (pintype "passive+no_connect"))
    (pad "8" smd roundrect (at -8.75 -2.15) (size 0.3 1.2) (layers "F.Cu" "F.Paste" "F.Mask") (roundrect_rratio 0.25)
      (net 70 "/CSI/SPI_SCK") (pintype "passive+no_connect"))
    (pad "9" smd roundrect (at -8.25 -2.15) (size 0.3 1.2) (layers "F.Cu" "F.Paste" "F.Mask") (roundrect_rratio 0.25)
      (net 69 "I2C1_SCL") (pintype "passive"))
    (pad "10" smd roundrect (at -7.75 -2.15) (size 0.3 1.2) (layers "F.Cu" "F.Paste" "F.Mask") (roundrect_rratio 0.25)
      (net 68 "I2C1_SDA") (pintype "passive"))
    (pad "11" smd roundrect (at -7.25 -2.15) (size 0.3 1.2) (layers "F.Cu" "F.Paste" "F.Mask") (roundrect_rratio 0.25)
      (net 67 "I2C3_SCL") (pintype "passive"))
    (pad "12" smd roundrect (at -6.75 -2.15) (size 0.3 1.2) (layers "F.Cu" "F.Paste" "F.Mask") (roundrect_rratio 0.25)
      (net 66 "I2C3_SDA") (pintype "passive"))
    (pad "13" smd roundrect (at -6.25 -2.15) (size 0.3 1.2) (layers "F.Cu" "F.Paste" "F.Mask") (roundrect_rratio 0.25)
      (net 65 "/CSI/UART4_RX") (pintype "passive+no_connect"))
    (pad "14" smd roundrect (at -5.75 -2.15) (size 0.3 1.2) (layers "F.Cu" "F.Paste" "F.Mask") (roundrect_rratio 0.25)
      (net 64 "/CSI/UART4_TX") (pintype "passive+no_connect"))
    (pad "15" smd roundrect (at -5.25 -2.15) (size 0.3 1.2) (layers "F.Cu" "F.Paste" "F.Mask") (roundrect_rratio 0.25)
      (net 63 "/CSI/UART3_RX") (pintype "passive+no_connect"))
    (pad "16" smd roundrect (at -4.75 -2.15) (size 0.3 1.2) (layers "F.Cu" "F.Paste" "F.Mask") (roundrect_rratio 0.25)
      (net 62 "/CSI/UART3_TX") (pintype "passive+no_connect"))
    (pad "17" smd roundrect (at -4.25 -2.15) (size 0.3 1.2) (layers "F.Cu" "F.Paste" "F.Mask") (roundrect_rratio 0.25)
      (net 61 "/CSI/GPIO4") (pintype "passive+no_connect"))
    (pad "18" smd roundrect (at -3.75 -2.15) (size 0.3 1.2) (layers "F.Cu" "F.Paste" "F.Mask") (roundrect_rratio 0.25)
      (net 60 "/CSI/GPIO3") (pintype "passive+no_connect"))
    (pad "19" smd roundrect (at -3.25 -2.15) (size 0.3 1.2) (layers "F.Cu" "F.Paste" "F.Mask") (roundrect_rratio 0.25)
      (net 59 "/CSI/GPIO2") (pintype "passive+no_connect"))
    (pad "20" smd roundrect (at -2.75 -2.15) (size 0.3 1.2) (layers "F.Cu" "F.Paste" "F.Mask") (roundrect_rratio 0.25)
      (net 58 "/CSI/GPIO1") (pintype "passive+no_connect"))
    (pad "21" smd roundrect (at -2.25 -2.15) (size 0.3 1.2) (layers "F.Cu" "F.Paste" "F.Mask") (roundrect_rratio 0.25)
      (net 144 "unconnected-(J6-Pad21)") (pintype "passive+no_connect"))
    (pad "22" smd roundrect (at -1.75 -2.15) (size 0.3 1.2) (layers "F.Cu" "F.Paste" "F.Mask") (roundrect_rratio 0.25)
      (net 57 "CSI1_CLK_P") (pintype "passive"))
    (pad "23" smd roundrect (at -1.25 -2.15) (size 0.3 1.2) (layers "F.Cu" "F.Paste" "F.Mask") (roundrect_rratio 0.25)
      (net 56 "CSI1_CLK_N") (pintype "passive"))
    (pad "24" smd roundrect (at -0.75 -2.15) (size 0.3 1.2) (layers "F.Cu" "F.Paste" "F.Mask") (roundrect_rratio 0.25)
      (net 145 "unconnected-(J6-Pad24)") (pintype "passive+no_connect"))
    (pad "25" smd roundrect (at -0.25 -2.15) (size 0.3 1.2) (layers "F.Cu" "F.Paste" "F.Mask") (roundrect_rratio 0.25)
      (net 55 "CSI1_D1_P") (pintype "passive"))
    (pad "26" smd roundrect (at 0.248 -2.15) (size 0.3 1.2) (layers "F.Cu" "F.Paste" "F.Mask") (roundrect_rratio 0.25)
      (net 54 "CSI1_D1_N") (pintype "passive"))
    (pad "27" smd roundrect (at 0.748 -2.15) (size 0.3 1.2) (layers "F.Cu" "F.Paste" "F.Mask") (roundrect_rratio 0.25)
      (net 53 "CSI1_D2_P") (pintype "passive"))
    (pad "28" smd roundrect (at 1.249 -2.15) (size 0.3 1.2) (layers "F.Cu" "F.Paste" "F.Mask") (roundrect_rratio 0.25)
      (net 52 "CSI1_D2_N") (pintype "passive"))
    (pad "29" smd roundrect (at 1.749 -2.15) (size 0.3 1.2) (layers "F.Cu" "F.Paste" "F.Mask") (roundrect_rratio 0.25)
      (net 51 "CSI1_D3_P") (pintype "passive"))
    (pad "30" smd roundrect (at 2.249 -2.15) (size 0.3 1.2) (layers "F.Cu" "F.Paste" "F.Mask") (roundrect_rratio 0.25)
      (net 50 "CSI1_D3_N") (pintype "passive"))
    (pad "31" smd roundrect (at 2.749 -2.15) (size 0.3 1.2) (layers "F.Cu" "F.Paste" "F.Mask") (roundrect_rratio 0.25)
      (net 49 "CSI1_D4_P") (pintype "passive"))
    (pad "32" smd roundrect (at 3.249 -2.15) (size 0.3 1.2) (layers "F.Cu" "F.Paste" "F.Mask") (roundrect_rratio 0.25)
      (net 48 "CSI1_D4_N") (pintype "passive"))
    (pad "33" smd roundrect (at 3.749 -2.15) (size 0.3 1.2) (layers "F.Cu" "F.Paste" "F.Mask") (roundrect_rratio 0.25)
      (net 2 "GND") (pintype "passive"))
    (pad "34" smd roundrect (at 4.248 -2.15) (size 0.3 1.2) (layers "F.Cu" "F.Paste" "F.Mask") (roundrect_rratio 0.25)
      (net 47 "/CSI/CSI2_D1_P") (pintype "passive+no_connect"))
    (pad "35" smd roundrect (at 4.748 -2.15) (size 0.3 1.2) (layers "F.Cu" "F.Paste" "F.Mask") (roundrect_rratio 0.25)
      (net 46 "/CSI/CSI2_D1_N") (pintype "passive+no_connect"))
    (pad "36" smd roundrect (at 5.248 -2.15) (size 0.3 1.2) (layers "F.Cu" "F.Paste" "F.Mask") (roundrect_rratio 0.25)
      (net 2 "GND") (pintype "passive"))
    (pad "37" smd roundrect (at 5.749 -2.15) (size 0.3 1.2) (layers "F.Cu" "F.Paste" "F.Mask") (roundrect_rratio 0.25)
      (net 45 "/CSI/CSI2_CLK_P") (pintype "passive+no_connect"))
    (pad "38" smd roundrect (at 6.249 -2.15) (size 0.3 1.2) (layers "F.Cu" "F.Paste" "F.Mask") (roundrect_rratio 0.25)
      (net 44 "/CSI/CSI2_CLK_N") (pintype "passive+no_connect"))
    (pad "39" smd roundrect (at 6.749 -2.15) (size 0.3 1.2) (layers "F.Cu" "F.Paste" "F.Mask") (roundrect_rratio 0.25)
      (net 2 "GND") (pintype "passive"))
    (pad "40" smd roundrect (at 7.249 -2.15) (size 0.3 1.2) (layers "F.Cu" "F.Paste" "F.Mask") (roundrect_rratio 0.25)
      (net 43 "CSI3_CLK_P") (pintype "passive"))
    (pad "41" smd roundrect (at 7.749 -2.15) (size 0.3 1.2) (layers "F.Cu" "F.Paste" "F.Mask") (roundrect_rratio 0.25)
      (net 42 "CSI3_CLK_N") (pintype "passive"))
    (pad "42" smd roundrect (at 8.249 -2.15) (size 0.3 1.2) (layers "F.Cu" "F.Paste" "F.Mask") (roundrect_rratio 0.25)
      (net 2 "GND") (pintype "passive"))
    (pad "43" smd roundrect (at 8.749 -2.15) (size 0.3 1.2) (layers "F.Cu" "F.Paste" "F.Mask") (roundrect_rratio 0.25)
      (net 41 "CSI3_D1_P") (pintype "passive"))
    (pad "44" smd roundrect (at 9.249 -2.15) (size 0.3 1.2) (layers "F.Cu" "F.Paste" "F.Mask") (roundrect_rratio 0.25)
      (net 40 "CSI3_D1_N") (pintype "passive"))
    (pad "45" smd roundrect (at 9.749 -2.15) (size 0.3 1.2) (layers "F.Cu" "F.Paste" "F.Mask") (roundrect_rratio 0.25)
      (net 39 "CSI3_D2_P") (pintype "passive"))
    (pad "46" smd roundrect (at 10.249 -2.15) (size 0.3 1.2) (layers "F.Cu" "F.Paste" "F.Mask") (roundrect_rratio 0.25)
      (net 38 "CSI3_D2_N") (pintype "passive"))
    (pad "47" smd roundrect (at 10.749 -2.15) (size 0.3 1.2) (layers "F.Cu" "F.Paste" "F.Mask") (roundrect_rratio 0.25)
      (net 37 "CSI3_D3_P") (pintype "passive"))
    (pad "48" smd roundrect (at 11.249 -2.15) (size 0.3 1.2) (layers "F.Cu" "F.Paste" "F.Mask") (roundrect_rratio 0.25)
      (net 36 "CSI3_D3_N") (pintype "passive"))
    (pad "49" smd roundrect (at 11.749 -2.15) (size 0.3 1.2) (layers "F.Cu" "F.Paste" "F.Mask") (roundrect_rratio 0.25)
      (net 35 "CSI3_D4_P") (pintype "passive"))
    (pad "50" smd roundrect (at 12.249 -2.15) (size 0.3 1.2) (layers "F.Cu" "F.Paste" "F.Mask") (roundrect_rratio 0.25)
      (net 34 "CSI3_D4_N") (pintype "passive"))
    (pad "MP1" smd roundrect (at -14.198 -0.3) (size 2.7 3) (layers "F.Cu" "F.Paste" "F.Mask") (roundrect_rratio 0.05)
      (net 2 "GND") (pinfunction "MP") (pintype "passive"))
    (pad "MP2" smd roundrect (at 14.198 -0.3) (size 2.7 3) (layers "F.Cu" "F.Paste" "F.Mask") (roundrect_rratio 0.05)
      (net 2 "GND") (pinfunction "MP") (pintype "passive"))
  )

  (footprint "antmicro-footprints:FB_0603_1608Metric" (layer "F.Cu")
    (at 170.2 99.85 90)
    (property "Author" "Antmicro")
    (property "Current" "")
    (property "License" "Apache-2.0")
    (property "MPN" "BLM18SG121TN1D")
    (property "Manufacturer" "Murata")
    (property "Public" "False")
    (property "Sheetfile" "channel2.kicad_sch")
    (property "Sheetname" "Channel 2")
    (property "Val" "120Z/3A")
    (property "ki_description" "Ferrite Bead, 0603 [1608 Metric], 120 ohm, 3 A, BLM18S, 0.025 ohm, ± 25%, DC power line (thin type) ")
    (property "ki_keywords" "0603, SMT, FERRITE BEAD, PASSIVE")
    (attr smd)
    (fp_text reference "FB7" (at -0.94 1.58 90) (layer "F.SilkS")
        (effects (font (size 0.65 0.65) (thickness 0.13)) (justify left bottom))
    )
    (fp_text value "FB_120Z_3A_Murata-BLM18SG_0603" (at 0 1.5 90) (layer "F.Fab")
        (effects (font (size 0.65 0.65) (thickness 0.13)) (justify left bottom))
    )
    (fp_text user "License: Apache-2.0" (at -1.653 5.9 90) (layer "F.Fab") hide
        (effects (font (size 0.7 0.7) (thickness 0.15)) (justify left bottom))
    )
    (fp_text user "${REFERENCE}" (at -1.653 4.6 90) (layer "F.Fab") hide
        (effects (font (size 0.7 0.7) (thickness 0.15)) (justify left bottom))
    )
    (fp_text user "Author: Antmicro" (at -1.653 3.162 90) (layer "F.Fab") hide
        (effects (font (size 0.7 0.7) (thickness 0.15)) (justify left bottom))
    )
    (fp_line (start -0.15 -0.4) (end 0.15 -0.4)
      (stroke (width 0.15) (type solid)) (layer "F.SilkS"))
    (fp_line (start -0.15 0.4) (end 0.15 0.4)
      (stroke (width 0.15) (type solid)) (layer "F.SilkS"))
    (fp_rect (start -1.25 -0.65) (end 1.25 0.65)
      (stroke (width 0.05) (type solid)) (fill none) (layer "F.CrtYd"))
    (fp_line (start -0.803 0.406) (end -0.803 -0.408)
      (stroke (width 0.15) (type solid)) (layer "F.Fab"))
    (fp_line (start 0.8 -0.408) (end -0.803 -0.408)
      (stroke (width 0.15) (type solid)) (layer "F.Fab"))
    (fp_line (start 0.8 -0.408) (end 0.8 0.406)
      (stroke (width 0.15) (type solid)) (layer "F.Fab"))
    (fp_line (start 0.8 0.406) (end -0.803 0.406)
      (stroke (width 0.15) (type solid)) (layer "F.Fab"))
    (pad "1" smd roundrect (at -0.7 0 90) (size 0.8 1) (layers "F.Cu" "F.Paste" "F.Mask") (roundrect_rratio 0.2)
      (net 2 "GND") (pintype "passive"))
    (pad "2" smd roundrect (at 0.7 0 90) (size 0.8 1) (layers "F.Cu" "F.Paste" "F.Mask") (roundrect_rratio 0.2)
      (net 29 "Net-(FB7-Pad2)") (pintype "passive"))
  )

  (footprint "antmicro-footprints:C_0603_1608Metric" (layer "F.Cu")
    (at 140.2 113 180)
    (descr "Capacitor SMD 0603")
    (tags "capacitor 0603")
    (property "Author" "Antmicro")
    (property "Dielectric" "")
    (property "License" "Apache-2.0")
    (property "MPN" "C1608X5R1V475M080AC")
    (property "Manufacturer" "TDK")
    (property "Public" "False")
    (property "Sheetfile" "channel1.kicad_sch")
    (property "Sheetname" "Channel 1")
    (property "Val" "4u7")
    (property "Voltage" "")
    (property "ki_description" "SMD Multilayer Ceramic Capacitor, 4.7 µF, 35 V, 0603 [1608 Metric], ± 20%, X5R, C")
    (property "ki_keywords" "0603, SMT, CAPACITOR, PASSIVE, CERAMIC, MLCC")
    (attr smd)
    (fp_text reference "C10" (at 1.9 -5.6) (layer "F.SilkS")
        (effects (font (size 0.65 0.65) (thickness 0.13)) (justify right bottom))
    )
    (fp_text value "C_4u7_0603" (at 0 1.6) (layer "F.Fab")
        (effects (font (size 0.65 0.65) (thickness 0.13)) (justify right bottom))
    )
    (fp_text user "License: Apache-2.0" (at -1.682 5.895) (layer "F.Fab") hide
        (effects (font (size 0.7 0.7) (thickness 0.15)) (justify right bottom))
    )
    (fp_text user "Author: Antmicro" (at -1.682 4.894) (layer "F.Fab") hide
        (effects (font (size 0.7 0.7) (thickness 0.15)) (justify right bottom))
    )
    (fp_text user "${REFERENCE}" (at -1.682 3.895) (layer "F.Fab") hide
        (effects (font (size 0.7 0.7) (thickness 0.15)) (justify right bottom))
    )
    (fp_line (start -0.15 -0.4) (end 0.15 -0.4)
      (stroke (width 0.15) (type solid)) (layer "F.SilkS"))
    (fp_line (start -0.15 0.4) (end 0.15 0.4)
      (stroke (width 0.15) (type solid)) (layer "F.SilkS"))
    (fp_rect (start -1.25 -0.65) (end 1.25 0.65)
      (stroke (width 0.05) (type solid)) (fill none) (layer "F.CrtYd"))
    (fp_rect (start -0.8 -0.4) (end 0.8 0.4)
      (stroke (width 0.15) (type solid)) (fill none) (layer "F.Fab"))
    (pad "1" smd roundrect (at -0.7 0 180) (size 0.8 1) (layers "F.Cu" "F.Paste" "F.Mask") (roundrect_rratio 0.2)
      (net 2 "GND") (pintype "passive"))
    (pad "2" smd roundrect (at 0.7 0 180) (size 0.8 1) (layers "F.Cu" "F.Paste" "F.Mask") (roundrect_rratio 0.2)
      (net 7 "Net-(C10-Pad2)") (pintype "passive"))
  )

  (footprint "antmicro-footprints:C_0402_1005Metric" (layer "F.Cu")
    (at 167.91 106.07)
    (descr "Capacitor SMD 0402")
    (tags "capacitor SMD 0402")
    (property "Author" "Antmicro")
    (property "Dielectric" "X5R")
    (property "License" "Apache-2.0")
    (property "MPN" "GRM155R61H104KE14D")
    (property "Manufacturer" "Murata")
    (property "Public" "False")
    (property "Sheetfile" "channel2.kicad_sch")
    (property "Sheetname" "Channel 2")
    (property "Val" "100n")
    (property "Voltage" "50V")
    (property "ki_description" "SMD Multilayer Ceramic Capacitor, 0.1 µF, 50 V, 0402 [1005 Metric], ± 10%, X5R, GRM Series")
    (property "ki_keywords" "0402, SMT, CAPACITOR, PASSIVE, CERAMIC, MLCC")
    (attr smd)
    (fp_text reference "C37" (at 0.88 0.38) (layer "F.SilkS")
        (effects (font (size 0.65 0.65) (thickness 0.13)) (justify left bottom))
    )
    (fp_text value "C_100n_0402" (at 0 1.4) (layer "F.Fab")
        (effects (font (size 0.65 0.65) (thickness 0.13)) (justify left bottom))
    )
    (fp_text user "Author: Antmicro" (at -0.932 4.17) (layer "F.Fab") hide
        (effects (font (size 0.7 0.7) (thickness 0.15)) (justify left bottom))
    )
    (fp_text user "License: Apache-2.0" (at -0.932 5.17) (layer "F.Fab") hide
        (effects (font (size 0.7 0.7) (thickness 0.15)) (justify left bottom))
    )
    (fp_text user "${REFERENCE}" (at -0.932 3.168) (layer "F.Fab") hide
        (effects (font (size 0.7 0.7) (thickness 0.15)) (justify left bottom))
    )
    (fp_rect (start -0.925 -0.47) (end 0.925 0.47)
      (stroke (width 0.05) (type default)) (fill none) (layer "F.CrtYd"))
    (fp_line (start -0.494 -0.25) (end 0.504 -0.25)
      (stroke (width 0.15) (type solid)) (layer "F.Fab"))
    (fp_line (start -0.494 0.248) (end -0.494 -0.25)
      (stroke (width 0.15) (type solid)) (layer "F.Fab"))
    (fp_line (start 0.504 -0.25) (end 0.504 0.248)
      (stroke (width 0.15) (type solid)) (layer "F.Fab"))
    (fp_line (start 0.504 0.248) (end -0.494 0.248)
      (stroke (width 0.15) (type solid)) (layer "F.Fab"))
    (pad "1" smd roundrect (at -0.48 0) (size 0.59 0.64) (layers "F.Cu" "F.Paste" "F.Mask") (roundrect_rratio 0.25)
      (net 9 "+3V3") (pintype "passive"))
    (pad "2" smd roundrect (at 0.48 0) (size 0.59 0.64) (layers "F.Cu" "F.Paste" "F.Mask") (roundrect_rratio 0.25)
      (net 2 "GND") (pintype "passive"))
  )

  (footprint "antmicro-footprints:SOT-23-5" (layer "F.Cu")
    (at 143.95 119.1 90)
    (property "Author" "Antmicro")
    (property "License" "Apache-2.0")
    (property "MPN" "TLV73312PDBVT")
    (property "Manufacturer" "Texas Instruments")
    (property "Sheetfile" "channel1.kicad_sch")
    (property "Sheetname" "Channel 1")
    (property "ki_description" "Fixed LDO Voltage Regulator, 1.4V to 5.5V, 122mV Dropout, 1.2Vout, 300mAout, SOT-23-5")
    (property "ki_keywords" "SMT, PMIC, IC, LDO, LINEAR, VOLTAGE, REGULATOR")
    (attr smd)
    (fp_text reference "IC2" (at -2.89 -0.9 180) (layer "F.SilkS")
        (effects (font (size 0.65 0.65) (thickness 0.13)) (justify left bottom))
    )
    (fp_text value "TLV73312PDBVT" (at 0.002 2.799 90) (layer "F.Fab")
        (effects (font (size 0.65 0.65) (thickness 0.13)) (justify left bottom))
    )
    (fp_text user "Author: Antmicro" (at -1.898 5.499 90) (layer "F.Fab") hide
        (effects (font (size 0.7 0.7) (thickness 0.15)) (justify left bottom))
    )
    (fp_text user "${REFERENCE}" (at -1.898 4.299 90) (layer "F.Fab") hide
        (effects (font (size 0.7 0.7) (thickness 0.15)) (justify left bottom))
    )
    (fp_text user "License: Apache-2.0" (at -1.898 6.7 90) (layer "F.Fab") hide
        (effects (font (size 0.7 0.7) (thickness 0.15)) (justify left bottom))
    )
    (fp_line (start -0.85 1.6) (end -0.85 1.301)
      (stroke (width 0.15) (type solid)) (layer "F.SilkS"))
    (fp_line (start -0.8 -1.6) (end -0.8 -1.3)
      (stroke (width 0.15) (type solid)) (layer "F.SilkS"))
    (fp_line (start -0.8 -1.6) (end -0.5 -1.6)
      (stroke (width 0.15) (type solid)) (layer "F.SilkS"))
    (fp_line (start -0.55 1.6) (end -0.85 1.6)
      (stroke (width 0.15) (type solid)) (layer "F.SilkS"))
    (fp_line (start 0.8 -1.6) (end 0.5 -1.6)
      (stroke (width 0.15) (type solid)) (layer "F.SilkS"))
    (fp_line (start 0.8 -1.3) (end 0.8 -1.6)
      (stroke (width 0.15) (type solid)) (layer "F.SilkS"))
    (fp_line (start 0.8 0.55) (end 0.8 -0.55)
      (stroke (width 0.15) (type solid)) (layer "F.SilkS"))
    (fp_line (start 0.8 1.3) (end 0.8 1.599)
      (stroke (width 0.15) (type solid)) (layer "F.SilkS"))
    (fp_line (start 0.8 1.599) (end 0.549 1.599)
      (stroke (width 0.15) (type solid)) (layer "F.SilkS"))
    (fp_circle (center -1.25 -1.5) (end -1.2 -1.5)
      (stroke (width 0.15) (type solid)) (fill solid) (layer "F.SilkS"))
    (fp_rect (start 1.9 -1.76) (end -1.9 1.75)
      (stroke (width 0.05) (type solid)) (fill none) (layer "F.CrtYd"))
    (fp_line (start -0.398 -1.526) (end -0.874 -1.05)
      (stroke (width 0.15) (type solid)) (layer "F.Fab"))
    (fp_rect (start 0.874 1.523) (end -0.873 -1.525)
      (stroke (width 0.15) (type solid)) (fill none) (layer "F.Fab"))
    (pad "1" smd rect (at -1.351 -0.951) (size 0.55 1) (layers "F.Cu" "F.Paste" "F.Mask")
      (net 9 "+3V3") (pinfunction "VIN") (pintype "power_in"))
    (pad "2" smd rect (at -1.351 0) (size 0.55 1) (layers "F.Cu" "F.Paste" "F.Mask")
      (net 2 "GND") (pinfunction "GND") (pintype "power_in"))
    (pad "3" smd rect (at -1.351 0.949) (size 0.55 1) (layers "F.Cu" "F.Paste" "F.Mask")
      (net 9 "+3V3") (pinfunction "EN") (pintype "input"))
    (pad "4" smd rect (at 1.35 0.949) (size 0.55 1) (layers "F.Cu" "F.Paste" "F.Mask")
      (net 101 "unconnected-(IC2-NC-Pad4)") (pinfunction "NC") (pintype "no_connect"))
    (pad "5" smd rect (at 1.35 -0.951) (size 0.55 1) (layers "F.Cu" "F.Paste" "F.Mask")
      (net 12 "CH1_1V2") (pinfunction "VOUT") (pintype "power_out"))
  )

  (footprint "antmicro-footprints:C_0402_1005Metric" (layer "F.Cu")
    (at 131 108.4 180)
    (descr "Capacitor SMD 0402")
    (tags "capacitor SMD 0402")
    (property "Author" "Antmicro")
    (property "Dielectric" "")
    (property "License" "Apache-2.0")
    (property "MPN" "0402B471K250CT")
    (property "Manufacturer" "Walsin")
    (property "Public" "False")
    (property "Sheetfile" "channel1.kicad_sch")
    (property "Sheetname" "Channel 1")
    (property "Val" "470p")
    (property "Voltage" "")
    (property "ki_description" "SMD Multilayer Ceramic Capacitor, General Purpose, 470 pF, 25 V, 0402 [1005 Metric], ± 10%, X7R")
    (property "ki_keywords" "0402, SMT, CAPACITOR, PASSIVE, MLCC")
    (attr smd)
    (fp_text reference "C7" (at 0.1 -7.6) (layer "F.SilkS")
        (effects (font (size 0.65 0.65) (thickness 0.13)) (justify right bottom))
    )
    (fp_text value "C_470p_0402" (at 0 1.4) (layer "F.Fab")
        (effects (font (size 0.65 0.65) (thickness 0.13)) (justify right bottom))
    )
    (fp_text user "License: Apache-2.0" (at -0.932 5.17) (layer "F.Fab") hide
        (effects (font (size 0.7 0.7) (thickness 0.15)) (justify right bottom))
    )
    (fp_text user "Author: Antmicro" (at -0.932 4.17) (layer "F.Fab") hide
        (effects (font (size 0.7 0.7) (thickness 0.15)) (justify right bottom))
    )
    (fp_text user "${REFERENCE}" (at -0.932 3.168) (layer "F.Fab") hide
        (effects (font (size 0.7 0.7) (thickness 0.15)) (justify right bottom))
    )
    (fp_rect (start -0.925 -0.47) (end 0.925 0.47)
      (stroke (width 0.05) (type default)) (fill none) (layer "F.CrtYd"))
    (fp_line (start -0.494 -0.25) (end 0.504 -0.25)
      (stroke (width 0.15) (type solid)) (layer "F.Fab"))
    (fp_line (start -0.494 0.248) (end -0.494 -0.25)
      (stroke (width 0.15) (type solid)) (layer "F.Fab"))
    (fp_line (start 0.504 -0.25) (end 0.504 0.248)
      (stroke (width 0.15) (type solid)) (layer "F.Fab"))
    (fp_line (start 0.504 0.248) (end -0.494 0.248)
      (stroke (width 0.15) (type solid)) (layer "F.Fab"))
    (pad "1" smd roundrect (at -0.48 0 180) (size 0.59 0.64) (layers "F.Cu" "F.Paste" "F.Mask") (roundrect_rratio 0.25)
      (net 8 "Net-(U1B-VDDC1)") (pintype "passive"))
    (pad "2" smd roundrect (at 0.48 0 180) (size 0.59 0.64) (layers "F.Cu" "F.Paste" "F.Mask") (roundrect_rratio 0.25)
      (net 2 "GND") (pintype "passive"))
  )

  (footprint "antmicro-footprints:R_0402_1005Metric" (layer "F.Cu")
    (at 169.15 107.95 -90)
    (descr "Resistor SMD 0402")
    (tags "resistor SMD 0402")
    (property "Author" "Antmicro")
    (property "License" "Apache-2.0")
    (property "MPN" "CR0402-FX-1002GLF")
    (property "Manufacturer" "Bourns")
    (property "Public" "False")
    (property "Sheetfile" "channel2.kicad_sch")
    (property "Sheetname" "Channel 2")
    (property "Tolerance" "1%")
    (property "Val" "10k")
    (property "ki_description" "SMD Chip Resistor, 10 kohm, ± 1%, 62.5 mW, 0402 [1005 Metric], Thick Film, General Purpose")
    (property "ki_keywords" "0402, SMT, RESISTOR, PASSIVE")
    (attr smd)
    (fp_text reference "R22" (at 1.11 -2.37 -90) (layer "F.SilkS")
        (effects (font (size 0.65 0.65) (thickness 0.13)) (justify left bottom))
    )
    (fp_text value "R_10k_0402" (at 0 1.4 -90) (layer "F.Fab")
        (effects (font (size 0.65 0.65) (thickness 0.13)) (justify left bottom))
    )
    (fp_text user "License: Apache-2.0" (at -0.95 5.169 -90) (layer "F.Fab") hide
        (effects (font (size 0.7 0.7) (thickness 0.15)) (justify left bottom))
    )
    (fp_text user "${REFERENCE}" (at -0.95 3.168 -90) (layer "F.Fab") hide
        (effects (font (size 0.7 0.7) (thickness 0.15)) (justify left bottom))
    )
    (fp_text user "Author: Antmicro" (at -0.95 4.169 -90) (layer "F.Fab") hide
        (effects (font (size 0.7 0.7) (thickness 0.15)) (justify left bottom))
    )
    (fp_rect (start -0.925 -0.47) (end 0.925 0.47)
      (stroke (width 0.05) (type default)) (fill none) (layer "F.CrtYd"))
    (fp_rect (start -0.5 -0.25) (end 0.5 0.25)
      (stroke (width 0.15) (type solid)) (fill none) (layer "F.Fab"))
    (pad "1" smd roundrect (at -0.48 0 270) (size 0.59 0.64) (layers "F.Cu" "F.Paste" "F.Mask") (roundrect_rratio 0.25)
      (net 111 "/Channel 2/HDMI2_DDC_SDA_3V3") (pintype "passive"))
    (pad "2" smd roundrect (at 0.48 0 270) (size 0.59 0.64) (layers "F.Cu" "F.Paste" "F.Mask") (roundrect_rratio 0.25)
      (net 9 "+3V3") (pintype "passive"))
  )

  (footprint "antmicro-footprints:C_0603_1608Metric" (layer "F.Cu")
    (at 130.6 107.2)
    (descr "Capacitor SMD 0603")
    (tags "capacitor 0603")
    (property "Author" "Antmicro")
    (property "Dielectric" "")
    (property "License" "Apache-2.0")
    (property "MPN" "C1608X5R1V475M080AC")
    (property "Manufacturer" "TDK")
    (property "Public" "False")
    (property "Sheetfile" "channel1.kicad_sch")
    (property "Sheetname" "Channel 1")
    (property "Val" "4u7")
    (property "Voltage" "")
    (property "ki_description" "SMD Multilayer Ceramic Capacitor, 4.7 µF, 35 V, 0603 [1608 Metric], ± 20%, X5R, C")
    (property "ki_keywords" "0603, SMT, CAPACITOR, PASSIVE, CERAMIC, MLCC")
    (attr smd)
    (fp_text reference "C11" (at -3.25 -0.1) (layer "F.SilkS")
        (effects (font (size 0.65 0.65) (thickness 0.13)) (justify left bottom))
    )
    (fp_text value "C_4u7_0603" (at 0 1.6) (layer "F.Fab")
        (effects (font (size 0.65 0.65) (thickness 0.13)) (justify left bottom))
    )
    (fp_text user "Author: Antmicro" (at -1.682 4.894) (layer "F.Fab") hide
        (effects (font (size 0.7 0.7) (thickness 0.15)) (justify left bottom))
    )
    (fp_text user "License: Apache-2.0" (at -1.682 5.895) (layer "F.Fab") hide
        (effects (font (size 0.7 0.7) (thickness 0.15)) (justify left bottom))
    )
    (fp_text user "${REFERENCE}" (at -1.682 3.895) (layer "F.Fab") hide
        (effects (font (size 0.7 0.7) (thickness 0.15)) (justify left bottom))
    )
    (fp_line (start -0.15 -0.4) (end 0.15 -0.4)
      (stroke (width 0.15) (type solid)) (layer "F.SilkS"))
    (fp_line (start -0.15 0.4) (end 0.15 0.4)
      (stroke (width 0.15) (type solid)) (layer "F.SilkS"))
    (fp_rect (start -1.25 -0.65) (end 1.25 0.65)
      (stroke (width 0.05) (type solid)) (fill none) (layer "F.CrtYd"))
    (fp_rect (start -0.8 -0.4) (end 0.8 0.4)
      (stroke (width 0.15) (type solid)) (fill none) (layer "F.Fab"))
    (pad "1" smd roundrect (at -0.7 0) (size 0.8 1) (layers "F.Cu" "F.Paste" "F.Mask") (roundrect_rratio 0.2)
      (net 2 "GND") (pintype "passive"))
    (pad "2" smd roundrect (at 0.7 0) (size 0.8 1) (layers "F.Cu" "F.Paste" "F.Mask") (roundrect_rratio 0.2)
      (net 8 "Net-(U1B-VDDC1)") (pintype "passive"))
  )

  (footprint "antmicro-footprints:R-PDSO-N15" (layer "F.Cu")
    (at 135.25 103.37 90)
    (property "Author" "Antmicro")
    (property "License" "Apache-2.0")
    (property "MPN" "TPD8S009DSMR")
    (property "Manufacturer" "Texas Instruments")
    (property "Sheetfile" "channel1.kicad_sch")
    (property "Sheetname" "Channel 1")
    (property "ki_description" "TVS diode array, 8 kV, R-PDSO-N15, 5.5 V, 0.8 pF")
    (property "ki_keywords" "SMT, DIODE, SEMICONDUCTOR, TVS, ESD")
    (attr smd)
    (fp_text reference "U2" (at -0.43 -3.65 90) (layer "F.SilkS")
        (effects (font (size 0.65 0.65) (thickness 0.13)) (justify left bottom))
    )
    (fp_text value "TPD8S009DSMR" (at 0 4.4 90) (layer "F.Fab")
        (effects (font (size 0.65 0.65) (thickness 0.13)) (justify left bottom))
    )
    (fp_text user "License: Apache-2.0" (at -4.1 6.15 90) (layer "F.Fab") hide
        (effects (font (size 0.7 0.7) (thickness 0.15)) (justify left bottom))
    )
    (fp_text user "${REFERENCE}" (at -4.1 4.95 90) (layer "F.Fab") hide
        (effects (font (size 0.7 0.7) (thickness 0.15)) (justify left bottom))
    )
    (fp_text user "Author: Antmicro" (at -4.1 7.35 90) (layer "F.Fab") hide
        (effects (font (size 0.7 0.7) (thickness 0.15)) (justify left bottom))
    )
    (fp_circle (center -1.6 -3.2) (end -1.6 -3.15)
      (stroke (width 0.15) (type solid)) (fill solid) (layer "F.SilkS"))
    (fp_rect (start 1.8 -3.5) (end -1.89 3.49)
      (stroke (width 0.05) (type solid)) (fill none) (layer "F.CrtYd"))
    (fp_line (start -1.3 -3.051) (end -1.1 -3.25)
      (stroke (width 0.15) (type solid)) (layer "F.Fab"))
    (fp_rect (start 1.301 -3.25) (end -1.3 3.249)
      (stroke (width 0.15) (type solid)) (fill none) (layer "F.Fab"))
    (pad "1" smd roundrect (at -0.95 -2.75) (size 0.3 1.45) (layers "F.Cu" "F.Paste" "F.Mask") (roundrect_rratio 0.25)
      (net 74 "/Channel 1/HDMI1_D2_P") (pinfunction "D0+") (pintype "passive"))
    (pad "2" smd roundrect (at -0.95 -2.25) (size 0.3 1.45) (layers "F.Cu" "F.Paste" "F.Mask") (roundrect_rratio 0.25)
      (net 2 "GND") (pinfunction "GND") (pintype "passive"))
    (pad "3" smd roundrect (at -0.95 -1.75) (size 0.3 1.45) (layers "F.Cu" "F.Paste" "F.Mask") (roundrect_rratio 0.25)
      (net 75 "/Channel 1/HDMI1_D2_N") (pinfunction "D0-") (pintype "passive"))
    (pad "4" smd roundrect (at -0.95 -1.25) (size 0.3 1.45) (layers "F.Cu" "F.Paste" "F.Mask") (roundrect_rratio 0.25)
      (net 76 "/Channel 1/HDMI1_D1_P") (pinfunction "D1+") (pintype "passive"))
    (pad "5" smd roundrect (at -0.95 -0.75) (size 0.3 1.45) (layers "F.Cu" "F.Paste" "F.Mask") (roundrect_rratio 0.25)
      (net 2 "GND") (pinfunction "GND") (pintype "passive"))
    (pad "6" smd roundrect (at -0.95 -0.25) (size 0.3 1.45) (layers "F.Cu" "F.Paste" "F.Mask") (roundrect_rratio 0.25)
      (net 77 "/Channel 1/HDMI1_D1_N") (pinfunction "D1-") (pintype "passive"))
    (pad "7" smd roundrect (at -0.95 0.247) (size 0.3 1.45) (layers "F.Cu" "F.Paste" "F.Mask") (roundrect_rratio 0.25)
      (net 78 "/Channel 1/HDMI1_D0_P") (pinfunction "D2+") (pintype "passive"))
    (pad "8" smd roundrect (at -0.95 0.747) (size 0.3 1.45) (layers "F.Cu" "F.Paste" "F.Mask") (roundrect_rratio 0.25)
      (net 2 "GND") (pinfunction "GND") (pintype "passive"))
    (pad "9" smd roundrect (at -0.95 1.249) (size 0.3 1.45) (layers "F.Cu" "F.Paste" "F.Mask") (roundrect_rratio 0.25)
      (net 79 "/Channel 1/HDMI1_D0_N") (pinfunction "D2-") (pintype "passive"))
    (pad "10" smd roundrect (at -0.95 1.749) (size 0.3 1.45) (layers "F.Cu" "F.Paste" "F.Mask") (roundrect_rratio 0.25)
      (net 80 "/Channel 1/HDMI1_CLK_P") (pinfunction "D3+") (pintype "passive"))
    (pad "11" smd roundrect (at -0.95 2.249) (size 0.3 1.45) (layers "F.Cu" "F.Paste" "F.Mask") (roundrect_rratio 0.25)
      (net 2 "GND") (pinfunction "GND") (pintype "passive"))
    (pad "12" smd roundrect (at -0.95 2.749) (size 0.3 1.45) (layers "F.Cu" "F.Paste" "F.Mask") (roundrect_rratio 0.25)
      (net 81 "/Channel 1/HDMI1_CLK_N") (pinfunction "D3-") (pintype "passive"))
    (pad "13" smd roundrect (at 0.901 1.499) (size 0.3 1.45) (layers "F.Cu" "F.Paste" "F.Mask") (roundrect_rratio 0.25)
      (net 9 "+3V3") (pinfunction "VCC") (pintype "power_in"))
    (pad "14" smd roundrect (at 0.901 0) (size 0.3 1.45) (layers "F.Cu" "F.Paste" "F.Mask") (roundrect_rratio 0.25)
      (net 130 "unconnected-(U2-NC-Pad14)") (pinfunction "NC") (pintype "no_connect"))
    (pad "15" smd roundrect (at 0.901 -1.5) (size 0.3 1.45) (layers "F.Cu" "F.Paste" "F.Mask") (roundrect_rratio 0.25)
      (net 9 "+3V3") (pinfunction "VCC") (pintype "passive"))
  )

  (footprint "antmicro-footprints:FB_0603_1608Metric" (layer "F.Cu")
    (at 146.2 99.8 90)
    (property "Author" "Antmicro")
    (property "Current" "")
    (property "License" "Apache-2.0")
    (property "MPN" "BLM18SG121TN1D")
    (property "Manufacturer" "Murata")
    (property "Public" "False")
    (property "Sheetfile" "channel1.kicad_sch")
    (property "Sheetname" "Channel 1")
    (property "Val" "120Z/3A")
    (property "ki_description" "Ferrite Bead, 0603 [1608 Metric], 120 ohm, 3 A, BLM18S, 0.025 ohm, ± 25%, DC power line (thin type) ")
    (property "ki_keywords" "0603, SMT, FERRITE BEAD, PASSIVE")
    (attr smd)
    (fp_text reference "FB1" (at -1.15 1.57 90) (layer "F.SilkS")
        (effects (font (size 0.65 0.65) (thickness 0.13)) (justify left bottom))
    )
    (fp_text value "FB_120Z_3A_Murata-BLM18SG_0603" (at 0 1.5 90) (layer "F.Fab")
        (effects (font (size 0.65 0.65) (thickness 0.13)) (justify left bottom))
    )
    (fp_text user "License: Apache-2.0" (at -1.653 5.9 90) (layer "F.Fab") hide
        (effects (font (size 0.7 0.7) (thickness 0.15)) (justify left bottom))
    )
    (fp_text user "Author: Antmicro" (at -1.653 3.162 90) (layer "F.Fab") hide
        (effects (font (size 0.7 0.7) (thickness 0.15)) (justify left bottom))
    )
    (fp_text user "${REFERENCE}" (at -1.653 4.6 90) (layer "F.Fab") hide
        (effects (font (size 0.7 0.7) (thickness 0.15)) (justify left bottom))
    )
    (fp_line (start -0.15 -0.4) (end 0.15 -0.4)
      (stroke (width 0.15) (type solid)) (layer "F.SilkS"))
    (fp_line (start -0.15 0.4) (end 0.15 0.4)
      (stroke (width 0.15) (type solid)) (layer "F.SilkS"))
    (fp_rect (start -1.25 -0.65) (end 1.25 0.65)
      (stroke (width 0.05) (type solid)) (fill none) (layer "F.CrtYd"))
    (fp_line (start -0.803 0.406) (end -0.803 -0.408)
      (stroke (width 0.15) (type solid)) (layer "F.Fab"))
    (fp_line (start 0.8 -0.408) (end -0.803 -0.408)
      (stroke (width 0.15) (type solid)) (layer "F.Fab"))
    (fp_line (start 0.8 -0.408) (end 0.8 0.406)
      (stroke (width 0.15) (type solid)) (layer "F.Fab"))
    (fp_line (start 0.8 0.406) (end -0.803 0.406)
      (stroke (width 0.15) (type solid)) (layer "F.Fab"))
    (pad "1" smd roundrect (at -0.7 0 90) (size 0.8 1) (layers "F.Cu" "F.Paste" "F.Mask") (roundrect_rratio 0.2)
      (net 2 "GND") (pintype "passive"))
    (pad "2" smd roundrect (at 0.7 0 90) (size 0.8 1) (layers "F.Cu" "F.Paste" "F.Mask") (roundrect_rratio 0.2)
      (net 28 "Net-(FB1-Pad2)") (pintype "passive"))
  )

  (footprint "antmicro-footprints:C_0603_1608Metric" (layer "F.Cu")
    (at 164.11 109.53 180)
    (descr "Capacitor SMD 0603")
    (tags "capacitor 0603")
    (property "Author" "Antmicro")
    (property "Dielectric" "")
    (property "License" "Apache-2.0")
    (property "MPN" "C1608X5R1V475M080AC")
    (property "Manufacturer" "TDK")
    (property "Public" "False")
    (property "Sheetfile" "channel2.kicad_sch")
    (property "Sheetname" "Channel 2")
    (property "Val" "4u7")
    (property "Voltage" "")
    (property "ki_description" "SMD Multilayer Ceramic Capacitor, 4.7 µF, 35 V, 0603 [1608 Metric], ± 20%, X5R, C")
    (property "ki_keywords" "0603, SMT, CAPACITOR, PASSIVE, CERAMIC, MLCC")
    (attr smd)
    (fp_text reference "C51" (at 1.9 -6.95) (layer "F.SilkS")
        (effects (font (size 0.65 0.65) (thickness 0.13)) (justify right bottom))
    )
    (fp_text value "C_4u7_0603" (at 0 1.6) (layer "F.Fab")
        (effects (font (size 0.65 0.65) (thickness 0.13)) (justify right bottom))
    )
    (fp_text user "License: Apache-2.0" (at -1.682 5.895) (layer "F.Fab") hide
        (effects (font (size 0.7 0.7) (thickness 0.15)) (justify right bottom))
    )
    (fp_text user "Author: Antmicro" (at -1.682 4.894) (layer "F.Fab") hide
        (effects (font (size 0.7 0.7) (thickness 0.15)) (justify right bottom))
    )
    (fp_text user "${REFERENCE}" (at -1.682 3.895) (layer "F.Fab") hide
        (effects (font (size 0.7 0.7) (thickness 0.15)) (justify right bottom))
    )
    (fp_line (start -0.15 -0.4) (end 0.15 -0.4)
      (stroke (width 0.15) (type solid)) (layer "F.SilkS"))
    (fp_line (start -0.15 0.4) (end 0.15 0.4)
      (stroke (width 0.15) (type solid)) (layer "F.SilkS"))
    (fp_rect (start -1.25 -0.65) (end 1.25 0.65)
      (stroke (width 0.05) (type solid)) (fill none) (layer "F.CrtYd"))
    (fp_rect (start -0.8 -0.4) (end 0.8 0.4)
      (stroke (width 0.15) (type solid)) (fill none) (layer "F.Fab"))
    (pad "1" smd roundrect (at -0.7 0 180) (size 0.8 1) (layers "F.Cu" "F.Paste" "F.Mask") (roundrect_rratio 0.2)
      (net 2 "GND") (pintype "passive"))
    (pad "2" smd roundrect (at 0.7 0 180) (size 0.8 1) (layers "F.Cu" "F.Paste" "F.Mask") (roundrect_rratio 0.2)
      (net 32 "Net-(U4B-AVDD25)") (pintype "passive"))
  )

  (footprint "antmicro-footprints:C_0603_1608Metric" (layer "F.Cu")
    (at 147.35 113.05 180)
    (descr "Capacitor SMD 0603")
    (tags "capacitor 0603")
    (property "Author" "Antmicro")
    (property "Dielectric" "template_dielectric")
    (property "License" "Apache-2.0")
    (property "MPN" "GRM188R61A106KE69D")
    (property "Manufacturer" "Murata")
    (property "Public" "False")
    (property "Sheetfile" "channel1.kicad_sch")
    (property "Sheetname" "Channel 1")
    (property "Val" "10u")
    (property "Voltage" "")
    (property "ki_description" "SMD Multilayer Ceramic Capacitor, 10 µF, 10 V, 0603 [1608 Metric], ± 10%, X5R, GRM Series")
    (property "ki_keywords" "0603, SMT, CAPACITOR, PASSIVE, CERAMIC, MLCC")
    (attr smd)
    (fp_text reference "C19" (at -3.21 -0.69) (layer "F.SilkS")
        (effects (font (size 0.65 0.65) (thickness 0.13)) (justify right bottom))
    )
    (fp_text value "C_10u_0603" (at 0 1.6) (layer "F.Fab")
        (effects (font (size 0.65 0.65) (thickness 0.13)) (justify right bottom))
    )
    (fp_text user "License: Apache-2.0" (at -1.682 5.895) (layer "F.Fab") hide
        (effects (font (size 0.7 0.7) (thickness 0.15)) (justify right bottom))
    )
    (fp_text user "Author: Antmicro" (at -1.682 4.894) (layer "F.Fab") hide
        (effects (font (size 0.7 0.7) (thickness 0.15)) (justify right bottom))
    )
    (fp_text user "${REFERENCE}" (at -1.682 3.895) (layer "F.Fab") hide
        (effects (font (size 0.7 0.7) (thickness 0.15)) (justify right bottom))
    )
    (fp_line (start -0.15 -0.4) (end 0.15 -0.4)
      (stroke (width 0.15) (type solid)) (layer "F.SilkS"))
    (fp_line (start -0.15 0.4) (end 0.15 0.4)
      (stroke (width 0.15) (type solid)) (layer "F.SilkS"))
    (fp_rect (start -1.25 -0.65) (end 1.25 0.65)
      (stroke (width 0.05) (type solid)) (fill none) (layer "F.CrtYd"))
    (fp_rect (start -0.8 -0.4) (end 0.8 0.4)
      (stroke (width 0.15) (type solid)) (fill none) (layer "F.Fab"))
    (pad "1" smd roundrect (at -0.7 0 180) (size 0.8 1) (layers "F.Cu" "F.Paste" "F.Mask") (roundrect_rratio 0.2)
      (net 2 "GND") (pintype "passive"))
    (pad "2" smd roundrect (at 0.7 0 180) (size 0.8 1) (layers "F.Cu" "F.Paste" "F.Mask") (roundrect_rratio 0.2)
      (net 11 "CH1_2V5") (pintype "passive"))
  )

  (footprint "antmicro-footprints:R_0402_1005Metric" (layer "F.Cu")
    (at 163.25 105.85 180)
    (descr "Resistor SMD 0402")
    (tags "resistor SMD 0402")
    (property "Author" "Antmicro")
    (property "License" "Apache-2.0")
    (property "MPN" "CR0402-FX-2001GLF")
    (property "Manufacturer" "Bourns")
    (property "Public" "False")
    (property "Sheetfile" "channel2.kicad_sch")
    (property "Sheetname" "Channel 2")
    (property "Tolerance" "1%")
    (property "Val" "2k")
    (property "ki_description" "SMD Chip Resistor, 2 kohm, ± 1%, 62.5 mW, 0402 [1005 Metric], Thick Film, General Purpose")
    (property "ki_keywords" "0402, SMT, RESISTOR, PASSIVE")
    (attr smd)
    (fp_text reference "R17" (at 2.88 -0.48 180) (layer "F.SilkS")
        (effects (font (size 0.65 0.65) (thickness 0.13)) (justify left bottom))
    )
    (fp_text value "R_2k_0402" (at 0 1.4 180) (layer "F.Fab")
        (effects (font (size 0.65 0.65) (thickness 0.13)) (justify left bottom))
    )
    (fp_text user "${REFERENCE}" (at -0.95 3.168 180) (layer "F.Fab") hide
        (effects (font (size 0.7 0.7) (thickness 0.15)) (justify left bottom))
    )
    (fp_text user "Author: Antmicro" (at -0.95 4.169 180) (layer "F.Fab") hide
        (effects (font (size 0.7 0.7) (thickness 0.15)) (justify left bottom))
    )
    (fp_text user "License: Apache-2.0" (at -0.95 5.169 180) (layer "F.Fab") hide
        (effects (font (size 0.7 0.7) (thickness 0.15)) (justify left bottom))
    )
    (fp_rect (start -0.925 -0.47) (end 0.925 0.47)
      (stroke (width 0.05) (type default)) (fill none) (layer "F.CrtYd"))
    (fp_rect (start -0.5 -0.25) (end 0.5 0.25)
      (stroke (width 0.15) (type solid)) (fill none) (layer "F.Fab"))
    (pad "1" smd roundrect (at -0.48 0 180) (size 0.59 0.64) (layers "F.Cu" "F.Paste" "F.Mask") (roundrect_rratio 0.25)
      (net 114 "Net-(U4B-REXT)") (pintype "passive"))
    (pad "2" smd roundrect (at 0.48 0 180) (size 0.59 0.64) (layers "F.Cu" "F.Paste" "F.Mask") (roundrect_rratio 0.25)
      (net 108 "/Channel 2/CH2_AVDD33") (pintype "passive"))
  )

  (footprint "antmicro-footprints:FB_0805_2012Metric" (layer "F.Cu")
    (at 142.6 108.7 90)
    (descr "FERRITE BEAD 0805")
    (tags "FERRITE BEAD 0805")
    (property "Author" "Antmicro")
    (property "Current" "")
    (property "License" "Apache-2.0")
    (property "MPN" "742792096")
    (property "Manufacturer" "Würth Elektronik")
    (property "Public" "False")
    (property "Sheetfile" "channel1.kicad_sch")
    (property "Sheetname" "Channel 1")
    (property "Val" "1kZ/0.8A")
    (property "ki_description" "Ferrite Beads WE-CBF 0805 100MHz 1kOhm 1A, High Current")
    (property "ki_keywords" "FERRITE BEAD, PASSIVE")
    (attr smd)
    (fp_text reference "FB3" (at -2.5 1.7 90) (layer "F.SilkS")
        (effects (font (size 0.65 0.65) (thickness 0.13)) (justify left bottom))
    )
    (fp_text value "FB_1kZ_0.8A_WE-CBF_0805" (at 0 1.8 90) (layer "F.Fab")
        (effects (font (size 0.65 0.65) (thickness 0.13)) (justify left bottom))
    )
    (fp_text user "Author: Antmicro" (at -1.9 4.4 90) (layer "F.Fab") hide
        (effects (font (size 0.7 0.7) (thickness 0.15)) (justify left bottom))
    )
    (fp_text user "License: Apache-2.0" (at -1.9 5.75 90) (layer "F.Fab") hide
        (effects (font (size 0.7 0.7) (thickness 0.15)) (justify left bottom))
    )
    (fp_text user "${REFERENCE}" (at -1.9 3.1 90) (layer "F.Fab") hide
        (effects (font (size 0.7 0.7) (thickness 0.15)) (justify left bottom))
    )
    (fp_line (start -0.319 0.698) (end 0.281 0.698)
      (stroke (width 0.15) (type solid)) (layer "F.SilkS"))
    (fp_line (start -0.299 -0.698) (end 0.299 -0.698)
      (stroke (width 0.15) (type solid)) (layer "F.SilkS"))
    (fp_rect (start 1.95 -0.9) (end -1.95 0.9)
      (stroke (width 0.05) (type default)) (fill none) (layer "F.CrtYd"))
    (fp_line (start -0.948 -0.681) (end 0.948 -0.681)
      (stroke (width 0.15) (type solid)) (layer "F.Fab"))
    (fp_line (start -0.948 -0.676) (end -0.948 0.676)
      (stroke (width 0.15) (type solid)) (layer "F.Fab"))
    (fp_line (start -0.948 0.681) (end 0.948 0.681)
      (stroke (width 0.15) (type solid)) (layer "F.Fab"))
    (fp_line (start 0.948 -0.676) (end 0.948 0.676)
      (stroke (width 0.15) (type solid)) (layer "F.Fab"))
    (pad "1" smd roundrect (at -1.1 0 90) (size 1.2 1.3) (layers "F.Cu" "F.Paste" "F.Mask") (roundrect_rratio 0.25)
      (net 6 "Net-(C5-Pad1)") (pintype "passive"))
    (pad "2" smd roundrect (at 1.1 0 90) (size 1.2 1.3) (layers "F.Cu" "F.Paste" "F.Mask") (roundrect_rratio 0.25)
      (net 12 "CH1_1V2") (pintype "passive"))
  )

  (footprint "antmicro-footprints:R_0603_1608Metric" (layer "F.Cu")
    (at 144.9 101.85)
    (descr "Resistor SMD 0603")
    (tags "resistor SMD 0603")
    (property "Author" "Antmicro")
    (property "Current" "1A")
    (property "License" "Apache-2.0")
    (property "MPN" "CR0603-J/-000ELF")
    (property "Manufacturer" "Bourns")
    (property "Public" "False")
    (property "Sheetfile" "channel1.kicad_sch")
    (property "Sheetname" "Channel 1")
    (property "Tolerance" "")
    (property "Val" "0R")
    (property "ki_description" "Zero Ohm Resistor, Jumper, 0603 [1608 Metric], Thick Film, 100 mW, 1 A, Surface Mount Device, CR")
    (property "ki_keywords" "0603, SMT, RESISTOR, PASSIVE")
    (attr smd)
    (fp_text reference "R1" (at 1 0.35) (layer "F.SilkS")
        (effects (font (size 0.7 0.7) (thickness 0.15)) (justify left bottom))
    )
    (fp_text value "R_0R_0603" (at 0 1.6) (layer "F.Fab")
        (effects (font (size 0.7 0.7) (thickness 0.15)) (justify left bottom))
    )
    (fp_text user "${REFERENCE}" (at -1.25 3.898) (layer "F.Fab") hide
        (effects (font (size 0.7 0.7) (thickness 0.15)) (justify left bottom))
    )
    (fp_text user "Author: Antmicro" (at -1.25 4.9) (layer "F.Fab") hide
        (effects (font (size 0.7 0.7) (thickness 0.15)) (justify left bottom))
    )
    (fp_text user "License: Apache-2.0" (at -1.25 5.9) (layer "F.Fab") hide
        (effects (font (size 0.7 0.7) (thickness 0.15)) (justify left bottom))
    )
    (fp_line (start -0.15 -0.4) (end 0.15 -0.4)
      (stroke (width 0.15) (type solid)) (layer "F.SilkS"))
    (fp_line (start -0.15 0.4) (end 0.15 0.4)
      (stroke (width 0.15) (type solid)) (layer "F.SilkS"))
    (fp_rect (start -1.25 -0.65) (end 1.25 0.65)
      (stroke (width 0.05) (type solid)) (fill none) (layer "F.CrtYd"))
    (fp_rect (start -0.8 -0.4) (end 0.8 0.4)
      (stroke (width 0.15) (type solid)) (fill none) (layer "F.Fab"))
    (pad "1" smd roundrect (at -0.7 0) (size 0.8 1) (layers "F.Cu" "F.Paste" "F.Mask") (roundrect_rratio 0.2)
      (net 86 "/Channel 1/HDMI1_POWER") (pintype "passive"))
    (pad "2" smd roundrect (at 0.7 0) (size 0.8 1) (layers "F.Cu" "F.Paste" "F.Mask") (roundrect_rratio 0.2)
      (net 87 "/Channel 1/HDMI1_HPD") (pintype "passive"))
  )

  (footprint "antmicro-footprints:C_0603_1608Metric" (layer "F.Cu")
    (at 165.5 119.95 -90)
    (descr "Capacitor SMD 0603")
    (tags "capacitor 0603")
    (property "Author" "Antmicro")
    (property "Dielectric" "template_dielectric")
    (property "License" "Apache-2.0")
    (property "MPN" "GRM188R61A106KE69D")
    (property "Manufacturer" "Murata")
    (property "Public" "False")
    (property "Sheetfile" "channel2.kicad_sch")
    (property "Sheetname" "Channel 2")
    (property "Val" "10u")
    (property "Voltage" "")
    (property "ki_description" "SMD Multilayer Ceramic Capacitor, 10 µF, 10 V, 0603 [1608 Metric], ± 10%, X5R, GRM Series")
    (property "ki_keywords" "0603, SMT, CAPACITOR, PASSIVE, CERAMIC, MLCC")
    (attr smd)
    (fp_text reference "C41" (at 1.15 -0.2 90) (layer "F.SilkS")
        (effects (font (size 0.65 0.65) (thickness 0.13)) (justify right bottom))
    )
    (fp_text value "C_10u_0603" (at 0 1.6 90) (layer "F.Fab")
        (effects (font (size 0.65 0.65) (thickness 0.13)) (justify right bottom))
    )
    (fp_text user "License: Apache-2.0" (at -1.682 5.895 90) (layer "F.Fab") hide
        (effects (font (size 0.7 0.7) (thickness 0.15)) (justify right bottom))
    )
    (fp_text user "Author: Antmicro" (at -1.682 4.894 90) (layer "F.Fab") hide
        (effects (font (size 0.7 0.7) (thickness 0.15)) (justify right bottom))
    )
    (fp_text user "${REFERENCE}" (at -1.682 3.895 90) (layer "F.Fab") hide
        (effects (font (size 0.7 0.7) (thickness 0.15)) (justify right bottom))
    )
    (fp_line (start -0.15 -0.4) (end 0.15 -0.4)
      (stroke (width 0.15) (type solid)) (layer "F.SilkS"))
    (fp_line (start -0.15 0.4) (end 0.15 0.4)
      (stroke (width 0.15) (type solid)) (layer "F.SilkS"))
    (fp_rect (start -1.25 -0.65) (end 1.25 0.65)
      (stroke (width 0.05) (type solid)) (fill none) (layer "F.CrtYd"))
    (fp_rect (start -0.8 -0.4) (end 0.8 0.4)
      (stroke (width 0.15) (type solid)) (fill none) (layer "F.Fab"))
    (pad "1" smd roundrect (at -0.7 0 270) (size 0.8 1) (layers "F.Cu" "F.Paste" "F.Mask") (roundrect_rratio 0.2)
      (net 2 "GND") (pintype "passive"))
    (pad "2" smd roundrect (at 0.7 0 270) (size 0.8 1) (layers "F.Cu" "F.Paste" "F.Mask") (roundrect_rratio 0.2)
      (net 9 "+3V3") (pintype "passive"))
  )

  (footprint "antmicro-footprints:R_0402_1005Metric" (layer "F.Cu")
    (at 144.1 108.085 -90)
    (descr "Resistor SMD 0402")
    (tags "resistor SMD 0402")
    (property "Author" "Antmicro")
    (property "License" "Apache-2.0")
    (property "MPN" "CR0402-FX-1002GLF")
    (property "Manufacturer" "Bourns")
    (property "Public" "False")
    (property "Sheetfile" "channel1.kicad_sch")
    (property "Sheetname" "Channel 1")
    (property "Tolerance" "1%")
    (property "Val" "10k")
    (property "ki_description" "SMD Chip Resistor, 10 kohm, ± 1%, 62.5 mW, 0402 [1005 Metric], Thick Film, General Purpose")
    (property "ki_keywords" "0402, SMT, RESISTOR, PASSIVE")
    (attr smd)
    (fp_text reference "R10" (at -1.035 -1.66 -90) (layer "F.SilkS")
        (effects (font (size 0.65 0.65) (thickness 0.13)) (justify left bottom))
    )
    (fp_text value "R_10k_0402" (at 0 1.4 -90) (layer "F.Fab")
        (effects (font (size 0.65 0.65) (thickness 0.13)) (justify left bottom))
    )
    (fp_text user "License: Apache-2.0" (at -0.95 5.169 -90) (layer "F.Fab") hide
        (effects (font (size 0.7 0.7) (thickness 0.15)) (justify left bottom))
    )
    (fp_text user "Author: Antmicro" (at -0.95 4.169 -90) (layer "F.Fab") hide
        (effects (font (size 0.7 0.7) (thickness 0.15)) (justify left bottom))
    )
    (fp_text user "${REFERENCE}" (at -0.95 3.168 -90) (layer "F.Fab") hide
        (effects (font (size 0.7 0.7) (thickness 0.15)) (justify left bottom))
    )
    (fp_rect (start -0.925 -0.47) (end 0.925 0.47)
      (stroke (width 0.05) (type default)) (fill none) (layer "F.CrtYd"))
    (fp_rect (start -0.5 -0.25) (end 0.5 0.25)
      (stroke (width 0.15) (type solid)) (fill none) (layer "F.Fab"))
    (pad "1" smd roundrect (at -0.48 0 270) (size 0.59 0.64) (layers "F.Cu" "F.Paste" "F.Mask") (roundrect_rratio 0.25)
      (net 105 "/Channel 1/HDMI1_DDC_SCL_3V3") (pintype "passive"))
    (pad "2" smd roundrect (at 0.48 0 270) (size 0.59 0.64) (layers "F.Cu" "F.Paste" "F.Mask") (roundrect_rratio 0.25)
      (net 9 "+3V3") (pintype "passive"))
  )

  (footprint "antmicro-footprints:C_0603_1608Metric" (layer "F.Cu")
    (at 145.2 115.7 -90)
    (descr "Capacitor SMD 0603")
    (tags "capacitor 0603")
    (property "Author" "Antmicro")
    (property "Dielectric" "template_dielectric")
    (property "License" "Apache-2.0")
    (property "MPN" "GRM188R61A106KE69D")
    (property "Manufacturer" "Murata")
    (property "Public" "False")
    (property "Sheetfile" "channel1.kicad_sch")
    (property "Sheetname" "Channel 1")
    (property "Val" "10u")
    (property "Voltage" "")
    (property "ki_description" "SMD Multilayer Ceramic Capacitor, 10 µF, 10 V, 0603 [1608 Metric], ± 10%, X5R, GRM Series")
    (property "ki_keywords" "0603, SMT, CAPACITOR, PASSIVE, CERAMIC, MLCC")
    (attr smd)
    (fp_text reference "C20" (at -3.1 -0.3 90) (layer "F.SilkS")
        (effects (font (size 0.65 0.65) (thickness 0.13)) (justify right bottom))
    )
    (fp_text value "C_10u_0603" (at 0 1.6 90) (layer "F.Fab")
        (effects (font (size 0.65 0.65) (thickness 0.13)) (justify right bottom))
    )
    (fp_text user "Author: Antmicro" (at -1.682 4.894 90) (layer "F.Fab") hide
        (effects (font (size 0.7 0.7) (thickness 0.15)) (justify right bottom))
    )
    (fp_text user "License: Apache-2.0" (at -1.682 5.895 90) (layer "F.Fab") hide
        (effects (font (size 0.7 0.7) (thickness 0.15)) (justify right bottom))
    )
    (fp_text user "${REFERENCE}" (at -1.682 3.895 90) (layer "F.Fab") hide
        (effects (font (size 0.7 0.7) (thickness 0.15)) (justify right bottom))
    )
    (fp_line (start -0.15 -0.4) (end 0.15 -0.4)
      (stroke (width 0.15) (type solid)) (layer "F.SilkS"))
    (fp_line (start -0.15 0.4) (end 0.15 0.4)
      (stroke (width 0.15) (type solid)) (layer "F.SilkS"))
    (fp_rect (start -1.25 -0.65) (end 1.25 0.65)
      (stroke (width 0.05) (type solid)) (fill none) (layer "F.CrtYd"))
    (fp_rect (start -0.8 -0.4) (end 0.8 0.4)
      (stroke (width 0.15) (type solid)) (fill none) (layer "F.Fab"))
    (pad "1" smd roundrect (at -0.7 0 270) (size 0.8 1) (layers "F.Cu" "F.Paste" "F.Mask") (roundrect_rratio 0.2)
      (net 2 "GND") (pintype "passive"))
    (pad "2" smd roundrect (at 0.7 0 270) (size 0.8 1) (layers "F.Cu" "F.Paste" "F.Mask") (roundrect_rratio 0.2)
      (net 12 "CH1_1V2") (pintype "passive"))
  )

  (footprint "antmicro-footprints:SOT-23-5" (layer "F.Cu")
    (at 148.25 115.95 90)
    (property "Author" "Antmicro")
    (property "License" "Apache-2.0")
    (property "MPN" "TLV73325PDBVT")
    (property "Manufacturer" "Texas Instruments")
    (property "Sheetfile" "channel1.kicad_sch")
    (property "Sheetname" "Channel 1")
    (property "ki_description" "Linear voltage regulator")
    (property "ki_keywords" "SMT, PMIC, IC, LDO, LINEAR, VOLTAGE, REGULATOR")
    (attr smd)
    (fp_text reference "IC1" (at -0.81 2.73 90) (layer "F.SilkS")
        (effects (font (size 0.65 0.65) (thickness 0.13)) (justify left bottom))
    )
    (fp_text value "TLV73325PDBVT" (at 0.002 2.799 90) (layer "F.Fab")
        (effects (font (size 0.65 0.65) (thickness 0.13)) (justify left bottom))
    )
    (fp_text user "${REFERENCE}" (at -1.898 4.299 90) (layer "F.Fab") hide
        (effects (font (size 0.7 0.7) (thickness 0.15)) (justify left bottom))
    )
    (fp_text user "Author: Antmicro" (at -1.898 5.499 90) (layer "F.Fab") hide
        (effects (font (size 0.7 0.7) (thickness 0.15)) (justify left bottom))
    )
    (fp_text user "License: Apache-2.0" (at -1.898 6.7 90) (layer "F.Fab") hide
        (effects (font (size 0.7 0.7) (thickness 0.15)) (justify left bottom))
    )
    (fp_line (start -0.85 1.6) (end -0.85 1.301)
      (stroke (width 0.15) (type solid)) (layer "F.SilkS"))
    (fp_line (start -0.8 -1.6) (end -0.8 -1.3)
      (stroke (width 0.15) (type solid)) (layer "F.SilkS"))
    (fp_line (start -0.8 -1.6) (end -0.5 -1.6)
      (stroke (width 0.15) (type solid)) (layer "F.SilkS"))
    (fp_line (start -0.55 1.6) (end -0.85 1.6)
      (stroke (width 0.15) (type solid)) (layer "F.SilkS"))
    (fp_line (start 0.8 -1.6) (end 0.5 -1.6)
      (stroke (width 0.15) (type solid)) (layer "F.SilkS"))
    (fp_line (start 0.8 -1.3) (end 0.8 -1.6)
      (stroke (width 0.15) (type solid)) (layer "F.SilkS"))
    (fp_line (start 0.8 0.55) (end 0.8 -0.55)
      (stroke (width 0.15) (type solid)) (layer "F.SilkS"))
    (fp_line (start 0.8 1.3) (end 0.8 1.599)
      (stroke (width 0.15) (type solid)) (layer "F.SilkS"))
    (fp_line (start 0.8 1.599) (end 0.549 1.599)
      (stroke (width 0.15) (type solid)) (layer "F.SilkS"))
    (fp_circle (center -1.25 -1.5) (end -1.2 -1.5)
      (stroke (width 0.15) (type solid)) (fill solid) (layer "F.SilkS"))
    (fp_rect (start 1.9 -1.76) (end -1.9 1.75)
      (stroke (width 0.05) (type solid)) (fill none) (layer "F.CrtYd"))
    (fp_line (start -0.398 -1.526) (end -0.874 -1.05)
      (stroke (width 0.15) (type solid)) (layer "F.Fab"))
    (fp_rect (start 0.874 1.523) (end -0.873 -1.525)
      (stroke (width 0.15) (type solid)) (fill none) (layer "F.Fab"))
    (pad "1" smd rect (at -1.351 -0.951) (size 0.55 1) (layers "F.Cu" "F.Paste" "F.Mask")
      (net 9 "+3V3") (pinfunction "VIN") (pintype "power_in"))
    (pad "2" smd rect (at -1.351 0) (size 0.55 1) (layers "F.Cu" "F.Paste" "F.Mask")
      (net 2 "GND") (pinfunction "GND") (pintype "power_in"))
    (pad "3" smd rect (at -1.351 0.949) (size 0.55 1) (layers "F.Cu" "F.Paste" "F.Mask")
      (net 9 "+3V3") (pinfunction "EN") (pintype "input"))
    (pad "4" smd rect (at 1.35 0.949) (size 0.55 1) (layers "F.Cu" "F.Paste" "F.Mask")
      (net 99 "unconnected-(IC1-NC-Pad4)") (pinfunction "NC") (pintype "no_connect"))
    (pad "5" smd rect (at 1.35 -0.951) (size 0.55 1) (layers "F.Cu" "F.Paste" "F.Mask")
      (net 11 "CH1_2V5") (pinfunction "VOUT") (pintype "power_out"))
  )

  (footprint "antmicro-footprints:SOT1069-2" (layer "F.Cu")
    (at 165.6 103.85)
    (property "Author" "Antmicro")
    (property "License" "Apache-2.0")
    (property "MPN" "PCA9517ATP")
    (property "Manufacturer" "NXP")
    (property "Sheetfile" "channel2.kicad_sch")
    (property "Sheetname" "Channel 2")
    (property "ki_description" "Level Translating I2C-Bus Repeater, 2 Inputs, 0.9 V to 5.5 V Supply, 50 mA Out, HWSON-8")
    (property "ki_keywords" "SMT, LEVEL-SHIFTER, IC, I2C")
    (attr smd)
    (fp_text reference "U6" (at 0.08 -2.36 180) (layer "F.SilkS")
        (effects (font (size 0.7 0.7) (thickness 0.15)) (justify left bottom))
    )
    (fp_text value "PCA9517ATP" (at -2.54 3.4544) (layer "F.Fab")
        (effects (font (size 0.7 0.7) (thickness 0.15)) (justify left bottom))
    )
    (fp_text user "." (at -3.101 -1.101 unlocked) (layer "F.SilkS") hide
        (effects (font (size 0.7 0.7) (thickness 0.15)) (justify left bottom))
    )
    (fp_text user "${REFERENCE}" (at -4.375 3.499) (layer "F.Fab") hide
        (effects (font (size 0.7 0.7) (thickness 0.15)) (justify left bottom))
    )
    (fp_text user "License: Apache-2.0" (at -4.375 5.9) (layer "F.Fab") hide
        (effects (font (size 0.7 0.7) (thickness 0.15)) (justify left bottom))
    )
    (fp_text user "Author: Antmicro" (at -4.375 4.7) (layer "F.Fab") hide
        (effects (font (size 0.7 0.7) (thickness 0.15)) (justify left bottom))
    )
    (fp_line (start -1.375 -2.226) (end 1.375 -2.226)
      (stroke (width 0.15) (type solid)) (layer "F.SilkS"))
    (fp_line (start -1.375 1.425) (end -1.375 -2.226)
      (stroke (width 0.15) (type solid)) (layer "F.SilkS"))
    (fp_line (start -0.577 2.224) (end -1.375 1.425)
      (stroke (width 0.15) (type solid)) (layer "F.SilkS"))
    (fp_line (start 1.375 -2.226) (end 1.375 2.224)
      (stroke (width 0.15) (type solid)) (layer "F.SilkS"))
    (fp_line (start 1.375 2.224) (end -0.577 2.224)
      (stroke (width 0.15) (type solid)) (layer "F.SilkS"))
    (fp_circle (center -1.3208 2.0836) (end -1.2708 2.0836)
      (stroke (width 0.15) (type solid)) (fill solid) (layer "F.SilkS"))
    (fp_line (start -1.13 -2) (end 1.12 -2)
      (stroke (width 0.05) (type solid)) (layer "F.CrtYd"))
    (fp_line (start -1.13 1.98) (end -1.13 -2)
      (stroke (width 0.05) (type solid)) (layer "F.CrtYd"))
    (fp_line (start 1.12 -2) (end 1.12 1.98)
      (stroke (width 0.05) (type solid)) (layer "F.CrtYd"))
    (fp_line (start 1.12 1.98) (end -1.13 1.98)
      (stroke (width 0.05) (type solid)) (layer "F.CrtYd"))
    (pad "1" smd rect (at -0.75 1.411) (size 0.25 0.625) (layers "F.Cu" "F.Paste" "F.Mask")
      (net 9 "+3V3") (pinfunction "Vref1") (pintype "power_in"))
    (pad "2" smd rect (at -0.25 1.411) (size 0.25 0.625) (layers "F.Cu" "F.Paste" "F.Mask")
      (net 112 "/Channel 2/HDMI2_DDC_SCL_3V3") (pinfunction "SCL1") (pintype "input"))
    (pad "3" smd rect (at 0.25 1.411) (size 0.25 0.625) (layers "F.Cu" "F.Paste" "F.Mask")
      (net 111 "/Channel 2/HDMI2_DDC_SDA_3V3") (pinfunction "SDA1") (pintype "bidirectional"))
    (pad "4" smd rect (at 0.75 1.411) (size 0.25 0.625) (layers "F.Cu" "F.Paste" "F.Mask")
      (net 2 "GND") (pinfunction "GND") (pintype "power_in"))
    (pad "5" smd rect (at 0.75 -1.414) (size 0.25 0.625) (layers "F.Cu" "F.Paste" "F.Mask")
      (net 122 "Net-(U6-EN)") (pinfunction "EN") (pintype "input"))
    (pad "6" smd rect (at 0.25 -1.414) (size 0.25 0.625) (layers "F.Cu" "F.Paste" "F.Mask")
      (net 140 "/Channel 2/HDMI2_DDC_SDA") (pinfunction "SDA2") (pintype "bidirectional"))
    (pad "7" smd rect (at -0.25 -1.414) (size 0.25 0.625) (layers "F.Cu" "F.Paste" "F.Mask")
      (net 139 "/Channel 2/HDMI2_DDC_SCL") (pinfunction "SCL2") (pintype "input"))
    (pad "8" smd rect (at -0.75 -1.414) (size 0.25 0.625) (layers "F.Cu" "F.Paste" "F.Mask")
      (net 14 "+5V") (pinfunction "Vref2") (pintype "power_in"))
    (pad "9" smd roundrect (at 0 0) (size 1.6 1.6) (layers "F.Cu" "F.Paste" "F.Mask") (roundrect_rratio 0.05)
      (net 2 "GND") (pinfunction "GND") (pintype "passive") (solder_paste_margin -0.05))
  )

  (footprint "antmicro-footprints:C_0402_1005Metric" (layer "F.Cu")
    (at 147 110.25 90)
    (descr "Capacitor SMD 0402")
    (tags "capacitor SMD 0402")
    (property "Author" "Antmicro")
    (property "Dielectric" "X5R")
    (property "License" "Apache-2.0")
    (property "MPN" "GRM155R61H104KE14D")
    (property "Manufacturer" "Murata")
    (property "Public" "False")
    (property "Sheetfile" "channel2.kicad_sch")
    (property "Sheetname" "Channel 2")
    (property "Val" "100n")
    (property "Voltage" "50V")
    (property "ki_description" "SMD Multilayer Ceramic Capacitor, 0.1 µF, 50 V, 0402 [1005 Metric], ± 10%, X5R, GRM Series")
    (property "ki_keywords" "0402, SMT, CAPACITOR, PASSIVE, CERAMIC, MLCC")
    (attr smd)
    (fp_text reference "C38" (at -1.95 -1.5 90) (layer "F.SilkS")
        (effects (font (size 0.65 0.65) (thickness 0.13)) (justify left bottom))
    )
    (fp_text value "C_100n_0402" (at 0 1.4 90) (layer "F.Fab")
        (effects (font (size 0.65 0.65) (thickness 0.13)) (justify left bottom))
    )
    (fp_text user "License: Apache-2.0" (at -0.932 5.17 90) (layer "F.Fab") hide
        (effects (font (size 0.7 0.7) (thickness 0.15)) (justify left bottom))
    )
    (fp_text user "${REFERENCE}" (at -0.932 3.168 90) (layer "F.Fab") hide
        (effects (font (size 0.7 0.7) (thickness 0.15)) (justify left bottom))
    )
    (fp_text user "Author: Antmicro" (at -0.932 4.17 90) (layer "F.Fab") hide
        (effects (font (size 0.7 0.7) (thickness 0.15)) (justify left bottom))
    )
    (fp_rect (start -0.925 -0.47) (end 0.925 0.47)
      (stroke (width 0.05) (type default)) (fill none) (layer "F.CrtYd"))
    (fp_line (start -0.494 -0.25) (end 0.504 -0.25)
      (stroke (width 0.15) (type solid)) (layer "F.Fab"))
    (fp_line (start -0.494 0.248) (end -0.494 -0.25)
      (stroke (width 0.15) (type solid)) (layer "F.Fab"))
    (fp_line (start 0.504 -0.25) (end 0.504 0.248)
      (stroke (width 0.15) (type solid)) (layer "F.Fab"))
    (fp_line (start 0.504 0.248) (end -0.494 0.248)
      (stroke (width 0.15) (type solid)) (layer "F.Fab"))
    (pad "1" smd roundrect (at -0.48 0 90) (size 0.59 0.64) (layers "F.Cu" "F.Paste" "F.Mask") (roundrect_rratio 0.25)
      (net 2 "GND") (pintype "passive"))
    (pad "2" smd roundrect (at 0.48 0 90) (size 0.59 0.64) (layers "F.Cu" "F.Paste" "F.Mask") (roundrect_rratio 0.25)
      (net 30 "Net-(Y2-EN)") (pintype "passive"))
  )

  (footprint "antmicro-footprints:FB_0805_2012Metric" (layer "F.Cu")
    (at 142.5 115.5)
    (descr "FERRITE BEAD 0805")
    (tags "FERRITE BEAD 0805")
    (property "Author" "Antmicro")
    (property "Current" "")
    (property "License" "Apache-2.0")
    (property "MPN" "742792096")
    (property "Manufacturer" "Würth Elektronik")
    (property "Public" "False")
    (property "Sheetfile" "channel1.kicad_sch")
    (property "Sheetname" "Channel 1")
    (property "Val" "1kZ/0.8A")
    (property "ki_description" "Ferrite Beads WE-CBF 0805 100MHz 1kOhm 1A, High Current")
    (property "ki_keywords" "FERRITE BEAD, PASSIVE")
    (attr smd)
    (fp_text reference "FB4" (at -1.87 1.72) (layer "F.SilkS")
        (effects (font (size 0.65 0.65) (thickness 0.13)) (justify left bottom))
    )
    (fp_text value "FB_1kZ_0.8A_WE-CBF_0805" (at 0 1.8) (layer "F.Fab")
        (effects (font (size 0.65 0.65) (thickness 0.13)) (justify left bottom))
    )
    (fp_text user "Author: Antmicro" (at -1.9 4.4) (layer "F.Fab") hide
        (effects (font (size 0.7 0.7) (thickness 0.15)) (justify left bottom))
    )
    (fp_text user "License: Apache-2.0" (at -1.9 5.75) (layer "F.Fab") hide
        (effects (font (size 0.7 0.7) (thickness 0.15)) (justify left bottom))
    )
    (fp_text user "${REFERENCE}" (at -1.9 3.1) (layer "F.Fab") hide
        (effects (font (size 0.7 0.7) (thickness 0.15)) (justify left bottom))
    )
    (fp_line (start -0.319 0.698) (end 0.281 0.698)
      (stroke (width 0.15) (type solid)) (layer "F.SilkS"))
    (fp_line (start -0.299 -0.698) (end 0.299 -0.698)
      (stroke (width 0.15) (type solid)) (layer "F.SilkS"))
    (fp_rect (start 1.95 -0.9) (end -1.95 0.9)
      (stroke (width 0.05) (type default)) (fill none) (layer "F.CrtYd"))
    (fp_line (start -0.948 -0.681) (end 0.948 -0.681)
      (stroke (width 0.15) (type solid)) (layer "F.Fab"))
    (fp_line (start -0.948 -0.676) (end -0.948 0.676)
      (stroke (width 0.15) (type solid)) (layer "F.Fab"))
    (fp_line (start -0.948 0.681) (end 0.948 0.681)
      (stroke (width 0.15) (type solid)) (layer "F.Fab"))
    (fp_line (start 0.948 -0.676) (end 0.948 0.676)
      (stroke (width 0.15) (type solid)) (layer "F.Fab"))
    (pad "1" smd roundrect (at -1.1 0) (size 1.2 1.3) (layers "F.Cu" "F.Paste" "F.Mask") (roundrect_rratio 0.25)
      (net 7 "Net-(C10-Pad2)") (pintype "passive"))
    (pad "2" smd roundrect (at 1.1 0) (size 1.2 1.3) (layers "F.Cu" "F.Paste" "F.Mask") (roundrect_rratio 0.25)
      (net 12 "CH1_1V2") (pintype "passive"))
  )

  (footprint "antmicro-footprints:C_0402_1005Metric" (layer "F.Cu")
    (at 139.28 104.12 90)
    (descr "Capacitor SMD 0402")
    (tags "capacitor SMD 0402")
    (property "Author" "Antmicro")
    (property "Dielectric" "X5R")
    (property "License" "Apache-2.0")
    (property "MPN" "GRM155R61H104KE14D")
    (property "Manufacturer" "Murata")
    (property "Public" "False")
    (property "Sheetfile" "channel1.kicad_sch")
    (property "Sheetname" "Channel 1")
    (property "Val" "100n")
    (property "Voltage" "50V")
    (property "ki_description" "SMD Multilayer Ceramic Capacitor, 0.1 µF, 50 V, 0402 [1005 Metric], ± 10%, X5R, GRM Series")
    (property "ki_keywords" "0402, SMT, CAPACITOR, PASSIVE, CERAMIC, MLCC")
    (attr smd)
    (fp_text reference "C22" (at 5.02 -11.64 270) (layer "F.SilkS")
        (effects (font (size 0.65 0.65) (thickness 0.13)) (justify right bottom))
    )
    (fp_text value "C_100n_0402" (at 0 1.4 90) (layer "F.Fab")
        (effects (font (size 0.65 0.65) (thickness 0.13)) (justify left bottom))
    )
    (fp_text user "Author: Antmicro" (at -0.932 4.17 90) (layer "F.Fab") hide
        (effects (font (size 0.7 0.7) (thickness 0.15)) (justify left bottom))
    )
    (fp_text user "License: Apache-2.0" (at -0.932 5.17 90) (layer "F.Fab") hide
        (effects (font (size 0.7 0.7) (thickness 0.15)) (justify left bottom))
    )
    (fp_text user "${REFERENCE}" (at -0.932 3.168 90) (layer "F.Fab") hide
        (effects (font (size 0.7 0.7) (thickness 0.15)) (justify left bottom))
    )
    (fp_rect (start -0.925 -0.47) (end 0.925 0.47)
      (stroke (width 0.05) (type default)) (fill none) (layer "F.CrtYd"))
    (fp_line (start -0.494 -0.25) (end 0.504 -0.25)
      (stroke (width 0.15) (type solid)) (layer "F.Fab"))
    (fp_line (start -0.494 0.248) (end -0.494 -0.25)
      (stroke (width 0.15) (type solid)) (layer "F.Fab"))
    (fp_line (start 0.504 -0.25) (end 0.504 0.248)
      (stroke (width 0.15) (type solid)) (layer "F.Fab"))
    (fp_line (start 0.504 0.248) (end -0.494 0.248)
      (stroke (width 0.15) (type solid)) (layer "F.Fab"))
    (pad "1" smd roundrect (at -0.48 0 90) (size 0.59 0.64) (layers "F.Cu" "F.Paste" "F.Mask") (roundrect_rratio 0.25)
      (net 2 "GND") (pintype "passive"))
    (pad "2" smd roundrect (at 0.48 0 90) (size 0.59 0.64) (layers "F.Cu" "F.Paste" "F.Mask") (roundrect_rratio 0.25)
      (net 14 "+5V") (pintype "passive"))
  )

  (footprint "antmicro-footprints:C_0402_1005Metric" (layer "F.Cu")
    (at 131 110.4)
    (descr "Capacitor SMD 0402")
    (tags "capacitor SMD 0402")
    (property "Author" "Antmicro")
    (property "Dielectric" "X5R")
    (property "License" "Apache-2.0")
    (property "MPN" "GRM155R61H104KE14D")
    (property "Manufacturer" "Murata")
    (property "Public" "False")
    (property "Sheetfile" "channel1.kicad_sch")
    (property "Sheetname" "Channel 1")
    (property "Val" "100n")
    (property "Voltage" "50V")
    (property "ki_description" "SMD Multilayer Ceramic Capacitor, 0.1 µF, 50 V, 0402 [1005 Metric], ± 10%, X5R, GRM Series")
    (property "ki_keywords" "0402, SMT, CAPACITOR, PASSIVE, CERAMIC, MLCC")
    (attr smd)
    (fp_text reference "C28" (at -1.6 7.59) (layer "F.SilkS")
        (effects (font (size 0.65 0.65) (thickness 0.13)) (justify left bottom))
    )
    (fp_text value "C_100n_0402" (at 0 1.4) (layer "F.Fab")
        (effects (font (size 0.65 0.65) (thickness 0.13)) (justify left bottom))
    )
    (fp_text user "Author: Antmicro" (at -0.932 4.17) (layer "F.Fab") hide
        (effects (font (size 0.7 0.7) (thickness 0.15)) (justify left bottom))
    )
    (fp_text user "${REFERENCE}" (at -0.932 3.168) (layer "F.Fab") hide
        (effects (font (size 0.7 0.7) (thickness 0.15)) (justify left bottom))
    )
    (fp_text user "License: Apache-2.0" (at -0.932 5.17) (layer "F.Fab") hide
        (effects (font (size 0.7 0.7) (thickness 0.15)) (justify left bottom))
    )
    (fp_rect (start -0.925 -0.47) (end 0.925 0.47)
      (stroke (width 0.05) (type default)) (fill none) (layer "F.CrtYd"))
    (fp_line (start -0.494 -0.25) (end 0.504 -0.25)
      (stroke (width 0.15) (type solid)) (layer "F.Fab"))
    (fp_line (start -0.494 0.248) (end -0.494 -0.25)
      (stroke (width 0.15) (type solid)) (layer "F.Fab"))
    (fp_line (start 0.504 -0.25) (end 0.504 0.248)
      (stroke (width 0.15) (type solid)) (layer "F.Fab"))
    (fp_line (start 0.504 0.248) (end -0.494 0.248)
      (stroke (width 0.15) (type solid)) (layer "F.Fab"))
    (pad "1" smd roundrect (at -0.48 0) (size 0.59 0.64) (layers "F.Cu" "F.Paste" "F.Mask") (roundrect_rratio 0.25)
      (net 2 "GND") (pintype "passive"))
    (pad "2" smd roundrect (at 0.48 0) (size 0.59 0.64) (layers "F.Cu" "F.Paste" "F.Mask") (roundrect_rratio 0.25)
      (net 20 "Net-(U1B-VDDIO1)") (pintype "passive"))
  )

  (footprint "antmicro-footprints:C_0402_1005Metric" (layer "F.Cu")
    (at 147 105.45 -90)
    (descr "Capacitor SMD 0402")
    (tags "capacitor SMD 0402")
    (property "Author" "Antmicro")
    (property "Dielectric" "X5R")
    (property "License" "Apache-2.0")
    (property "MPN" "GRM155R61H104KE14D")
    (property "Manufacturer" "Murata")
    (property "Public" "False")
    (property "Sheetfile" "channel2.kicad_sch")
    (property "Sheetname" "Channel 2")
    (property "Val" "100n")
    (property "Voltage" "50V")
    (property "ki_description" "SMD Multilayer Ceramic Capacitor, 0.1 µF, 50 V, 0402 [1005 Metric], ± 10%, X5R, GRM Series")
    (property "ki_keywords" "0402, SMT, CAPACITOR, PASSIVE, CERAMIC, MLCC")
    (attr smd)
    (fp_text reference "C35" (at -1.15 -2.4 90) (layer "F.SilkS")
        (effects (font (size 0.65 0.65) (thickness 0.13)) (justify right bottom))
    )
    (fp_text value "C_100n_0402" (at 0 1.4 90) (layer "F.Fab")
        (effects (font (size 0.65 0.65) (thickness 0.13)) (justify right bottom))
    )
    (fp_text user "License: Apache-2.0" (at -0.932 5.17 90) (layer "F.Fab") hide
        (effects (font (size 0.7 0.7) (thickness 0.15)) (justify right bottom))
    )
    (fp_text user "${REFERENCE}" (at -0.932 3.168 90) (layer "F.Fab") hide
        (effects (font (size 0.7 0.7) (thickness 0.15)) (justify right bottom))
    )
    (fp_text user "Author: Antmicro" (at -0.932 4.17 90) (layer "F.Fab") hide
        (effects (font (size 0.7 0.7) (thickness 0.15)) (justify right bottom))
    )
    (fp_rect (start -0.925 -0.47) (end 0.925 0.47)
      (stroke (width 0.05) (type default)) (fill none) (layer "F.CrtYd"))
    (fp_line (start -0.494 -0.25) (end 0.504 -0.25)
      (stroke (width 0.15) (type solid)) (layer "F.Fab"))
    (fp_line (start -0.494 0.248) (end -0.494 -0.25)
      (stroke (width 0.15) (type solid)) (layer "F.Fab"))
    (fp_line (start 0.504 -0.25) (end 0.504 0.248)
      (stroke (width 0.15) (type solid)) (layer "F.Fab"))
    (fp_line (start 0.504 0.248) (end -0.494 0.248)
      (stroke (width 0.15) (type solid)) (layer "F.Fab"))
    (pad "1" smd roundrect (at -0.48 0 270) (size 0.59 0.64) (layers "F.Cu" "F.Paste" "F.Mask") (roundrect_rratio 0.25)
      (net 2 "GND") (pintype "passive"))
    (pad "2" smd roundrect (at 0.48 0 270) (size 0.59 0.64) (layers "F.Cu" "F.Paste" "F.Mask") (roundrect_rratio 0.25)
      (net 9 "+3V3") (pintype "passive"))
  )

  (footprint "antmicro-footprints:R_0603_1608Metric" (layer "F.Cu")
    (at 168.9 101.9)
    (descr "Resistor SMD 0603")
    (tags "resistor SMD 0603")
    (property "Author" "Antmicro")
    (property "Current" "1A")
    (property "License" "Apache-2.0")
    (property "MPN" "CR0603-J/-000ELF")
    (property "Manufacturer" "Bourns")
    (property "Public" "False")
    (property "Sheetfile" "channel2.kicad_sch")
    (property "Sheetname" "Channel 2")
    (property "Tolerance" "")
    (property "Val" "0R")
    (property "ki_description" "Zero Ohm Resistor, Jumper, 0603 [1608 Metric], Thick Film, 100 mW, 1 A, Surface Mount Device, CR")
    (property "ki_keywords" "0603, SMT, RESISTOR, PASSIVE")
    (attr smd)
    (fp_text reference "R14" (at 1 0.4) (layer "F.SilkS")
        (effects (font (size 0.7 0.7) (thickness 0.15)) (justify left bottom))
    )
    (fp_text value "R_0R_0603" (at 0 1.6) (layer "F.Fab")
        (effects (font (size 0.7 0.7) (thickness 0.15)) (justify left bottom))
    )
    (fp_text user "Author: Antmicro" (at -1.25 4.9) (layer "F.Fab") hide
        (effects (font (size 0.7 0.7) (thickness 0.15)) (justify left bottom))
    )
    (fp_text user "License: Apache-2.0" (at -1.25 5.9) (layer "F.Fab") hide
        (effects (font (size 0.7 0.7) (thickness 0.15)) (justify left bottom))
    )
    (fp_text user "${REFERENCE}" (at -1.25 3.898) (layer "F.Fab") hide
        (effects (font (size 0.7 0.7) (thickness 0.15)) (justify left bottom))
    )
    (fp_line (start -0.15 -0.4) (end 0.15 -0.4)
      (stroke (width 0.15) (type solid)) (layer "F.SilkS"))
    (fp_line (start -0.15 0.4) (end 0.15 0.4)
      (stroke (width 0.15) (type solid)) (layer "F.SilkS"))
    (fp_rect (start -1.25 -0.65) (end 1.25 0.65)
      (stroke (width 0.05) (type solid)) (fill none) (layer "F.CrtYd"))
    (fp_rect (start -0.8 -0.4) (end 0.8 0.4)
      (stroke (width 0.15) (type solid)) (fill none) (layer "F.Fab"))
    (pad "1" smd roundrect (at -0.7 0) (size 0.8 1) (layers "F.Cu" "F.Paste" "F.Mask") (roundrect_rratio 0.2)
      (net 96 "/Channel 2/HDMI2_POWER") (pintype "passive"))
    (pad "2" smd roundrect (at 0.7 0) (size 0.8 1) (layers "F.Cu" "F.Paste" "F.Mask") (roundrect_rratio 0.2)
      (net 141 "/Channel 2/HDMI2_HPD") (pintype "passive"))
  )

  (footprint "antmicro-footprints:C_0402_1005Metric" (layer "F.Cu")
    (at 163.79 111.84)
    (descr "Capacitor SMD 0402")
    (tags "capacitor SMD 0402")
    (property "Author" "Antmicro")
    (property "Dielectric" "")
    (property "License" "Apache-2.0")
    (property "MPN" "0402B471K250CT")
    (property "Manufacturer" "Walsin")
    (property "Public" "False")
    (property "Sheetfile" "channel2.kicad_sch")
    (property "Sheetname" "Channel 2")
    (property "Val" "470p")
    (property "Voltage" "")
    (property "ki_description" "SMD Multilayer Ceramic Capacitor, General Purpose, 470 pF, 25 V, 0402 [1005 Metric], ± 10%, X7R")
    (property "ki_keywords" "0402, SMT, CAPACITOR, PASSIVE, MLCC")
    (attr smd)
    (fp_text reference "C49" (at -3.69 6.96) (layer "F.SilkS")
        (effects (font (size 0.65 0.65) (thickness 0.13)) (justify left bottom))
    )
    (fp_text value "C_470p_0402" (at 0 1.4) (layer "F.Fab")
        (effects (font (size 0.65 0.65) (thickness 0.13)) (justify left bottom))
    )
    (fp_text user "License: Apache-2.0" (at -0.932 5.17) (layer "F.Fab") hide
        (effects (font (size 0.7 0.7) (thickness 0.15)) (justify left bottom))
    )
    (fp_text user "Author: Antmicro" (at -0.932 4.17) (layer "F.Fab") hide
        (effects (font (size 0.7 0.7) (thickness 0.15)) (justify left bottom))
    )
    (fp_text user "${REFERENCE}" (at -0.932 3.168) (layer "F.Fab") hide
        (effects (font (size 0.7 0.7) (thickness 0.15)) (justify left bottom))
    )
    (fp_rect (start -0.925 -0.47) (end 0.925 0.47)
      (stroke (width 0.05) (type default)) (fill none) (layer "F.CrtYd"))
    (fp_line (start -0.494 -0.25) (end 0.504 -0.25)
      (stroke (width 0.15) (type solid)) (layer "F.Fab"))
    (fp_line (start -0.494 0.248) (end -0.494 -0.25)
      (stroke (width 0.15) (type solid)) (layer "F.Fab"))
    (fp_line (start 0.504 -0.25) (end 0.504 0.248)
      (stroke (width 0.15) (type solid)) (layer "F.Fab"))
    (fp_line (start 0.504 0.248) (end -0.494 0.248)
      (stroke (width 0.15) (type solid)) (layer "F.Fab"))
    (pad "1" smd roundrect (at -0.48 0) (size 0.59 0.64) (layers "F.Cu" "F.Paste" "F.Mask") (roundrect_rratio 0.25)
      (net 110 "Net-(C49-Pad1)") (pintype "passive"))
    (pad "2" smd roundrect (at 0.48 0) (size 0.59 0.64) (layers "F.Cu" "F.Paste" "F.Mask") (roundrect_rratio 0.25)
      (net 2 "GND") (pintype "passive"))
  )

  (footprint "antmicro-footprints:C_0603_1608Metric" (layer "F.Cu")
    (at 141.3 119.9 -90)
    (descr "Capacitor SMD 0603")
    (tags "capacitor 0603")
    (property "Author" "Antmicro")
    (property "Dielectric" "template_dielectric")
    (property "License" "Apache-2.0")
    (property "MPN" "GRM188R61A106KE69D")
    (property "Manufacturer" "Murata")
    (property "Public" "False")
    (property "Sheetfile" "channel1.kicad_sch")
    (property "Sheetname" "Channel 1")
    (property "Val" "10u")
    (property "Voltage" "")
    (property "ki_description" "SMD Multilayer Ceramic Capacitor, 10 µF, 10 V, 0603 [1608 Metric], ± 10%, X5R, GRM Series")
    (property "ki_keywords" "0603, SMT, CAPACITOR, PASSIVE, CERAMIC, MLCC")
    (attr smd)
    (fp_text reference "C18" (at -1 0.6 90) (layer "F.SilkS")
        (effects (font (size 0.65 0.65) (thickness 0.13)) (justify right bottom))
    )
    (fp_text value "C_10u_0603" (at 0 1.6 90) (layer "F.Fab")
        (effects (font (size 0.65 0.65) (thickness 0.13)) (justify right bottom))
    )
    (fp_text user "License: Apache-2.0" (at -1.682 5.895 90) (layer "F.Fab") hide
        (effects (font (size 0.7 0.7) (thickness 0.15)) (justify right bottom))
    )
    (fp_text user "Author: Antmicro" (at -1.682 4.894 90) (layer "F.Fab") hide
        (effects (font (size 0.7 0.7) (thickness 0.15)) (justify right bottom))
    )
    (fp_text user "${REFERENCE}" (at -1.682 3.895 90) (layer "F.Fab") hide
        (effects (font (size 0.7 0.7) (thickness 0.15)) (justify right bottom))
    )
    (fp_line (start -0.15 -0.4) (end 0.15 -0.4)
      (stroke (width 0.15) (type solid)) (layer "F.SilkS"))
    (fp_line (start -0.15 0.4) (end 0.15 0.4)
      (stroke (width 0.15) (type solid)) (layer "F.SilkS"))
    (fp_rect (start -1.25 -0.65) (end 1.25 0.65)
      (stroke (width 0.05) (type solid)) (fill none) (layer "F.CrtYd"))
    (fp_rect (start -0.8 -0.4) (end 0.8 0.4)
      (stroke (width 0.15) (type solid)) (fill none) (layer "F.Fab"))
    (pad "1" smd roundrect (at -0.7 0 270) (size 0.8 1) (layers "F.Cu" "F.Paste" "F.Mask") (roundrect_rratio 0.2)
      (net 2 "GND") (pintype "passive"))
    (pad "2" smd roundrect (at 0.7 0 270) (size 0.8 1) (layers "F.Cu" "F.Paste" "F.Mask") (roundrect_rratio 0.2)
      (net 9 "+3V3") (pintype "passive"))
  )

  (footprint "antmicro-footprints:C_0402_1005Metric" (layer "F.Cu")
    (at 139.8 111.8)
    (descr "Capacitor SMD 0402")
    (tags "capacitor SMD 0402")
    (property "Author" "Antmicro")
    (property "Dielectric" "")
    (property "License" "Apache-2.0")
    (property "MPN" "0402B471K250CT")
    (property "Manufacturer" "Walsin")
    (property "Public" "False")
    (property "Sheetfile" "channel1.kicad_sch")
    (property "Sheetname" "Channel 1")
    (property "Val" "470p")
    (property "Voltage" "")
    (property "ki_description" "SMD Multilayer Ceramic Capacitor, General Purpose, 470 pF, 25 V, 0402 [1005 Metric], ± 10%, X7R")
    (property "ki_keywords" "0402, SMT, CAPACITOR, PASSIVE, MLCC")
    (attr smd)
    (fp_text reference "C6" (at -3.7 5.7) (layer "F.SilkS")
        (effects (font (size 0.65 0.65) (thickness 0.13)) (justify left bottom))
    )
    (fp_text value "C_470p_0402" (at 0 1.4) (layer "F.Fab")
        (effects (font (size 0.65 0.65) (thickness 0.13)) (justify left bottom))
    )
    (fp_text user "License: Apache-2.0" (at -0.932 5.17) (layer "F.Fab") hide
        (effects (font (size 0.7 0.7) (thickness 0.15)) (justify left bottom))
    )
    (fp_text user "Author: Antmicro" (at -0.932 4.17) (layer "F.Fab") hide
        (effects (font (size 0.7 0.7) (thickness 0.15)) (justify left bottom))
    )
    (fp_text user "${REFERENCE}" (at -0.932 3.168) (layer "F.Fab") hide
        (effects (font (size 0.7 0.7) (thickness 0.15)) (justify left bottom))
    )
    (fp_rect (start -0.925 -0.47) (end 0.925 0.47)
      (stroke (width 0.05) (type default)) (fill none) (layer "F.CrtYd"))
    (fp_line (start -0.494 -0.25) (end 0.504 -0.25)
      (stroke (width 0.15) (type solid)) (layer "F.Fab"))
    (fp_line (start -0.494 0.248) (end -0.494 -0.25)
      (stroke (width 0.15) (type solid)) (layer "F.Fab"))
    (fp_line (start 0.504 -0.25) (end 0.504 0.248)
      (stroke (width 0.15) (type solid)) (layer "F.Fab"))
    (fp_line (start 0.504 0.248) (end -0.494 0.248)
      (stroke (width 0.15) (type solid)) (layer "F.Fab"))
    (pad "1" smd roundrect (at -0.48 0) (size 0.59 0.64) (layers "F.Cu" "F.Paste" "F.Mask") (roundrect_rratio 0.25)
      (net 7 "Net-(C10-Pad2)") (pintype "passive"))
    (pad "2" smd roundrect (at 0.48 0) (size 0.59 0.64) (layers "F.Cu" "F.Paste" "F.Mask") (roundrect_rratio 0.25)
      (net 2 "GND") (pintype "passive"))
  )

  (footprint "antmicro-footprints:C_0402_1005Metric" (layer "F.Cu")
    (at 139.8 110.8)
    (descr "Capacitor SMD 0402")
    (tags "capacitor SMD 0402")
    (property "Author" "Antmicro")
    (property "Dielectric" "")
    (property "License" "Apache-2.0")
    (property "MPN" "0402B471K250CT")
    (property "Manufacturer" "Walsin")
    (property "Public" "False")
    (property "Sheetfile" "channel1.kicad_sch")
    (property "Sheetname" "Channel 1")
    (property "Val" "470p")
    (property "Voltage" "")
    (property "ki_description" "SMD Multilayer Ceramic Capacitor, General Purpose, 470 pF, 25 V, 0402 [1005 Metric], ± 10%, X7R")
    (property "ki_keywords" "0402, SMT, CAPACITOR, PASSIVE, MLCC")
    (attr smd)
    (fp_text reference "C4" (at -3.7 5.7) (layer "F.SilkS")
        (effects (font (size 0.65 0.65) (thickness 0.13)) (justify left bottom))
    )
    (fp_text value "C_470p_0402" (at 0 1.4) (layer "F.Fab")
        (effects (font (size 0.65 0.65) (thickness 0.13)) (justify left bottom))
    )
    (fp_text user "${REFERENCE}" (at -0.932 3.168) (layer "F.Fab") hide
        (effects (font (size 0.7 0.7) (thickness 0.15)) (justify left bottom))
    )
    (fp_text user "License: Apache-2.0" (at -0.932 5.17) (layer "F.Fab") hide
        (effects (font (size 0.7 0.7) (thickness 0.15)) (justify left bottom))
    )
    (fp_text user "Author: Antmicro" (at -0.932 4.17) (layer "F.Fab") hide
        (effects (font (size 0.7 0.7) (thickness 0.15)) (justify left bottom))
    )
    (fp_rect (start -0.925 -0.47) (end 0.925 0.47)
      (stroke (width 0.05) (type default)) (fill none) (layer "F.CrtYd"))
    (fp_line (start -0.494 -0.25) (end 0.504 -0.25)
      (stroke (width 0.15) (type solid)) (layer "F.Fab"))
    (fp_line (start -0.494 0.248) (end -0.494 -0.25)
      (stroke (width 0.15) (type solid)) (layer "F.Fab"))
    (fp_line (start 0.504 -0.25) (end 0.504 0.248)
      (stroke (width 0.15) (type solid)) (layer "F.Fab"))
    (fp_line (start 0.504 0.248) (end -0.494 0.248)
      (stroke (width 0.15) (type solid)) (layer "F.Fab"))
    (pad "1" smd roundrect (at -0.48 0) (size 0.59 0.64) (layers "F.Cu" "F.Paste" "F.Mask") (roundrect_rratio 0.25)
      (net 5 "Net-(U1B-AVDD25)") (pintype "passive"))
    (pad "2" smd roundrect (at 0.48 0) (size 0.59 0.64) (layers "F.Cu" "F.Paste" "F.Mask") (roundrect_rratio 0.25)
      (net 2 "GND") (pintype "passive"))
  )

  (footprint "antmicro-footprints:C_0402_1005Metric" (layer "F.Cu")
    (at 148.01 110.25 90)
    (descr "Capacitor SMD 0402")
    (tags "capacitor SMD 0402")
    (property "Author" "Antmicro")
    (property "Dielectric" "C0G")
    (property "License" "Apache-2.0")
    (property "MPN" "C0402C470J5GACTU")
    (property "Manufacturer" "KEMET")
    (property "Public" "False")
    (property "Sheetfile" "channel2.kicad_sch")
    (property "Sheetname" "Channel 2")
    (property "Val" "47p")
    (property "Voltage" "")
    (property "ki_description" "SMD Multilayer Ceramic Capacitor, 47 pF, 50 V, 0402 [1005 Metric], ± 5%, C0G / NP0, C Series KEMET")
    (property "ki_keywords" "0402, SMT, CAPACITOR, PASSIVE, CERAMIC, MLCC")
    (attr smd)
    (fp_text reference "C39" (at 0.05 -1.51 90) (layer "F.SilkS")
        (effects (font (size 0.65 0.65) (thickness 0.13)) (justify right bottom))
    )
    (fp_text value "C_47p_0402" (at 0 1.4 90) (layer "F.Fab")
        (effects (font (size 0.65 0.65) (thickness 0.13)) (justify left bottom))
    )
    (fp_text user "Author: Antmicro" (at -0.932 4.17 90) (layer "F.Fab") hide
        (effects (font (size 0.7 0.7) (thickness 0.15)) (justify left bottom))
    )
    (fp_text user "${REFERENCE}" (at -0.932 3.168 90) (layer "F.Fab") hide
        (effects (font (size 0.7 0.7) (thickness 0.15)) (justify left bottom))
    )
    (fp_text user "License: Apache-2.0" (at -0.932 5.17 90) (layer "F.Fab") hide
        (effects (font (size 0.7 0.7) (thickness 0.15)) (justify left bottom))
    )
    (fp_rect (start -0.925 -0.47) (end 0.925 0.47)
      (stroke (width 0.05) (type default)) (fill none) (layer "F.CrtYd"))
    (fp_line (start -0.494 -0.25) (end 0.504 -0.25)
      (stroke (width 0.15) (type solid)) (layer "F.Fab"))
    (fp_line (start -0.494 0.248) (end -0.494 -0.25)
      (stroke (width 0.15) (type solid)) (layer "F.Fab"))
    (fp_line (start 0.504 -0.25) (end 0.504 0.248)
      (stroke (width 0.15) (type solid)) (layer "F.Fab"))
    (fp_line (start 0.504 0.248) (end -0.494 0.248)
      (stroke (width 0.15) (type solid)) (layer "F.Fab"))
    (pad "1" smd roundrect (at -0.48 0 90) (size 0.59 0.64) (layers "F.Cu" "F.Paste" "F.Mask") (roundrect_rratio 0.25)
      (net 2 "GND") (pintype "passive"))
    (pad "2" smd roundrect (at 0.48 0 90) (size 0.59 0.64) (layers "F.Cu" "F.Paste" "F.Mask") (roundrect_rratio 0.25)
      (net 30 "Net-(Y2-EN)") (pintype "passive"))
  )

  (footprint "antmicro-footprints:C_0402_1005Metric" (layer "F.Cu")
    (at 124 105.4 -90)
    (descr "Capacitor SMD 0402")
    (tags "capacitor SMD 0402")
    (property "Author" "Antmicro")
    (property "Dielectric" "X5R")
    (property "License" "Apache-2.0")
    (property "MPN" "GRM155R61H104KE14D")
    (property "Manufacturer" "Murata")
    (property "Public" "False")
    (property "Sheetfile" "channel1.kicad_sch")
    (property "Sheetname" "Channel 1")
    (property "Val" "100n")
    (property "Voltage" "50V")
    (property "ki_description" "SMD Multilayer Ceramic Capacitor, 0.1 µF, 50 V, 0402 [1005 Metric], ± 10%, X5R, GRM Series")
    (property "ki_keywords" "0402, SMT, CAPACITOR, PASSIVE, CERAMIC, MLCC")
    (attr smd)
    (fp_text reference "C12" (at -3 -0.4 90) (layer "F.SilkS")
        (effects (font (size 0.65 0.65) (thickness 0.13)) (justify right bottom))
    )
    (fp_text value "C_100n_0402" (at 0 1.4 90) (layer "F.Fab")
        (effects (font (size 0.65 0.65) (thickness 0.13)) (justify right bottom))
    )
    (fp_text user "${REFERENCE}" (at -0.932 3.168 90) (layer "F.Fab") hide
        (effects (font (size 0.7 0.7) (thickness 0.15)) (justify right bottom))
    )
    (fp_text user "License: Apache-2.0" (at -0.932 5.17 90) (layer "F.Fab") hide
        (effects (font (size 0.7 0.7) (thickness 0.15)) (justify right bottom))
    )
    (fp_text user "Author: Antmicro" (at -0.932 4.17 90) (layer "F.Fab") hide
        (effects (font (size 0.7 0.7) (thickness 0.15)) (justify right bottom))
    )
    (fp_rect (start -0.925 -0.47) (end 0.925 0.47)
      (stroke (width 0.05) (type default)) (fill none) (layer "F.CrtYd"))
    (fp_line (start -0.494 -0.25) (end 0.504 -0.25)
      (stroke (width 0.15) (type solid)) (layer "F.Fab"))
    (fp_line (start -0.494 0.248) (end -0.494 -0.25)
      (stroke (width 0.15) (type solid)) (layer "F.Fab"))
    (fp_line (start 0.504 -0.25) (end 0.504 0.248)
      (stroke (width 0.15) (type solid)) (layer "F.Fab"))
    (fp_line (start 0.504 0.248) (end -0.494 0.248)
      (stroke (width 0.15) (type solid)) (layer "F.Fab"))
    (pad "1" smd roundrect (at -0.48 0 270) (size 0.59 0.64) (layers "F.Cu" "F.Paste" "F.Mask") (roundrect_rratio 0.25)
      (net 2 "GND") (pintype "passive"))
    (pad "2" smd roundrect (at 0.48 0 270) (size 0.59 0.64) (layers "F.Cu" "F.Paste" "F.Mask") (roundrect_rratio 0.25)
      (net 9 "+3V3") (pintype "passive"))
  )

  (footprint "antmicro-footprints:C_0402_1005Metric" (layer "F.Cu")
    (at 131 113.4)
    (descr "Capacitor SMD 0402")
    (tags "capacitor SMD 0402")
    (property "Author" "Antmicro")
    (property "Dielectric" "X5R")
    (property "License" "Apache-2.0")
    (property "MPN" "GRM155R61H104KE14D")
    (property "Manufacturer" "Murata")
    (property "Public" "False")
    (property "Sheetfile" "channel1.kicad_sch")
    (property "Sheetname" "Channel 1")
    (property "Val" "100n")
    (property "Voltage" "50V")
    (property "ki_description" "SMD Multilayer Ceramic Capacitor, 0.1 µF, 50 V, 0402 [1005 Metric], ± 10%, X5R, GRM Series")
    (property "ki_keywords" "0402, SMT, CAPACITOR, PASSIVE, CERAMIC, MLCC")
    (attr smd)
    (fp_text reference "C29" (at -1.6 7.6) (layer "F.SilkS")
        (effects (font (size 0.65 0.65) (thickness 0.13)) (justify left bottom))
    )
    (fp_text value "C_100n_0402" (at 0 1.4) (layer "F.Fab")
        (effects (font (size 0.65 0.65) (thickness 0.13)) (justify left bottom))
    )
    (fp_text user "License: Apache-2.0" (at -0.932 5.17) (layer "F.Fab") hide
        (effects (font (size 0.7 0.7) (thickness 0.15)) (justify left bottom))
    )
    (fp_text user "Author: Antmicro" (at -0.932 4.17) (layer "F.Fab") hide
        (effects (font (size 0.7 0.7) (thickness 0.15)) (justify left bottom))
    )
    (fp_text user "${REFERENCE}" (at -0.932 3.168) (layer "F.Fab") hide
        (effects (font (size 0.7 0.7) (thickness 0.15)) (justify left bottom))
    )
    (fp_rect (start -0.925 -0.47) (end 0.925 0.47)
      (stroke (width 0.05) (type default)) (fill none) (layer "F.CrtYd"))
    (fp_line (start -0.494 -0.25) (end 0.504 -0.25)
      (stroke (width 0.15) (type solid)) (layer "F.Fab"))
    (fp_line (start -0.494 0.248) (end -0.494 -0.25)
      (stroke (width 0.15) (type solid)) (layer "F.Fab"))
    (fp_line (start 0.504 -0.25) (end 0.504 0.248)
      (stroke (width 0.15) (type solid)) (layer "F.Fab"))
    (fp_line (start 0.504 0.248) (end -0.494 0.248)
      (stroke (width 0.15) (type solid)) (layer "F.Fab"))
    (pad "1" smd roundrect (at -0.48 0) (size 0.59 0.64) (layers "F.Cu" "F.Paste" "F.Mask") (roundrect_rratio 0.25)
      (net 2 "GND") (pintype "passive"))
    (pad "2" smd roundrect (at 0.48 0) (size 0.59 0.64) (layers "F.Cu" "F.Paste" "F.Mask") (roundrect_rratio 0.25)
      (net 21 "Net-(U1B-VDDIO2)") (pintype "passive"))
  )

  (footprint "antmicro-footprints:C_0402_1005Metric" (layer "F.Cu")
    (at 153.6 111.855 90)
    (descr "Capacitor SMD 0402")
    (tags "capacitor SMD 0402")
    (property "Author" "Antmicro")
    (property "Dielectric" "C0G")
    (property "License" "Apache-2.0")
    (property "MPN" "C0402C470J5GACTU")
    (property "Manufacturer" "KEMET")
    (property "Public" "False")
    (property "Sheetfile" "channel2.kicad_sch")
    (property "Sheetname" "Channel 2")
    (property "Val" "47p")
    (property "Voltage" "")
    (property "ki_description" "SMD Multilayer Ceramic Capacitor, 47 pF, 50 V, 0402 [1005 Metric], ± 5%, C0G / NP0, C Series KEMET")
    (property "ki_keywords" "0402, SMT, CAPACITOR, PASSIVE, CERAMIC, MLCC")
    (attr smd)
    (fp_text reference "C44" (at 0.855 0.2 270) (layer "F.SilkS")
        (effects (font (size 0.65 0.65) (thickness 0.13)) (justify left bottom))
    )
    (fp_text value "C_47p_0402" (at 0 1.4 90) (layer "F.Fab")
        (effects (font (size 0.65 0.65) (thickness 0.13)) (justify left bottom))
    )
    (fp_text user "${REFERENCE}" (at -0.932 3.168 90) (layer "F.Fab") hide
        (effects (font (size 0.7 0.7) (thickness 0.15)) (justify left bottom))
    )
    (fp_text user "Author: Antmicro" (at -0.932 4.17 90) (layer "F.Fab") hide
        (effects (font (size 0.7 0.7) (thickness 0.15)) (justify left bottom))
    )
    (fp_text user "License: Apache-2.0" (at -0.932 5.17 90) (layer "F.Fab") hide
        (effects (font (size 0.7 0.7) (thickness 0.15)) (justify left bottom))
    )
    (fp_rect (start -0.925 -0.47) (end 0.925 0.47)
      (stroke (width 0.05) (type default)) (fill none) (layer "F.CrtYd"))
    (fp_line (start -0.494 -0.25) (end 0.504 -0.25)
      (stroke (width 0.15) (type solid)) (layer "F.Fab"))
    (fp_line (start -0.494 0.248) (end -0.494 -0.25)
      (stroke (width 0.15) (type solid)) (layer "F.Fab"))
    (fp_line (start 0.504 -0.25) (end 0.504 0.248)
      (stroke (width 0.15) (type solid)) (layer "F.Fab"))
    (fp_line (start 0.504 0.248) (end -0.494 0.248)
      (stroke (width 0.15) (type solid)) (layer "F.Fab"))
    (pad "1" smd roundrect (at -0.48 0 90) (size 0.59 0.64) (layers "F.Cu" "F.Paste" "F.Mask") (roundrect_rratio 0.25)
      (net 2 "GND") (pintype "passive"))
    (pad "2" smd roundrect (at 0.48 0 90) (size 0.59 0.64) (layers "F.Cu" "F.Paste" "F.Mask") (roundrect_rratio 0.25)
      (net 31 "Net-(Y2-OUT)") (pintype "passive"))
  )

  (footprint "antmicro-footprints:FB_0805_2012Metric" (layer "F.Cu")
    (at 153.4 105.45 180)
    (descr "FERRITE BEAD 0805")
    (tags "FERRITE BEAD 0805")
    (property "Author" "Antmicro")
    (property "Current" "")
    (property "License" "Apache-2.0")
    (property "MPN" "742792096")
    (property "Manufacturer" "Würth Elektronik")
    (property "Public" "False")
    (property "Sheetfile" "channel2.kicad_sch")
    (property "Sheetname" "Channel 2")
    (property "Val" "1kZ/0.8A")
    (property "ki_description" "Ferrite Beads WE-CBF 0805 100MHz 1kOhm 1A, High Current")
    (property "ki_keywords" "FERRITE BEAD, PASSIVE")
    (attr smd)
    (fp_text reference "FB11" (at 1.24 1.12 180) (layer "F.SilkS")
        (effects (font (size 0.65 0.65) (thickness 0.13)) (justify left bottom))
    )
    (fp_text value "FB_1kZ_0.8A_WE-CBF_0805" (at 0 1.8 180) (layer "F.Fab")
        (effects (font (size 0.65 0.65) (thickness 0.13)) (justify left bottom))
    )
    (fp_text user "Author: Antmicro" (at -1.9 4.4 180) (layer "F.Fab") hide
        (effects (font (size 0.7 0.7) (thickness 0.15)) (justify left bottom))
    )
    (fp_text user "License: Apache-2.0" (at -1.9 5.75 180) (layer "F.Fab") hide
        (effects (font (size 0.7 0.7) (thickness 0.15)) (justify left bottom))
    )
    (fp_text user "${REFERENCE}" (at -1.9 3.1 180) (layer "F.Fab") hide
        (effects (font (size 0.7 0.7) (thickness 0.15)) (justify left bottom))
    )
    (fp_line (start -0.319 0.698) (end 0.281 0.698)
      (stroke (width 0.15) (type solid)) (layer "F.SilkS"))
    (fp_line (start -0.299 -0.698) (end 0.299 -0.698)
      (stroke (width 0.15) (type solid)) (layer "F.SilkS"))
    (fp_rect (start 1.95 -0.9) (end -1.95 0.9)
      (stroke (width 0.05) (type default)) (fill none) (layer "F.CrtYd"))
    (fp_line (start -0.948 -0.681) (end 0.948 -0.681)
      (stroke (width 0.15) (type solid)) (layer "F.Fab"))
    (fp_line (start -0.948 -0.676) (end -0.948 0.676)
      (stroke (width 0.15) (type solid)) (layer "F.Fab"))
    (fp_line (start -0.948 0.681) (end 0.948 0.681)
      (stroke (width 0.15) (type solid)) (layer "F.Fab"))
    (fp_line (start 0.948 -0.676) (end 0.948 0.676)
      (stroke (width 0.15) (type solid)) (layer "F.Fab"))
    (pad "1" smd roundrect (at -1.1 0 180) (size 1.2 1.3) (layers "F.Cu" "F.Paste" "F.Mask") (roundrect_rratio 0.25)
      (net 33 "Net-(U4B-VDDC1)") (pintype "passive"))
    (pad "2" smd roundrect (at 1.1 0 180) (size 1.2 1.3) (layers "F.Cu" "F.Paste" "F.Mask") (roundrect_rratio 0.25)
      (net 25 "CH2_1V2") (pintype "passive"))
  )

  (footprint "antmicro-footprints:C_0402_1005Metric" (layer "F.Cu")
    (at 131 109.4)
    (descr "Capacitor SMD 0402")
    (tags "capacitor SMD 0402")
    (property "Author" "Antmicro")
    (property "Dielectric" "X5R")
    (property "License" "Apache-2.0")
    (property "MPN" "GRM155R61H104KE14D")
    (property "Manufacturer" "Murata")
    (property "Public" "False")
    (property "Sheetfile" "channel1.kicad_sch")
    (property "Sheetname" "Channel 1")
    (property "Val" "100n")
    (property "Voltage" "50V")
    (property "ki_description" "SMD Multilayer Ceramic Capacitor, 0.1 µF, 50 V, 0402 [1005 Metric], ± 10%, X5R, GRM Series")
    (property "ki_keywords" "0402, SMT, CAPACITOR, PASSIVE, CERAMIC, MLCC")
    (attr smd)
    (fp_text reference "C30" (at -1.6 7.6) (layer "F.SilkS")
        (effects (font (size 0.65 0.65) (thickness 0.13)) (justify left bottom))
    )
    (fp_text value "C_100n_0402" (at 0 1.4) (layer "F.Fab")
        (effects (font (size 0.65 0.65) (thickness 0.13)) (justify left bottom))
    )
    (fp_text user "Author: Antmicro" (at -0.932 4.17) (layer "F.Fab") hide
        (effects (font (size 0.7 0.7) (thickness 0.15)) (justify left bottom))
    )
    (fp_text user "License: Apache-2.0" (at -0.932 5.17) (layer "F.Fab") hide
        (effects (font (size 0.7 0.7) (thickness 0.15)) (justify left bottom))
    )
    (fp_text user "${REFERENCE}" (at -0.932 3.168) (layer "F.Fab") hide
        (effects (font (size 0.7 0.7) (thickness 0.15)) (justify left bottom))
    )
    (fp_rect (start -0.925 -0.47) (end 0.925 0.47)
      (stroke (width 0.05) (type default)) (fill none) (layer "F.CrtYd"))
    (fp_line (start -0.494 -0.25) (end 0.504 -0.25)
      (stroke (width 0.15) (type solid)) (layer "F.Fab"))
    (fp_line (start -0.494 0.248) (end -0.494 -0.25)
      (stroke (width 0.15) (type solid)) (layer "F.Fab"))
    (fp_line (start 0.504 -0.25) (end 0.504 0.248)
      (stroke (width 0.15) (type solid)) (layer "F.Fab"))
    (fp_line (start 0.504 0.248) (end -0.494 0.248)
      (stroke (width 0.15) (type solid)) (layer "F.Fab"))
    (pad "1" smd roundrect (at -0.48 0) (size 0.59 0.64) (layers "F.Cu" "F.Paste" "F.Mask") (roundrect_rratio 0.25)
      (net 2 "GND") (pintype "passive"))
    (pad "2" smd roundrect (at 0.48 0) (size 0.59 0.64) (layers "F.Cu" "F.Paste" "F.Mask") (roundrect_rratio 0.25)
      (net 100 "/Channel 1/CH1_AVDD33") (pintype "passive"))
  )

  (footprint "antmicro-footprints:C_0402_1005Metric" (layer "F.Cu")
    (at 148 105.45 -90)
    (descr "Capacitor SMD 0402")
    (tags "capacitor SMD 0402")
    (property "Author" "Antmicro")
    (property "Dielectric" "C0G")
    (property "License" "Apache-2.0")
    (property "MPN" "C0402C470J5GACTU")
    (property "Manufacturer" "KEMET")
    (property "Public" "False")
    (property "Sheetfile" "channel2.kicad_sch")
    (property "Sheetname" "Channel 2")
    (property "Val" "47p")
    (property "Voltage" "")
    (property "ki_description" "SMD Multilayer Ceramic Capacitor, 47 pF, 50 V, 0402 [1005 Metric], ± 5%, C0G / NP0, C Series KEMET")
    (property "ki_keywords" "0402, SMT, CAPACITOR, PASSIVE, CERAMIC, MLCC")
    (attr smd)
    (fp_text reference "C36" (at -1.15 -2.4 90) (layer "F.SilkS")
        (effects (font (size 0.65 0.65) (thickness 0.13)) (justify right bottom))
    )
    (fp_text value "C_47p_0402" (at 0 1.4 90) (layer "F.Fab")
        (effects (font (size 0.65 0.65) (thickness 0.13)) (justify right bottom))
    )
    (fp_text user "${REFERENCE}" (at -0.932 3.168 90) (layer "F.Fab") hide
        (effects (font (size 0.7 0.7) (thickness 0.15)) (justify right bottom))
    )
    (fp_text user "License: Apache-2.0" (at -0.932 5.17 90) (layer "F.Fab") hide
        (effects (font (size 0.7 0.7) (thickness 0.15)) (justify right bottom))
    )
    (fp_text user "Author: Antmicro" (at -0.932 4.17 90) (layer "F.Fab") hide
        (effects (font (size 0.7 0.7) (thickness 0.15)) (justify right bottom))
    )
    (fp_rect (start -0.925 -0.47) (end 0.925 0.47)
      (stroke (width 0.05) (type default)) (fill none) (layer "F.CrtYd"))
    (fp_line (start -0.494 -0.25) (end 0.504 -0.25)
      (stroke (width 0.15) (type solid)) (layer "F.Fab"))
    (fp_line (start -0.494 0.248) (end -0.494 -0.25)
      (stroke (width 0.15) (type solid)) (layer "F.Fab"))
    (fp_line (start 0.504 -0.25) (end 0.504 0.248)
      (stroke (width 0.15) (type solid)) (layer "F.Fab"))
    (fp_line (start 0.504 0.248) (end -0.494 0.248)
      (stroke (width 0.15) (type solid)) (layer "F.Fab"))
    (pad "1" smd roundrect (at -0.48 0 270) (size 0.59 0.64) (layers "F.Cu" "F.Paste" "F.Mask") (roundrect_rratio 0.25)
      (net 2 "GND") (pintype "passive"))
    (pad "2" smd roundrect (at 0.48 0 270) (size 0.59 0.64) (layers "F.Cu" "F.Paste" "F.Mask") (roundrect_rratio 0.25)
      (net 9 "+3V3") (pintype "passive"))
  )

  (footprint "antmicro-footprints:R_0402_1005Metric" (layer "F.Cu")
    (at 163.39 102.27 -90)
    (descr "Resistor SMD 0402")
    (tags "resistor SMD 0402")
    (property "Author" "Antmicro")
    (property "License" "Apache-2.0")
    (property "MPN" "CR0402-FX-1002GLF")
    (property "Manufacturer" "Bourns")
    (property "Public" "False")
    (property "Sheetfile" "channel2.kicad_sch")
    (property "Sheetname" "Channel 2")
    (property "Tolerance" "1%")
    (property "Val" "10k")
    (property "ki_description" "SMD Chip Resistor, 10 kohm, ± 1%, 62.5 mW, 0402 [1005 Metric], Thick Film, General Purpose")
    (property "ki_keywords" "0402, SMT, RESISTOR, PASSIVE")
    (attr smd)
    (fp_text reference "R24" (at -3.25 11.68 90) (layer "F.SilkS")
        (effects (font (size 0.65 0.65) (thickness 0.13)) (justify left bottom))
    )
    (fp_text value "R_10k_0402" (at 0 1.4 -90) (layer "F.Fab")
        (effects (font (size 0.65 0.65) (thickness 0.13)) (justify left bottom))
    )
    (fp_text user "Author: Antmicro" (at -0.95 4.169 -90) (layer "F.Fab") hide
        (effects (font (size 0.7 0.7) (thickness 0.15)) (justify left bottom))
    )
    (fp_text user "${REFERENCE}" (at -0.95 3.168 -90) (layer "F.Fab") hide
        (effects (font (size 0.7 0.7) (thickness 0.15)) (justify left bottom))
    )
    (fp_text user "License: Apache-2.0" (at -0.95 5.169 -90) (layer "F.Fab") hide
        (effects (font (size 0.7 0.7) (thickness 0.15)) (justify left bottom))
    )
    (fp_rect (start -0.925 -0.47) (end 0.925 0.47)
      (stroke (width 0.05) (type default)) (fill none) (layer "F.CrtYd"))
    (fp_rect (start -0.5 -0.25) (end 0.5 0.25)
      (stroke (width 0.15) (type solid)) (fill none) (layer "F.Fab"))
    (pad "1" smd roundrect (at -0.48 0 270) (size 0.59 0.64) (layers "F.Cu" "F.Paste" "F.Mask") (roundrect_rratio 0.25)
      (net 139 "/Channel 2/HDMI2_DDC_SCL") (pintype "passive"))
    (pad "2" smd roundrect (at 0.48 0 270) (size 0.59 0.64) (layers "F.Cu" "F.Paste" "F.Mask") (roundrect_rratio 0.25)
      (net 14 "+5V") (pintype "passive"))
  )

  (footprint "antmicro-footprints:BGA-64_8x8_6.0x6.0mm" locked (layer "F.Cu")
    (at 159.425 110.45 -90)
    (property "Author" "Antmicro")
    (property "License" "Apache-2.0")
    (property "MPN" "TC358743XBG")
    (property "Manufacturer" "Toshiba")
    (property "Sheetfile" "channel2.kicad_sch")
    (property "Sheetname" "Channel 2")
    (property "ki_description" "HDMI to MIPI CSI-2 bridge. Supports HDMI 1.4. MIPI CSI-2 compliant. 80-Pin VFBGA")
    (property "ki_keywords" "SMT, INTERFACE, IC, CONTROLLER")
    (attr smd)
    (fp_text reference "U4" (at -3.45 3.325) (layer "F.SilkS")
        (effects (font (size 0.65 0.65) (thickness 0.13)) (justify left bottom))
    )
    (fp_text value "TC358743XBG" (at -7.0104 4.8768 -90) (layer "F.Fab")
        (effects (font (size 0.65 0.65) (thickness 0.13)) (justify left bottom))
    )
    (fp_text user "Author: Antmicro" (at -9 7.2 -90) (layer "F.Fab") hide
        (effects (font (size 0.7 0.7) (thickness 0.15)) (justify left bottom))
    )
    (fp_text user "${REFERENCE}" (at -9 5.999 -90) (layer "F.Fab") hide
        (effects (font (size 0.7 0.7) (thickness 0.15)) (justify left bottom))
    )
    (fp_text user "License: Apache-2.0" (at -9 8.4 -90) (layer "F.Fab") hide
        (effects (font (size 0.7 0.7) (thickness 0.15)) (justify left bottom))
    )
    (fp_line (start -3.121 -2) (end -3.121 -1.621)
      (stroke (width 0.15) (type solid)) (layer "F.SilkS"))
    (fp_line (start -3.121 3.12) (end -3.121 1.62)
      (stroke (width 0.15) (type solid)) (layer "F.SilkS"))
    (fp_line (start -2 -3.121) (end -3.121 -2)
      (stroke (width 0.15) (type solid)) (layer "F.SilkS"))
    (fp_line (start -1.621 -3.121) (end -2 -3.121)
      (stroke (width 0.15) (type solid)) (layer "F.SilkS"))
    (fp_line (start -1.621 3.12) (end -3.121 3.12)
      (stroke (width 0.15) (type solid)) (layer "F.SilkS"))
    (fp_line (start 1.62 -3.121) (end 3.12 -3.121)
      (stroke (width 0.15) (type solid)) (layer "F.SilkS"))
    (fp_line (start 1.62 -3.121) (end 3.12 -3.121)
      (stroke (width 0.15) (type solid)) (layer "F.SilkS"))
    (fp_line (start 1.62 -3.121) (end 3.12 -3.121)
      (stroke (width 0.15) (type solid)) (layer "F.SilkS"))
    (fp_line (start 1.62 3.12) (end 3.12 3.12)
      (stroke (width 0.15) (type solid)) (layer "F.SilkS"))
    (fp_line (start 3.12 -3.121) (end 3.12 -1.621)
      (stroke (width 0.15) (type solid)) (layer "F.SilkS"))
    (fp_line (start 3.12 -3.121) (end 3.12 -1.621)
      (stroke (width 0.15) (type solid)) (layer "F.SilkS"))
    (fp_line (start 3.12 -3.121) (end 3.12 -1.621)
      (stroke (width 0.15) (type solid)) (layer "F.SilkS"))
    (fp_line (start 3.12 3.12) (end 3.12 1.62)
      (stroke (width 0.15) (type solid)) (layer "F.SilkS"))
    (fp_circle (center -3 -2.9954) (end -2.951 -2.9954)
      (stroke (width 0.15) (type solid)) (fill solid) (layer "F.SilkS"))
    (fp_line (start -3.21 -3.21) (end 3.2 -3.21)
      (stroke (width 0.05) (type solid)) (layer "F.CrtYd"))
    (fp_line (start -3.21 3.2) (end -3.21 -3.21)
      (stroke (width 0.05) (type solid)) (layer "F.CrtYd"))
    (fp_line (start 3.2 -3.21) (end 3.2 3.2)
      (stroke (width 0.05) (type solid)) (layer "F.CrtYd"))
    (fp_line (start 3.2 3.2) (end -3.21 3.2)
      (stroke (width 0.05) (type solid)) (layer "F.CrtYd"))
    (fp_line (start -3 -2) (end -3 2.999)
      (stroke (width 0.15) (type solid)) (layer "F.Fab"))
    (fp_line (start -3 2.999) (end 2.999 2.999)
      (stroke (width 0.15) (type solid)) (layer "F.Fab"))
    (fp_line (start -2 -3) (end -3 -2)
      (stroke (width 0.15) (type solid)) (layer "F.Fab"))
    (fp_line (start 2.999 -3) (end -2 -3)
      (stroke (width 0.15) (type solid)) (layer "F.Fab"))
    (fp_line (start 2.999 2.999) (end 2.999 -3)
      (stroke (width 0.15) (type solid)) (layer "F.Fab"))
    (pad "A1" smd circle locked (at -2.275 -2.275 270) (size 0.3 0.3) (layers "F.Cu" "F.Paste" "F.Mask")
      (net 114 "Net-(U4B-REXT)") (pinfunction "REXT") (pintype "input"))
    (pad "A2" smd circle locked (at -1.625 -2.275 270) (size 0.3 0.3) (layers "F.Cu" "F.Paste" "F.Mask")
      (net 2 "GND") (pinfunction "GND") (pintype "power_in"))
    (pad "A3" smd circle locked (at -0.975 -2.275 270) (size 0.3 0.3) (layers "F.Cu" "F.Paste" "F.Mask")
      (net 2 "GND") (pinfunction "VPGM") (pintype "input"))
    (pad "A4" smd circle locked (at -0.326 -2.275 270) (size 0.3 0.3) (layers "F.Cu" "F.Paste" "F.Mask")
      (net 16 "Net-(U4C-BIASDA)") (pinfunction "BIASDA") (pintype "output"))
    (pad "A5" smd circle locked (at 0.325 -2.275 270) (size 0.3 0.3) (layers "F.Cu" "F.Paste" "F.Mask")
      (net 17 "Net-(U4C-DAOUT)") (pinfunction "DAOUT") (pintype "output"))
    (pad "A6" smd circle locked (at 0.974 -2.275 270) (size 0.3 0.3) (layers "F.Cu" "F.Paste" "F.Mask")
      (net 131 "unconnected-(U4C-PFIL-PadA6)") (pinfunction "PFIL") (pintype "output+no_connect"))
    (pad "A7" smd circle locked (at 1.624 -2.275 270) (size 0.3 0.3) (layers "F.Cu" "F.Paste" "F.Mask")
      (net 34 "CSI3_D4_N") (pinfunction "CSID3_N") (pintype "output"))
    (pad "A8" smd circle locked (at 2.274 -2.275 270) (size 0.3 0.3) (layers "F.Cu" "F.Paste" "F.Mask")
      (net 35 "CSI3_D4_P") (pinfunction "CSID3_P") (pintype "output"))
    (pad "B1" smd circle locked (at -2.275 -1.625 270) (size 0.3 0.3) (layers "F.Cu" "F.Paste" "F.Mask")
      (net 108 "/Channel 2/CH2_AVDD33") (pinfunction "AVDD33") (pintype "power_in"))
    (pad "B2" smd circle locked (at -1.625 -1.625 270) (size 0.3 0.3) (layers "F.Cu" "F.Paste" "F.Mask")
      (net 109 "Net-(C48-Pad1)") (pinfunction "AVDD12") (pintype "power_in"))
    (pad "B3" smd circle locked (at -0.975 -1.625 270) (size 0.3 0.3) (layers "F.Cu" "F.Paste" "F.Mask")
      (net 132 "unconnected-(U4B-INT-PadB3)") (pinfunction "INT") (pintype "output+no_connect"))
    (pad "B4" smd circle locked (at -0.326 -1.625 270) (size 0.3 0.3) (layers "F.Cu" "F.Paste" "F.Mask")
      (net 133 "unconnected-(U4A-IR-PadB4)") (pinfunction "IR") (pintype "input+no_connect"))
    (pad "B5" smd circle locked (at 0.325 -1.625 270) (size 0.3 0.3) (layers "F.Cu" "F.Paste" "F.Mask")
      (net 32 "Net-(U4B-AVDD25)") (pinfunction "AVDD25") (pintype "power_in"))
    (pad "B6" smd circle locked (at 0.974 -1.625 270) (size 0.3 0.3) (layers "F.Cu" "F.Paste" "F.Mask")
      (net 18 "Net-(U4C-PCKIN)") (pinfunction "PCKIN") (pintype "input"))
    (pad "B7" smd circle locked (at 1.624 -1.625 270) (size 0.3 0.3) (layers "F.Cu" "F.Paste" "F.Mask")
      (net 36 "CSI3_D3_N") (pinfunction "CSID2_N") (pintype "output"))
    (pad "B8" smd circle locked (at 2.274 -1.625 270) (size 0.3 0.3) (layers "F.Cu" "F.Paste" "F.Mask")
      (net 37 "CSI3_D3_P") (pinfunction "CSID2_P") (pintype "output"))
    (pad "C1" smd circle locked (at -2.275 -0.975 270) (size 0.3 0.3) (layers "F.Cu" "F.Paste" "F.Mask")
      (net 94 "/Channel 2/HDMI2_CLK_P") (pinfunction "HDMIC_P") (pintype "input"))
    (pad "C2" smd circle locked (at -1.625 -0.975 270) (size 0.3 0.3) (layers "F.Cu" "F.Paste" "F.Mask")
      (net 137 "/Channel 2/HDMI2_CLK_N") (pinfunction "HDMIC_N") (pintype "input"))
    (pad "C3" smd circle locked (at -0.975 -0.975 270) (size 0.3 0.3) (layers "F.Cu" "F.Paste" "F.Mask")
      (net 22 "Net-(C31-Pad2)") (pinfunction "VDDC2") (pintype "power_in"))
    (pad "C4" smd circle locked (at -0.326 -0.975 270) (size 0.3 0.3) (layers "F.Cu" "F.Paste" "F.Mask")
      (net 2 "GND") (pinfunction "GND") (pintype "passive"))
    (pad "C5" smd circle locked (at 0.325 -0.975 270) (size 0.3 0.3) (layers "F.Cu" "F.Paste" "F.Mask")
      (net 2 "GND") (pinfunction "GND") (pintype "passive"))
    (pad "C6" smd circle locked (at 0.974 -0.975 270) (size 0.3 0.3) (layers "F.Cu" "F.Paste" "F.Mask")
      (net 110 "Net-(C49-Pad1)") (pinfunction "VDD_MIPI") (pintype "power_in"))
    (pad "C7" smd circle locked (at 1.624 -0.975 270) (size 0.3 0.3) (layers "F.Cu" "F.Paste" "F.Mask")
      (net 42 "CSI3_CLK_N") (pinfunction "CSIC_N") (pintype "output"))
    (pad "C8" smd circle locked (at 2.274 -0.975 270) (size 0.3 0.3) (layers "F.Cu" "F.Paste" "F.Mask")
      (net 43 "CSI3_CLK_P") (pinfunction "CSIC_P") (pintype "output"))
    (pad "D1" smd circle locked (at -2.275 -0.326 270) (size 0.3 0.3) (layers "F.Cu" "F.Paste" "F.Mask")
      (net 92 "/Channel 2/HDMI2_D0_P") (pinfunction "HDMID0_P") (pintype "input"))
    (pad "D2" smd circle locked (at -1.625 -0.326 270) (size 0.3 0.3) (layers "F.Cu" "F.Paste" "F.Mask")
      (net 93 "/Channel 2/HDMI2_D0_N") (pinfunction "HDMID0_N") (pintype "input"))
    (pad "D3" smd circle locked (at -0.975 -0.326 270) (size 0.3 0.3) (layers "F.Cu" "F.Paste" "F.Mask")
      (net 109 "Net-(C48-Pad1)") (pinfunction "AVDD12") (pintype "passive"))
    (pad "D4" smd circle locked (at -0.326 -0.326 270) (size 0.3 0.3) (layers "F.Cu" "F.Paste" "F.Mask")
      (net 2 "GND") (pinfunction "GND") (pintype "passive"))
    (pad "D5" smd circle locked (at 0.325 -0.326 270) (size 0.3 0.3) (layers "F.Cu" "F.Paste" "F.Mask")
      (net 2 "GND") (pinfunction "GND") (pintype "passive"))
    (pad "D6" smd circle locked (at 0.974 -0.326 270) (size 0.3 0.3) (layers "F.Cu" "F.Paste" "F.Mask")
      (net 2 "GND") (pinfunction "GND") (pintype "passive"))
    (pad "D7" smd circle locked (at 1.624 -0.326 270) (size 0.3 0.3) (layers "F.Cu" "F.Paste" "F.Mask")
      (net 38 "CSI3_D2_N") (pinfunction "CSID1_N") (pintype "output"))
    (pad "D8" smd circle locked (at 2.274 -0.326 270) (size 0.3 0.3) (layers "F.Cu" "F.Paste" "F.Mask")
      (net 39 "CSI3_D2_P") (pinfunction "CSID1_P") (pintype "output"))
    (pad "E1" smd circle locked (at -2.275 0.325 270) (size 0.3 0.3) (layers "F.Cu" "F.Paste" "F.Mask")
      (net 90 "/Channel 2/HDMI2_D1_P") (pinfunction "HDMID1_P") (pintype "input"))
    (pad "E2" smd circle locked (at -1.625 0.325 270) (size 0.3 0.3) (layers "F.Cu" "F.Paste" "F.Mask")
      (net 91 "/Channel 2/HDMI2_D1_N") (pinfunction "HDMID1_N") (pintype "input"))
    (pad "E3" smd circle locked (at -0.975 0.325 270) (size 0.3 0.3) (layers "F.Cu" "F.Paste" "F.Mask")
      (net 2 "GND") (pinfunction "GND") (pintype "passive"))
    (pad "E4" smd circle locked (at -0.326 0.325 270) (size 0.3 0.3) (layers "F.Cu" "F.Paste" "F.Mask")
      (net 2 "GND") (pinfunction "GND") (pintype "passive"))
    (pad "E5" smd circle locked (at 0.325 0.325 270) (size 0.3 0.3) (layers "F.Cu" "F.Paste" "F.Mask")
      (net 2 "GND") (pinfunction "TEST") (pintype "input"))
    (pad "E6" smd circle locked (at 0.974 0.325 270) (size 0.3 0.3) (layers "F.Cu" "F.Paste" "F.Mask")
      (net 2 "GND") (pinfunction "GND") (pintype "passive"))
    (pad "E7" smd circle locked (at 1.624 0.325 270) (size 0.3 0.3) (layers "F.Cu" "F.Paste" "F.Mask")
      (net 40 "CSI3_D1_N") (pinfunction "CSID0_N") (pintype "output"))
    (pad "E8" smd circle locked (at 2.274 0.325 270) (size 0.3 0.3) (layers "F.Cu" "F.Paste" "F.Mask")
      (net 41 "CSI3_D1_P") (pinfunction "CSID0_P") (pintype "output"))
    (pad "F1" smd circle locked (at -2.275 0.974 270) (size 0.3 0.3) (layers "F.Cu" "F.Paste" "F.Mask")
      (net 88 "/Channel 2/HDMI2_D2_P") (pinfunction "HDMID2_P") (pintype "input"))
    (pad "F2" smd circle locked (at -1.625 0.974 270) (size 0.3 0.3) (layers "F.Cu" "F.Paste" "F.Mask")
      (net 89 "/Channel 2/HDMI2_D2_N") (pinfunction "HDMID2_N") (pintype "input"))
    (pad "F3" smd circle locked (at -0.975 0.974 270) (size 0.3 0.3) (layers "F.Cu" "F.Paste" "F.Mask")
      (net 108 "/Channel 2/CH2_AVDD33") (pinfunction "AVDD33") (pintype "passive"))
    (pad "F4" smd circle locked (at -0.326 0.974 270) (size 0.3 0.3) (layers "F.Cu" "F.Paste" "F.Mask")
      (net 23 "Net-(U4B-VDDIO1)") (pinfunction "VDDIO1") (pintype "power_in"))
    (pad "F5" smd circle locked (at 0.325 0.974 270) (size 0.3 0.3) (layers "F.Cu" "F.Paste" "F.Mask")
      (net 22 "Net-(C31-Pad2)") (pinfunction "VDDC2") (pintype "passive"))
    (pad "F6" smd circle locked (at 0.974 0.974 270) (size 0.3 0.3) (layers "F.Cu" "F.Paste" "F.Mask")
      (net 110 "Net-(C49-Pad1)") (pinfunction "VDD_MIPI") (pintype "passive"))
    (pad "F7" smd circle locked (at 1.624 0.974 270) (size 0.3 0.3) (layers "F.Cu" "F.Paste" "F.Mask")
      (net 134 "unconnected-(U4C-A_SCK-PadF7)") (pinfunction "A_SCK") (pintype "output+no_connect"))
    (pad "F8" smd circle locked (at 2.274 0.974 270) (size 0.3 0.3) (layers "F.Cu" "F.Paste" "F.Mask")
      (net 135 "unconnected-(U4C-A_SD-PadF8)") (pinfunction "A_SD") (pintype "output+no_connect"))
    (pad "G1" smd circle locked (at -2.275 1.624 270) (size 0.3 0.3) (layers "F.Cu" "F.Paste" "F.Mask")
      (net 138 "/Channel 2/HDMI2_CEC") (pinfunction "CEC") (pintype "bidirectional"))
    (pad "G2" smd circle locked (at -1.625 1.624 270) (size 0.3 0.3) (layers "F.Cu" "F.Paste" "F.Mask")
      (net 33 "Net-(U4B-VDDC1)") (pinfunction "VDDC1") (pintype "power_in"))
    (pad "G3" smd circle locked (at -0.975 1.624 270) (size 0.3 0.3) (layers "F.Cu" "F.Paste" "F.Mask")
      (net 111 "/Channel 2/HDMI2_DDC_SDA_3V3") (pinfunction "DDC_SDA") (pintype "bidirectional"))
    (pad "G4" smd circle locked (at -0.326 1.624 270) (size 0.3 0.3) (layers "F.Cu" "F.Paste" "F.Mask")
      (net 66 "I2C3_SDA") (pinfunction "I2C_SDA") (pintype "bidirectional"))
    (pad "G5" smd circle locked (at 0.325 1.624 270) (size 0.3 0.3) (layers "F.Cu" "F.Paste" "F.Mask")
      (net 107 "/Channel 2/CH2_~{RST}") (pinfunction "~{RESET}") (pintype "input"))
    (pad "G6" smd circle locked (at 0.974 1.624 270) (size 0.3 0.3) (layers "F.Cu" "F.Paste" "F.Mask")
      (net 120 "Net-(U4A-EDID_SDA)") (pinfunction "EDID_SDA") (pintype "bidirectional"))
    (pad "G7" smd circle locked (at 1.624 1.624 270) (size 0.3 0.3) (layers "F.Cu" "F.Paste" "F.Mask")
      (net 136 "unconnected-(U4C-A_WFS-PadG7)") (pinfunction "A_WFS") (pintype "output+no_connect"))
    (pad "G8" smd circle locked (at 2.274 1.624 270) (size 0.3 0.3) (layers "F.Cu" "F.Paste" "F.Mask")
      (net 142 "unconnected-(U4C-A_OSCK-PadG8)") (pinfunction "A_OSCK") (pintype "output+no_connect"))
    (pad "H1" smd circle locked (at -2.275 2.274 270) (size 0.3 0.3) (layers "F.Cu" "F.Paste" "F.Mask")
      (net 119 "/Channel 2/HDMI2_HPDO") (pinfunction "HPDO") (pintype "output"))
    (pad "H2" smd circle locked (at -1.625 2.274 270) (size 0.3 0.3) (layers "F.Cu" "F.Paste" "F.Mask")
      (net 106 "/Channel 2/HDMI2_HPDI") (pinfunction "HPDI") (pintype "input"))
    (pad "H3" smd circle locked (at -0.975 2.274 270) (size 0.3 0.3) (layers "F.Cu" "F.Paste" "F.Mask")
      (net 112 "/Channel 2/HDMI2_DDC_SCL_3V3") (pinfunction "DDC_SCL") (pintype "bidirectional"))
    (pad "H4" smd circle locked (at -0.326 2.274 270) (size 0.3 0.3) (layers "F.Cu" "F.Paste" "F.Mask")
      (net 67 "I2C3_SCL") (pinfunction "I2C_SCL") (pintype "bidirectional"))
    (pad "H5" smd circle locked (at 0.325 2.274 270) (size 0.3 0.3) (layers "F.Cu" "F.Paste" "F.Mask")
      (net 27 "/Channel 2/CH2_REFCLK") (pinfunction "REFCLK") (pintype "input"))
    (pad "H6" smd circle locked (at 0.974 2.274 270) (size 0.3 0.3) (layers "F.Cu" "F.Paste" "F.Mask")
      (net 121 "Net-(U4A-EDID_SCL)") (pinfunction "EDID_SCL") (pintype "bidirectional"))
    (pad "H7" smd circle locked (at 1.624 2.274 270) (size 0.3 0.3) (layers "F.Cu" "F.Paste" "F.Mask")
      (net 26 "Net-(U4B-VDDIO2)") (pinfunction "VDDIO2") (pintype "power_in"))
    (pad "H8" smd circle locked (at 2.274 2.274 270) (size 0.3 0.3) (layers "F.Cu" "F.Paste" "F.Mask")
      (net 2 "GND") (pinfunction "GND") (pintype "passive"))
  )

  (footprint "antmicro-footprints:HDMI-A_Receptacle_Molex_471511001" (layer "F.Cu")
    (at 160.999 94.344 180)
    (property "Author" "Antmicro")
    (property "License" "Apache-2.0")
    (property "MPN" "471511001")
    (property "Manufacturer" "Molex")
    (property "Sheetfile" "channel2.kicad_sch")
    (property "Sheetname" "Channel 2")
    (property "ki_description" "HDMI Receptacle Connector 19 Position Surface Mount, Right Angle; Through Hole")
    (property "ki_keywords" "HDMI, CONNECTOR, SMT, HORIZONTAL")
    (attr smd)
    (fp_text reference "J4" (at 9.879 1.614 unlocked) (layer "F.SilkS")
        (effects (font (size 0.7 0.7) (thickness 0.15)) (justify left bottom))
    )
    (fp_text value "HDMI-A_Molex_471511001" (at 0 7.55 180 unlocked) (layer "F.Fab")
        (effects (font (size 0.7 0.7) (thickness 0.15)) (justify left bottom))
    )
    (fp_text user "${REFERENCE}" (at -10.001 12.48 180 unlocked) (layer "F.Fab") hide
        (effects (font (size 0.7 0.7) (thickness 0.15)) (justify left bottom))
    )
    (fp_text user "Author: Antmicro" (at -10.001 13.678 180) (layer "F.Fab") hide
        (effects (font (size 0.7 0.7) (thickness 0.15)) (justify left bottom))
    )
    (fp_text user "License: Apache-2.0" (at -10.001 14.878 180) (layer "F.Fab") hide
        (effects (font (size 0.7 0.7) (thickness 0.15)) (justify left bottom))
    )
    (fp_circle (center 4.948 -5.705) (end 4.998 -5.705)
      (stroke (width 0.15) (type solid)) (fill solid) (layer "F.SilkS"))
    (fp_rect (start -8.0296 -6.5548) (end 8.0296 6.5532)
      (stroke (width 0.05) (type solid)) (fill none) (layer "F.CrtYd"))
    (pad "1" smd rect (at 4.499 -5.056 180) (size 0.3 2.6) (layers "F.Cu" "F.Paste" "F.Mask")
      (net 88 "/Channel 2/HDMI2_D2_P") (pinfunction "D2+") (pintype "bidirectional"))
    (pad "2" smd rect (at 3.999 -5.056 180) (size 0.3 2.6) (layers "F.Cu" "F.Paste" "F.Mask")
      (net 2 "GND") (pinfunction "D2S") (pintype "passive"))
    (pad "3" smd rect (at 3.499 -5.056 180) (size 0.3 2.6) (layers "F.Cu" "F.Paste" "F.Mask")
      (net 89 "/Channel 2/HDMI2_D2_N") (pinfunction "D2-") (pintype "bidirectional"))
    (pad "4" smd rect (at 2.999 -5.056 180) (size 0.3 2.6) (layers "F.Cu" "F.Paste" "F.Mask")
      (net 90 "/Channel 2/HDMI2_D1_P") (pinfunction "D1+") (pintype "bidirectional"))
    (pad "5" smd rect (at 2.499 -5.056 180) (size 0.3 2.6) (layers "F.Cu" "F.Paste" "F.Mask")
      (net 2 "GND") (pinfunction "D1S") (pintype "passive"))
    (pad "6" smd rect (at 1.999 -5.056 180) (size 0.3 2.6) (layers "F.Cu" "F.Paste" "F.Mask")
      (net 91 "/Channel 2/HDMI2_D1_N") (pinfunction "D1-") (pintype "bidirectional"))
    (pad "7" smd rect (at 1.499 -5.056 180) (size 0.3 2.6) (layers "F.Cu" "F.Paste" "F.Mask")
      (net 92 "/Channel 2/HDMI2_D0_P") (pinfunction "D0+") (pintype "bidirectional"))
    (pad "8" smd rect (at 0.998 -5.056 180) (size 0.3 2.6) (layers "F.Cu" "F.Paste" "F.Mask")
      (net 2 "GND") (pinfunction "D0S") (pintype "passive"))
    (pad "9" smd rect (at 0.498 -5.056 180) (size 0.3 2.6) (layers "F.Cu" "F.Paste" "F.Mask")
      (net 93 "/Channel 2/HDMI2_D0_N") (pinfunction "D0-") (pintype "bidirectional"))
    (pad "10" smd rect (at 0 -5.056 180) (size 0.3 2.6) (layers "F.Cu" "F.Paste" "F.Mask")
      (net 94 "/Channel 2/HDMI2_CLK_P") (pinfunction "CK+") (pintype "bidirectional"))
    (pad "11" smd rect (at -0.5 -5.056 180) (size 0.3 2.6) (layers "F.Cu" "F.Paste" "F.Mask")
      (net 2 "GND") (pinfunction "CKS") (pintype "passive"))
    (pad "12" smd rect (at -1.002 -5.056 180) (size 0.3 2.6) (layers "F.Cu" "F.Paste" "F.Mask")
      (net 137 "/Channel 2/HDMI2_CLK_N") (pinfunction "CK-") (pintype "bidirectional"))
    (pad "13" smd rect (at -1.5 -5.056 180) (size 0.3 2.6) (layers "F.Cu" "F.Paste" "F.Mask")
      (net 138 "/Channel 2/HDMI2_CEC") (pinfunction "CEC") (pintype "bidirectional"))
    (pad "14" smd rect (at -2.001 -5.056 180) (size 0.3 2.6) (layers "F.Cu" "F.Paste" "F.Mask")
      (net 95 "/Channel 2/DUMMY2") (pinfunction "UTILITY/HEAC+") (pintype "bidirectional"))
    (pad "15" smd rect (at -2.501 -5.056 180) (size 0.3 2.6) (layers "F.Cu" "F.Paste" "F.Mask")
      (net 139 "/Channel 2/HDMI2_DDC_SCL") (pinfunction "SCL") (pintype "bidirectional"))
    (pad "16" smd rect (at -3 -5.056 180) (size 0.3 2.6) (layers "F.Cu" "F.Paste" "F.Mask")
      (net 140 "/Channel 2/HDMI2_DDC_SDA") (pinfunction "SDA") (pintype "bidirectional"))
    (pad "17" smd rect (at -3.501 -5.056 180) (size 0.3 2.6) (layers "F.Cu" "F.Paste" "F.Mask")
      (net 2 "GND") (pinfunction "GND") (pintype "power_in"))
    (pad "18" smd rect (at -4 -5.056 180) (size 0.3 2.6) (layers "F.Cu" "F.Paste" "F.Mask")
      (net 96 "/Channel 2/HDMI2_POWER") (pinfunction "+5V") (pintype "power_in"))
    (pad "19" smd rect (at -4.502 -5.056 180) (size 0.3 2.6) (layers "F.Cu" "F.Paste" "F.Mask")
      (net 141 "/Channel 2/HDMI2_HPD") (pinfunction "HPD/HEAC-") (pintype "bidirectional"))
    (pad "SH" thru_hole oval (at -7.25 -4.297 180) (size 1.5 3.3) (drill oval 0.9 2.7) (layers "*.Cu" "*.Mask")
      (net 29 "Net-(FB7-Pad2)") (pinfunction "SH") (pintype "passive"))
    (pad "SH" thru_hole oval (at -7.25 1.664 180) (size 1.5 2.3) (drill oval 0.9 1.7) (layers "*.Cu" "*.Mask")
      (net 29 "Net-(FB7-Pad2)") (pinfunction "SH") (pintype "passive"))
    (pad "SH" thru_hole oval (at 7.249 -4.297 180) (size 1.5 3.3) (drill oval 0.9 2.7) (layers "*.Cu" "*.Mask")
      (net 29 "Net-(FB7-Pad2)") (pinfunction "SH") (pintype "passive"))
    (pad "SH" thru_hole oval (at 7.249 1.664 180) (size 1.5 2.3) (drill oval 0.9 1.7) (layers "*.Cu" "*.Mask")
      (net 29 "Net-(FB7-Pad2)") (pinfunction "SH") (pintype "passive"))
  )

  (footprint "antmicro-footprints:C_0603_1608Metric" (layer "F.Cu")
    (at 164.2 113.05 180)
    (descr "Capacitor SMD 0603")
    (tags "capacitor 0603")
    (property "Author" "Antmicro")
    (property "Dielectric" "")
    (property "License" "Apache-2.0")
    (property "MPN" "C1608X5R1V475M080AC")
    (property "Manufacturer" "TDK")
    (property "Public" "False")
    (property "Sheetfile" "channel2.kicad_sch")
    (property "Sheetname" "Channel 2")
    (property "Val" "4u7")
    (property "Voltage" "")
    (property "ki_description" "SMD Multilayer Ceramic Capacitor, 4.7 µF, 35 V, 0603 [1608 Metric], ± 20%, X5R, C")
    (property "ki_keywords" "0603, SMT, CAPACITOR, PASSIVE, CERAMIC, MLCC")
    (attr smd)
    (fp_text reference "C53" (at 2 -6.85) (layer "F.SilkS")
        (effects (font (size 0.65 0.65) (thickness 0.13)) (justify right bottom))
    )
    (fp_text value "C_4u7_0603" (at 0 1.6) (layer "F.Fab")
        (effects (font (size 0.65 0.65) (thickness 0.13)) (justify right bottom))
    )
    (fp_text user "License: Apache-2.0" (at -1.682 5.895) (layer "F.Fab") hide
        (effects (font (size 0.7 0.7) (thickness 0.15)) (justify right bottom))
    )
    (fp_text user "Author: Antmicro" (at -1.682 4.894) (layer "F.Fab") hide
        (effects (font (size 0.7 0.7) (thickness 0.15)) (justify right bottom))
    )
    (fp_text user "${REFERENCE}" (at -1.682 3.895) (layer "F.Fab") hide
        (effects (font (size 0.7 0.7) (thickness 0.15)) (justify right bottom))
    )
    (fp_line (start -0.15 -0.4) (end 0.15 -0.4)
      (stroke (width 0.15) (type solid)) (layer "F.SilkS"))
    (fp_line (start -0.15 0.4) (end 0.15 0.4)
      (stroke (width 0.15) (type solid)) (layer "F.SilkS"))
    (fp_rect (start -1.25 -0.65) (end 1.25 0.65)
      (stroke (width 0.05) (type solid)) (fill none) (layer "F.CrtYd"))
    (fp_rect (start -0.8 -0.4) (end 0.8 0.4)
      (stroke (width 0.15) (type solid)) (fill none) (layer "F.Fab"))
    (pad "1" smd roundrect (at -0.7 0 180) (size 0.8 1) (layers "F.Cu" "F.Paste" "F.Mask") (roundrect_rratio 0.2)
      (net 2 "GND") (pintype "passive"))
    (pad "2" smd roundrect (at 0.7 0 180) (size 0.8 1) (layers "F.Cu" "F.Paste" "F.Mask") (roundrect_rratio 0.2)
      (net 110 "Net-(C49-Pad1)") (pintype "passive"))
  )

  (footprint "antmicro-footprints:R-PDSO-N15" (layer "F.Cu")
    (at 159.25 103.42 90)
    (property "Author" "Antmicro")
    (property "License" "Apache-2.0")
    (property "MPN" "TPD8S009DSMR")
    (property "Manufacturer" "Texas Instruments")
    (property "Sheetfile" "channel2.kicad_sch")
    (property "Sheetname" "Channel 2")
    (property "ki_description" "TVS diode array, 8 kV, R-PDSO-N15, 5.5 V, 0.8 pF")
    (property "ki_keywords" "SMT, DIODE, SEMICONDUCTOR, TVS, ESD")
    (attr smd)
    (fp_text reference "U5" (at 0 -3.7 90) (layer "F.SilkS")
        (effects (font (size 0.65 0.65) (thickness 0.13)) (justify left bottom))
    )
    (fp_text value "TPD8S009DSMR" (at 0 4.4 90) (layer "F.Fab")
        (effects (font (size 0.65 0.65) (thickness 0.13)) (justify left bottom))
    )
    (fp_text user "Author: Antmicro" (at -4.1 7.35 90) (layer "F.Fab") hide
        (effects (font (size 0.7 0.7) (thickness 0.15)) (justify left bottom))
    )
    (fp_text user "License: Apache-2.0" (at -4.1 6.15 90) (layer "F.Fab") hide
        (effects (font (size 0.7 0.7) (thickness 0.15)) (justify left bottom))
    )
    (fp_text user "${REFERENCE}" (at -4.1 4.95 90) (layer "F.Fab") hide
        (effects (font (size 0.7 0.7) (thickness 0.15)) (justify left bottom))
    )
    (fp_circle (center -1.6 -3.2) (end -1.6 -3.15)
      (stroke (width 0.15) (type solid)) (fill solid) (layer "F.SilkS"))
    (fp_rect (start 1.8 -3.5) (end -1.89 3.49)
      (stroke (width 0.05) (type solid)) (fill none) (layer "F.CrtYd"))
    (fp_line (start -1.3 -3.051) (end -1.1 -3.25)
      (stroke (width 0.15) (type solid)) (layer "F.Fab"))
    (fp_rect (start 1.301 -3.25) (end -1.3 3.249)
      (stroke (width 0.15) (type solid)) (fill none) (layer "F.Fab"))
    (pad "1" smd roundrect (at -0.95 -2.75) (size 0.3 1.45) (layers "F.Cu" "F.Paste" "F.Mask") (roundrect_rratio 0.25)
      (net 88 "/Channel 2/HDMI2_D2_P") (pinfunction "D0+") (pintype "passive"))
    (pad "2" smd roundrect (at -0.95 -2.25) (size 0.3 1.45) (layers "F.Cu" "F.Paste" "F.Mask") (roundrect_rratio 0.25)
      (net 2 "GND") (pinfunction "GND") (pintype "passive"))
    (pad "3" smd roundrect (at -0.95 -1.75) (size 0.3 1.45) (layers "F.Cu" "F.Paste" "F.Mask") (roundrect_rratio 0.25)
      (net 89 "/Channel 2/HDMI2_D2_N") (pinfunction "D0-") (pintype "passive"))
    (pad "4" smd roundrect (at -0.95 -1.25) (size 0.3 1.45) (layers "F.Cu" "F.Paste" "F.Mask") (roundrect_rratio 0.25)
      (net 90 "/Channel 2/HDMI2_D1_P") (pinfunction "D1+") (pintype "passive"))
    (pad "5" smd roundrect (at -0.95 -0.75) (size 0.3 1.45) (layers "F.Cu" "F.Paste" "F.Mask") (roundrect_rratio 0.25)
      (net 2 "GND") (pinfunction "GND") (pintype "passive"))
    (pad "6" smd roundrect (at -0.95 -0.25) (size 0.3 1.45) (layers "F.Cu" "F.Paste" "F.Mask") (roundrect_rratio 0.25)
      (net 91 "/Channel 2/HDMI2_D1_N") (pinfunction "D1-") (pintype "passive"))
    (pad "7" smd roundrect (at -0.95 0.247) (size 0.3 1.45) (layers "F.Cu" "F.Paste" "F.Mask") (roundrect_rratio 0.25)
      (net 92 "/Channel 2/HDMI2_D0_P") (pinfunction "D2+") (pintype "passive"))
    (pad "8" smd roundrect (at -0.95 0.747) (size 0.3 1.45) (layers "F.Cu" "F.Paste" "F.Mask") (roundrect_rratio 0.25)
      (net 2 "GND") (pinfunction "GND") (pintype "passive"))
    (pad "9" smd roundrect (at -0.95 1.249) (size 0.3 1.45) (layers "F.Cu" "F.Paste" "F.Mask") (roundrect_rratio 0.25)
      (net 93 "/Channel 2/HDMI2_D0_N") (pinfunction "D2-") (pintype "passive"))
    (pad "10" smd roundrect (at -0.95 1.749) (size 0.3 1.45) (layers "F.Cu" "F.Paste" "F.Mask") (roundrect_rratio 0.25)
      (net 94 "/Channel 2/HDMI2_CLK_P") (pinfunction "D3+") (pintype "passive"))
    (pad "11" smd roundrect (at -0.95 2.249) (size 0.3 1.45) (layers "F.Cu" "F.Paste" "F.Mask") (roundrect_rratio 0.25)
      (net 2 "GND") (pinfunction "GND") (pintype "passive"))
    (pad "12" smd roundrect (at -0.95 2.749) (size 0.3 1.45) (layers "F.Cu" "F.Paste" "F.Mask") (roundrect_rratio 0.25)
      (net 137 "/Channel 2/HDMI2_CLK_N") (pinfunction "D3-") (pintype "passive"))
    (pad "13" smd roundrect (at 0.901 1.499) (size 0.3 1.45) (layers "F.Cu" "F.Paste" "F.Mask") (roundrect_rratio 0.25)
      (net 9 "+3V3") (pinfunction "VCC") (pintype "power_in"))
    (pad "14" smd roundrect (at 0.901 0) (size 0.3 1.45) (layers "F.Cu" "F.Paste" "F.Mask") (roundrect_rratio 0.25)
      (net 143 "unconnected-(U5-NC-Pad14)") (pinfunction "NC") (pintype "no_connect"))
    (pad "15" smd roundrect (at 0.901 -1.5) (size 0.3 1.45) (layers "F.Cu" "F.Paste" "F.Mask") (roundrect_rratio 0.25)
      (net 9 "+3V3") (pinfunction "VCC") (pintype "passive"))
  )

  (footprint "antmicro-footprints:R_0603_1608Metric" (layer "F.Cu")
    (at 139.8 116.1 -90)
    (descr "Resistor SMD 0603")
    (tags "resistor SMD 0603")
    (property "Author" "Antmicro")
    (property "Current" "1A")
    (property "License" "Apache-2.0")
    (property "MPN" "CR0603-J/-000ELF")
    (property "Manufacturer" "Bourns")
    (property "Public" "False")
    (property "Sheetfile" "channel1.kicad_sch")
    (property "Sheetname" "Channel 1")
    (property "Tolerance" "")
    (property "Val" "0R")
    (property "ki_description" "Zero Ohm Resistor, Jumper, 0603 [1608 Metric], Thick Film, 100 mW, 1 A, Surface Mount Device, CR")
    (property "ki_keywords" "0603, SMT, RESISTOR, PASSIVE")
    (attr smd)
    (fp_text reference "R5" (at 2.65 -0.2 -90) (layer "F.SilkS")
        (effects (font (size 0.7 0.7) (thickness 0.15)) (justify left bottom))
    )
    (fp_text value "R_0R_0603" (at 0 1.6 -90) (layer "F.Fab")
        (effects (font (size 0.7 0.7) (thickness 0.15)) (justify left bottom))
    )
    (fp_text user "${REFERENCE}" (at -1.25 3.898 -90) (layer "F.Fab") hide
        (effects (font (size 0.7 0.7) (thickness 0.15)) (justify left bottom))
    )
    (fp_text user "License: Apache-2.0" (at -1.25 5.9 -90) (layer "F.Fab") hide
        (effects (font (size 0.7 0.7) (thickness 0.15)) (justify left bottom))
    )
    (fp_text user "Author: Antmicro" (at -1.25 4.9 -90) (layer "F.Fab") hide
        (effects (font (size 0.7 0.7) (thickness 0.15)) (justify left bottom))
    )
    (fp_line (start -0.15 -0.4) (end 0.15 -0.4)
      (stroke (width 0.15) (type solid)) (layer "F.SilkS"))
    (fp_line (start -0.15 0.4) (end 0.15 0.4)
      (stroke (width 0.15) (type solid)) (layer "F.SilkS"))
    (fp_rect (start -1.25 -0.65) (end 1.25 0.65)
      (stroke (width 0.05) (type solid)) (fill none) (layer "F.CrtYd"))
    (fp_rect (start -0.8 -0.4) (end 0.8 0.4)
      (stroke (width 0.15) (type solid)) (fill none) (layer "F.Fab"))
    (pad "1" smd roundrect (at -0.7 0 270) (size 0.8 1) (layers "F.Cu" "F.Paste" "F.Mask") (roundrect_rratio 0.2)
      (net 19 "Net-(C27-Pad2)") (pintype "passive"))
    (pad "2" smd roundrect (at 0.7 0 270) (size 0.8 1) (layers "F.Cu" "F.Paste" "F.Mask") (roundrect_rratio 0.2)
      (net 8 "Net-(U1B-VDDC1)") (pintype "passive"))
  )

  (footprint "antmicro-footprints:R_0402_1005Metric" (layer "F.Cu")
    (at 167.92 104.81)
    (descr "Resistor SMD 0402")
    (tags "resistor SMD 0402")
    (property "Author" "Antmicro")
    (property "License" "Apache-2.0")
    (property "MPN" "CR0402-FX-1002GLF")
    (property "Manufacturer" "Bourns")
    (property "Public" "False")
    (property "Sheetfile" "channel2.kicad_sch")
    (property "Sheetname" "Channel 2")
    (property "Tolerance" "1%")
    (property "Val" "10k")
    (property "ki_description" "SMD Chip Resistor, 10 kohm, ± 1%, 62.5 mW, 0402 [1005 Metric], Thick Film, General Purpose")
    (property "ki_keywords" "0402, SMT, RESISTOR, PASSIVE")
    (attr smd)
    (fp_text reference "R25" (at 0.905 0.36) (layer "F.SilkS")
        (effects (font (size 0.65 0.65) (thickness 0.13)) (justify left bottom))
    )
    (fp_text value "R_10k_0402" (at 0 1.4) (layer "F.Fab")
        (effects (font (size 0.65 0.65) (thickness 0.13)) (justify left bottom))
    )
    (fp_text user "License: Apache-2.0" (at -0.95 5.169) (layer "F.Fab") hide
        (effects (font (size 0.7 0.7) (thickness 0.15)) (justify left bottom))
    )
    (fp_text user "Author: Antmicro" (at -0.95 4.169) (layer "F.Fab") hide
        (effects (font (size 0.7 0.7) (thickness 0.15)) (justify left bottom))
    )
    (fp_text user "${REFERENCE}" (at -0.95 3.168) (layer "F.Fab") hide
        (effects (font (size 0.7 0.7) (thickness 0.15)) (justify left bottom))
    )
    (fp_rect (start -0.925 -0.47) (end 0.925 0.47)
      (stroke (width 0.05) (type default)) (fill none) (layer "F.CrtYd"))
    (fp_rect (start -0.5 -0.25) (end 0.5 0.25)
      (stroke (width 0.15) (type solid)) (fill none) (layer "F.Fab"))
    (pad "1" smd roundrect (at -0.48 0) (size 0.59 0.64) (layers "F.Cu" "F.Paste" "F.Mask") (roundrect_rratio 0.25)
      (net 140 "/Channel 2/HDMI2_DDC_SDA") (pintype "passive"))
    (pad "2" smd roundrect (at 0.48 0) (size 0.59 0.64) (layers "F.Cu" "F.Paste" "F.Mask") (roundrect_rratio 0.25)
      (net 14 "+5V") (pintype "passive"))
  )

  (footprint "antmicro-footprints:TP_SMD_0.75mm" (layer "B.Cu")
    (at 131.4 115 180)
    (property "Author" "Antmicro")
    (property "License" "Apache-2.0")
    (property "MPN" "")
    (property "Manufacturer" "")
    (property "Public" "False")
    (property "Sheetfile" "channel1.kicad_sch")
    (property "Sheetname" "Channel 1")
    (property "exclude_from_bom" "")
    (property "ki_description" "SMT test point")
    (property "ki_keywords" "TESTPOINT")
    (attr exclude_from_pos_files exclude_from_bom)
    (fp_text reference "TP2" (at -2.66 -0.45) (layer "B.SilkS")
        (effects (font (size 0.65 0.65) (thickness 0.13)) (justify left bottom mirror))
    )
    (fp_text value "TP_0.75mm_SMD" (at 0 -1.2) (layer "B.Fab")
        (effects (font (size 0.65 0.65) (thickness 0.13)) (justify left bottom mirror))
    )
    (fp_text user "License: Apache-2.0" (at -0.4 -5.101) (layer "B.Fab") hide
        (effects (font (size 0.7 0.7) (thickness 0.15)) (justify left bottom mirror))
    )
    (fp_text user "${REFERENCE}" (at -0.4 -2.7) (layer "B.Fab") hide
        (effects (font (size 0.7 0.7) (thickness 0.15)) (justify left bottom mirror))
    )
    (fp_text user "Author: Antmicro" (at -0.4 -3.901) (layer "B.Fab") hide
        (effects (font (size 0.7 0.7) (thickness 0.15)) (justify left bottom mirror))
    )
    (pad "1" smd circle (at 0 0 180) (size 0.75 0.75) (layers "B.Cu" "B.Mask")
      (net 117 "Net-(U1A-EDID_SCL)") (pinfunction "1") (pintype "passive"))
  )

  (footprint "antmicro-footprints:R_0603_1608Metric" (layer "B.Cu")
    (at 154.7 113.65 180)
    (descr "Resistor SMD 0603")
    (tags "resistor SMD 0603")
    (property "Author" "Antmicro")
    (property "Current" "1A")
    (property "License" "Apache-2.0")
    (property "MPN" "CR0603-J/-000ELF")
    (property "Manufacturer" "Bourns")
    (property "Public" "False")
    (property "Sheetfile" "channel2.kicad_sch")
    (property "Sheetname" "Channel 2")
    (property "Tolerance" "")
    (property "Val" "0R")
    (property "ki_description" "Zero Ohm Resistor, Jumper, 0603 [1608 Metric], Thick Film, 100 mW, 1 A, Surface Mount Device, CR")
    (property "ki_keywords" "0603, SMT, RESISTOR, PASSIVE")
    (attr smd)
    (fp_text reference "R20" (at 1 -0.45) (layer "B.SilkS")
        (effects (font (size 0.7 0.7) (thickness 0.15)) (justify left bottom mirror))
    )
    (fp_text value "R_0R_0603" (at 0 -1.6) (layer "B.Fab")
        (effects (font (size 0.7 0.7) (thickness 0.15)) (justify left bottom mirror))
    )
    (fp_text user "${REFERENCE}" (at -1.25 -3.898) (layer "B.Fab") hide
        (effects (font (size 0.7 0.7) (thickness 0.15)) (justify left bottom mirror))
    )
    (fp_text user "Author: Antmicro" (at -1.25 -4.9) (layer "B.Fab") hide
        (effects (font (size 0.7 0.7) (thickness 0.15)) (justify left bottom mirror))
    )
    (fp_text user "License: Apache-2.0" (at -1.25 -5.9) (layer "B.Fab") hide
        (effects (font (size 0.7 0.7) (thickness 0.15)) (justify left bottom mirror))
    )
    (fp_line (start -0.15 -0.4) (end 0.15 -0.4)
      (stroke (width 0.15) (type solid)) (layer "B.SilkS"))
    (fp_line (start -0.15 0.4) (end 0.15 0.4)
      (stroke (width 0.15) (type solid)) (layer "B.SilkS"))
    (fp_rect (start -1.25 0.65) (end 1.25 -0.65)
      (stroke (width 0.05) (type solid)) (fill none) (layer "B.CrtYd"))
    (fp_rect (start -0.8 0.4) (end 0.8 -0.4)
      (stroke (width 0.15) (type solid)) (fill none) (layer "B.Fab"))
    (pad "1" smd roundrect (at -0.7 0 180) (size 0.8 1) (layers "B.Cu" "B.Paste" "B.Mask") (roundrect_rratio 0.2)
      (net 26 "Net-(U4B-VDDIO2)") (pintype "passive"))
    (pad "2" smd roundrect (at 0.7 0 180) (size 0.8 1) (layers "B.Cu" "B.Paste" "B.Mask") (roundrect_rratio 0.2)
      (net 9 "+3V3") (pintype "passive"))
  )

  (footprint "antmicro-footprints:C_0402_1005Metric" (layer "B.Cu")
    (at 139.8 110.1 180)
    (descr "Capacitor SMD 0402")
    (tags "capacitor SMD 0402")
    (property "Author" "Antmicro")
    (property "Dielectric" "X5R")
    (property "License" "Apache-2.0")
    (property "MPN" "GRM155R61H104KE14D")
    (property "Manufacturer" "Murata")
    (property "Public" "False")
    (property "Sheetfile" "channel1.kicad_sch")
    (property "Sheetname" "Channel 1")
    (property "Val" "100n")
    (property "Voltage" "50V")
    (property "ki_description" "SMD Multilayer Ceramic Capacitor, 0.1 µF, 50 V, 0402 [1005 Metric], ± 10%, X5R, GRM Series")
    (property "ki_keywords" "0402, SMT, CAPACITOR, PASSIVE, CERAMIC, MLCC")
    (attr smd)
    (fp_text reference "C3" (at 1.05 -0.21) (layer "B.SilkS")
        (effects (font (size 0.65 0.65) (thickness 0.13)) (justify left bottom mirror))
    )
    (fp_text value "C_100n_0402" (at 0 -1.4) (layer "B.Fab")
        (effects (font (size 0.65 0.65) (thickness 0.13)) (justify left bottom mirror))
    )
    (fp_text user "License: Apache-2.0" (at -0.932 -5.17) (layer "B.Fab") hide
        (effects (font (size 0.7 0.7) (thickness 0.15)) (justify left bottom mirror))
    )
    (fp_text user "Author: Antmicro" (at -0.932 -4.17) (layer "B.Fab") hide
        (effects (font (size 0.7 0.7) (thickness 0.15)) (justify left bottom mirror))
    )
    (fp_text user "${REFERENCE}" (at -0.932 -3.168) (layer "B.Fab") hide
        (effects (font (size 0.7 0.7) (thickness 0.15)) (justify left bottom mirror))
    )
    (fp_rect (start -0.925 0.47) (end 0.925 -0.47)
      (stroke (width 0.05) (type default)) (fill none) (layer "B.CrtYd"))
    (fp_line (start -0.494 -0.248) (end -0.494 0.25)
      (stroke (width 0.15) (type solid)) (layer "B.Fab"))
    (fp_line (start -0.494 0.25) (end 0.504 0.25)
      (stroke (width 0.15) (type solid)) (layer "B.Fab"))
    (fp_line (start 0.504 -0.248) (end -0.494 -0.248)
      (stroke (width 0.15) (type solid)) (layer "B.Fab"))
    (fp_line (start 0.504 0.25) (end 0.504 -0.248)
      (stroke (width 0.15) (type solid)) (layer "B.Fab"))
    (pad "1" smd roundrect (at -0.48 0 180) (size 0.59 0.64) (layers "B.Cu" "B.Paste" "B.Mask") (roundrect_rratio 0.25)
      (net 2 "GND") (pintype "passive"))
    (pad "2" smd roundrect (at 0.48 0 180) (size 0.59 0.64) (layers "B.Cu" "B.Paste" "B.Mask") (roundrect_rratio 0.25)
      (net 4 "Net-(U1C-PCKIN)") (pintype "passive"))
  )

  (footprint "antmicro-footprints:TP_SMD_0.75mm" (layer "B.Cu")
    (at 131.4 116.2 180)
    (property "Author" "Antmicro")
    (property "License" "Apache-2.0")
    (property "MPN" "")
    (property "Manufacturer" "")
    (property "Public" "False")
    (property "Sheetfile" "channel1.kicad_sch")
    (property "Sheetname" "Channel 1")
    (property "exclude_from_bom" "")
    (property "ki_description" "SMT test point")
    (property "ki_keywords" "TESTPOINT")
    (attr exclude_from_pos_files exclude_from_bom)
    (fp_text reference "TP1" (at -2.53 -0.38) (layer "B.SilkS")
        (effects (font (size 0.65 0.65) (thickness 0.13)) (justify left bottom mirror))
    )
    (fp_text value "TP_0.75mm_SMD" (at 0 -1.2) (layer "B.Fab")
        (effects (font (size 0.65 0.65) (thickness 0.13)) (justify left bottom mirror))
    )
    (fp_text user "Author: Antmicro" (at -0.4 -3.901) (layer "B.Fab") hide
        (effects (font (size 0.7 0.7) (thickness 0.15)) (justify left bottom mirror))
    )
    (fp_text user "License: Apache-2.0" (at -0.4 -5.101) (layer "B.Fab") hide
        (effects (font (size 0.7 0.7) (thickness 0.15)) (justify left bottom mirror))
    )
    (fp_text user "${REFERENCE}" (at -0.4 -2.7) (layer "B.Fab") hide
        (effects (font (size 0.7 0.7) (thickness 0.15)) (justify left bottom mirror))
    )
    (pad "1" smd circle (at 0 0 180) (size 0.75 0.75) (layers "B.Cu" "B.Mask")
      (net 116 "Net-(U1A-EDID_SDA)") (pinfunction "1") (pintype "passive"))
  )

  (footprint "antmicro-footprints:TP_SMD_0.75mm" (layer "B.Cu")
    (at 155.4 116.2508 180)
    (property "Author" "Antmicro")
    (property "License" "Apache-2.0")
    (property "MPN" "")
    (property "Manufacturer" "")
    (property "Public" "False")
    (property "Sheetfile" "channel2.kicad_sch")
    (property "Sheetname" "Channel 2")
    (property "exclude_from_bom" "")
    (property "ki_description" "SMT test point")
    (property "ki_keywords" "TESTPOINT")
    (attr exclude_from_pos_files exclude_from_bom)
    (fp_text reference "TP5" (at -2.68 -0.3692) (layer "B.SilkS")
        (effects (font (size 0.65 0.65) (thickness 0.13)) (justify left bottom mirror))
    )
    (fp_text value "TP_0.75mm_SMD" (at 0 -1.2) (layer "B.Fab")
        (effects (font (size 0.65 0.65) (thickness 0.13)) (justify left bottom mirror))
    )
    (fp_text user "Author: Antmicro" (at -0.4 -3.901) (layer "B.Fab") hide
        (effects (font (size 0.7 0.7) (thickness 0.15)) (justify left bottom mirror))
    )
    (fp_text user "License: Apache-2.0" (at -0.4 -5.101) (layer "B.Fab") hide
        (effects (font (size 0.7 0.7) (thickness 0.15)) (justify left bottom mirror))
    )
    (fp_text user "${REFERENCE}" (at -0.4 -2.7) (layer "B.Fab") hide
        (effects (font (size 0.7 0.7) (thickness 0.15)) (justify left bottom mirror))
    )
    (pad "1" smd circle (at 0 0 180) (size 0.75 0.75) (layers "B.Cu" "B.Mask")
      (net 120 "Net-(U4A-EDID_SDA)") (pinfunction "1") (pintype "passive"))
  )

  (footprint "antmicro-footprints:R_0402_1005Metric" (layer "B.Cu")
    (at 131.1 112.2 180)
    (descr "Resistor SMD 0402")
    (tags "resistor SMD 0402")
    (property "Author" "Antmicro")
    (property "License" "Apache-2.0")
    (property "MPN" "CR0402-FX-1002GLF")
    (property "Manufacturer" "Bourns")
    (property "Public" "False")
    (property "Sheetfile" "channel1.kicad_sch")
    (property "Sheetname" "Channel 1")
    (property "Tolerance" "1%")
    (property "Val" "10k")
    (property "ki_description" "SMD Chip Resistor, 10 kohm, ± 1%, 62.5 mW, 0402 [1005 Metric], Thick Film, General Purpose")
    (property "ki_keywords" "0402, SMT, RESISTOR, PASSIVE")
    (attr smd)
    (fp_text reference "R3" (at 0.8 -0.3) (layer "B.SilkS")
        (effects (font (size 0.65 0.65) (thickness 0.13)) (justify left bottom mirror))
    )
    (fp_text value "R_10k_0402" (at 0 -1.4) (layer "B.Fab")
        (effects (font (size 0.65 0.65) (thickness 0.13)) (justify left bottom mirror))
    )
    (fp_text user "License: Apache-2.0" (at -0.95 -5.169) (layer "B.Fab") hide
        (effects (font (size 0.7 0.7) (thickness 0.15)) (justify left bottom mirror))
    )
    (fp_text user "Author: Antmicro" (at -0.95 -4.169) (layer "B.Fab") hide
        (effects (font (size 0.7 0.7) (thickness 0.15)) (justify left bottom mirror))
    )
    (fp_text user "${REFERENCE}" (at -0.95 -3.168) (layer "B.Fab") hide
        (effects (font (size 0.7 0.7) (thickness 0.15)) (justify left bottom mirror))
    )
    (fp_rect (start -0.925 0.47) (end 0.925 -0.47)
      (stroke (width 0.05) (type default)) (fill none) (layer "B.CrtYd"))
    (fp_rect (start -0.5 0.25) (end 0.5 -0.25)
      (stroke (width 0.15) (type solid)) (fill none) (layer "B.Fab"))
    (pad "1" smd roundrect (at -0.48 0 180) (size 0.59 0.64) (layers "B.Cu" "B.Paste" "B.Mask") (roundrect_rratio 0.25)
      (net 98 "/Channel 1/CH1_~{RST}") (pintype "passive"))
    (pad "2" smd roundrect (at 0.48 0 180) (size 0.59 0.64) (layers "B.Cu" "B.Paste" "B.Mask") (roundrect_rratio 0.25)
      (net 9 "+3V3") (pintype "passive"))
  )

  (footprint "antmicro-footprints:TP_SMD_0.75mm" (layer "B.Cu")
    (at 167.7 102.4508 180)
    (property "Author" "Antmicro")
    (property "License" "Apache-2.0")
    (property "MPN" "")
    (property "Manufacturer" "")
    (property "Public" "False")
    (property "Sheetfile" "channel2.kicad_sch")
    (property "Sheetname" "Channel 2")
    (property "exclude_from_bom" "")
    (property "ki_description" "SMT test point")
    (property "ki_keywords" "TESTPOINT")
    (attr exclude_from_pos_files exclude_from_bom)
    (fp_text reference "TP8" (at 0 0.6) (layer "B.SilkS")
        (effects (font (size 0.65 0.65) (thickness 0.13)) (justify left bottom mirror))
    )
    (fp_text value "TP_0.75mm_SMD" (at 0 -1.2) (layer "B.Fab")
        (effects (font (size 0.65 0.65) (thickness 0.13)) (justify left bottom mirror))
    )
    (fp_text user "Author: Antmicro" (at -0.4 -3.901) (layer "B.Fab") hide
        (effects (font (size 0.7 0.7) (thickness 0.15)) (justify left bottom mirror))
    )
    (fp_text user "License: Apache-2.0" (at -0.4 -5.101) (layer "B.Fab") hide
        (effects (font (size 0.7 0.7) (thickness 0.15)) (justify left bottom mirror))
    )
    (fp_text user "${REFERENCE}" (at -0.4 -2.7) (layer "B.Fab") hide
        (effects (font (size 0.7 0.7) (thickness 0.15)) (justify left bottom mirror))
    )
    (pad "1" smd circle (at 0 0 180) (size 0.75 0.75) (layers "B.Cu" "B.Mask")
      (net 122 "Net-(U6-EN)") (pinfunction "1") (pintype "passive"))
  )

  (footprint "antmicro-footprints:C_0402_1005Metric" (layer "B.Cu")
    (at 163.8 108.15 180)
    (descr "Capacitor SMD 0402")
    (tags "capacitor SMD 0402")
    (property "Author" "Antmicro")
    (property "Dielectric" "X5R")
    (property "License" "Apache-2.0")
    (property "MPN" "GRM155R61H104KE14D")
    (property "Manufacturer" "Murata")
    (property "Public" "False")
    (property "Sheetfile" "channel2.kicad_sch")
    (property "Sheetname" "Channel 2")
    (property "Val" "100n")
    (property "Voltage" "50V")
    (property "ki_description" "SMD Multilayer Ceramic Capacitor, 0.1 µF, 50 V, 0402 [1005 Metric], ± 10%, X5R, GRM Series")
    (property "ki_keywords" "0402, SMT, CAPACITOR, PASSIVE, CERAMIC, MLCC")
    (attr smd)
    (fp_text reference "C24" (at 0.9 -0.35) (layer "B.SilkS")
        (effects (font (size 0.65 0.65) (thickness 0.13)) (justify left bottom mirror))
    )
    (fp_text value "C_100n_0402" (at 0 -1.4) (layer "B.Fab")
        (effects (font (size 0.65 0.65) (thickness 0.13)) (justify left bottom mirror))
    )
    (fp_text user "${REFERENCE}" (at -0.932 -3.168) (layer "B.Fab") hide
        (effects (font (size 0.7 0.7) (thickness 0.15)) (justify left bottom mirror))
    )
    (fp_text user "Author: Antmicro" (at -0.932 -4.17) (layer "B.Fab") hide
        (effects (font (size 0.7 0.7) (thickness 0.15)) (justify left bottom mirror))
    )
    (fp_text user "License: Apache-2.0" (at -0.932 -5.17) (layer "B.Fab") hide
        (effects (font (size 0.7 0.7) (thickness 0.15)) (justify left bottom mirror))
    )
    (fp_rect (start -0.925 0.47) (end 0.925 -0.47)
      (stroke (width 0.05) (type default)) (fill none) (layer "B.CrtYd"))
    (fp_line (start -0.494 -0.248) (end -0.494 0.25)
      (stroke (width 0.15) (type solid)) (layer "B.Fab"))
    (fp_line (start -0.494 0.25) (end 0.504 0.25)
      (stroke (width 0.15) (type solid)) (layer "B.Fab"))
    (fp_line (start 0.504 -0.248) (end -0.494 -0.248)
      (stroke (width 0.15) (type solid)) (layer "B.Fab"))
    (fp_line (start 0.504 0.25) (end 0.504 -0.248)
      (stroke (width 0.15) (type solid)) (layer "B.Fab"))
    (pad "1" smd roundrect (at -0.48 0 180) (size 0.59 0.64) (layers "B.Cu" "B.Paste" "B.Mask") (roundrect_rratio 0.25)
      (net 2 "GND") (pintype "passive"))
    (pad "2" smd roundrect (at 0.48 0 180) (size 0.59 0.64) (layers "B.Cu" "B.Paste" "B.Mask") (roundrect_rratio 0.25)
      (net 16 "Net-(U4C-BIASDA)") (pintype "passive"))
  )

  (footprint "antmicro-footprints:C_0402_1005Metric" (layer "B.Cu")
    (at 163.8 109.15 180)
    (descr "Capacitor SMD 0402")
    (tags "capacitor SMD 0402")
    (property "Author" "Antmicro")
    (property "Dielectric" "X5R")
    (property "License" "Apache-2.0")
    (property "MPN" "GRM155R61H104KE14D")
    (property "Manufacturer" "Murata")
    (property "Public" "False")
    (property "Sheetfile" "channel2.kicad_sch")
    (property "Sheetname" "Channel 2")
    (property "Val" "100n")
    (property "Voltage" "50V")
    (property "ki_description" "SMD Multilayer Ceramic Capacitor, 0.1 µF, 50 V, 0402 [1005 Metric], ± 10%, X5R, GRM Series")
    (property "ki_keywords" "0402, SMT, CAPACITOR, PASSIVE, CERAMIC, MLCC")
    (attr smd)
    (fp_text reference "C25" (at 0.92 -0.29) (layer "B.SilkS")
        (effects (font (size 0.65 0.65) (thickness 0.13)) (justify left bottom mirror))
    )
    (fp_text value "C_100n_0402" (at 0 -1.4) (layer "B.Fab")
        (effects (font (size 0.65 0.65) (thickness 0.13)) (justify left bottom mirror))
    )
    (fp_text user "License: Apache-2.0" (at -0.932 -5.17) (layer "B.Fab") hide
        (effects (font (size 0.7 0.7) (thickness 0.15)) (justify left bottom mirror))
    )
    (fp_text user "${REFERENCE}" (at -0.932 -3.168) (layer "B.Fab") hide
        (effects (font (size 0.7 0.7) (thickness 0.15)) (justify left bottom mirror))
    )
    (fp_text user "Author: Antmicro" (at -0.932 -4.17) (layer "B.Fab") hide
        (effects (font (size 0.7 0.7) (thickness 0.15)) (justify left bottom mirror))
    )
    (fp_rect (start -0.925 0.47) (end 0.925 -0.47)
      (stroke (width 0.05) (type default)) (fill none) (layer "B.CrtYd"))
    (fp_line (start -0.494 -0.248) (end -0.494 0.25)
      (stroke (width 0.15) (type solid)) (layer "B.Fab"))
    (fp_line (start -0.494 0.25) (end 0.504 0.25)
      (stroke (width 0.15) (type solid)) (layer "B.Fab"))
    (fp_line (start 0.504 -0.248) (end -0.494 -0.248)
      (stroke (width 0.15) (type solid)) (layer "B.Fab"))
    (fp_line (start 0.504 0.25) (end 0.504 -0.248)
      (stroke (width 0.15) (type solid)) (layer "B.Fab"))
    (pad "1" smd roundrect (at -0.48 0 180) (size 0.59 0.64) (layers "B.Cu" "B.Paste" "B.Mask") (roundrect_rratio 0.25)
      (net 2 "GND") (pintype "passive"))
    (pad "2" smd roundrect (at 0.48 0 180) (size 0.59 0.64) (layers "B.Cu" "B.Paste" "B.Mask") (roundrect_rratio 0.25)
      (net 17 "Net-(U4C-DAOUT)") (pintype "passive"))
  )

  (footprint "antmicro-footprints:R_0603_1608Metric" (layer "B.Cu")
    (at 154.8 110.9 180)
    (descr "Resistor SMD 0603")
    (tags "resistor SMD 0603")
    (property "Author" "Antmicro")
    (property "Current" "1A")
    (property "License" "Apache-2.0")
    (property "MPN" "CR0603-J/-000ELF")
    (property "Manufacturer" "Bourns")
    (property "Public" "False")
    (property "Sheetfile" "channel2.kicad_sch")
    (property "Sheetname" "Channel 2")
    (property "Tolerance" "")
    (property "Val" "0R")
    (property "ki_description" "Zero Ohm Resistor, Jumper, 0603 [1608 Metric], Thick Film, 100 mW, 1 A, Surface Mount Device, CR")
    (property "ki_keywords" "0603, SMT, RESISTOR, PASSIVE")
    (attr smd)
    (fp_text reference "R19" (at 1 -0.4) (layer "B.SilkS")
        (effects (font (size 0.7 0.7) (thickness 0.15)) (justify left bottom mirror))
    )
    (fp_text value "R_0R_0603" (at 0 -1.6) (layer "B.Fab")
        (effects (font (size 0.7 0.7) (thickness 0.15)) (justify left bottom mirror))
    )
    (fp_text user "${REFERENCE}" (at -1.25 -3.898) (layer "B.Fab") hide
        (effects (font (size 0.7 0.7) (thickness 0.15)) (justify left bottom mirror))
    )
    (fp_text user "License: Apache-2.0" (at -1.25 -5.9) (layer "B.Fab") hide
        (effects (font (size 0.7 0.7) (thickness 0.15)) (justify left bottom mirror))
    )
    (fp_text user "Author: Antmicro" (at -1.25 -4.9) (layer "B.Fab") hide
        (effects (font (size 0.7 0.7) (thickness 0.15)) (justify left bottom mirror))
    )
    (fp_line (start -0.15 -0.4) (end 0.15 -0.4)
      (stroke (width 0.15) (type solid)) (layer "B.SilkS"))
    (fp_line (start -0.15 0.4) (end 0.15 0.4)
      (stroke (width 0.15) (type solid)) (layer "B.SilkS"))
    (fp_rect (start -1.25 0.65) (end 1.25 -0.65)
      (stroke (width 0.05) (type solid)) (fill none) (layer "B.CrtYd"))
    (fp_rect (start -0.8 0.4) (end 0.8 -0.4)
      (stroke (width 0.15) (type solid)) (fill none) (layer "B.Fab"))
    (pad "1" smd roundrect (at -0.7 0 180) (size 0.8 1) (layers "B.Cu" "B.Paste" "B.Mask") (roundrect_rratio 0.2)
      (net 23 "Net-(U4B-VDDIO1)") (pintype "passive"))
    (pad "2" smd roundrect (at 0.7 0 180) (size 0.8 1) (layers "B.Cu" "B.Paste" "B.Mask") (roundrect_rratio 0.2)
      (net 9 "+3V3") (pintype "passive"))
  )

  (footprint "antmicro-footprints:TP_SMD_0.75mm" (layer "B.Cu")
    (at 130.3 103.1 180)
    (property "Author" "Antmicro")
    (property "License" "Apache-2.0")
    (property "MPN" "")
    (property "Manufacturer" "")
    (property "Public" "False")
    (property "Sheetfile" "channel1.kicad_sch")
    (property "Sheetname" "Channel 1")
    (property "exclude_from_bom" "")
    (property "ki_description" "SMT test point")
    (property "ki_keywords" "TESTPOINT")
    (attr exclude_from_pos_files exclude_from_bom)
    (fp_text reference "TP3" (at 0 0.6) (layer "B.SilkS")
        (effects (font (size 0.65 0.65) (thickness 0.13)) (justify left bottom mirror))
    )
    (fp_text value "TP_0.75mm_SMD" (at 0 -1.2) (layer "B.Fab")
        (effects (font (size 0.65 0.65) (thickness 0.13)) (justify left bottom mirror))
    )
    (fp_text user "License: Apache-2.0" (at -0.4 -5.101) (layer "B.Fab") hide
        (effects (font (size 0.7 0.7) (thickness 0.15)) (justify left bottom mirror))
    )
    (fp_text user "Author: Antmicro" (at -0.4 -3.901) (layer "B.Fab") hide
        (effects (font (size 0.7 0.7) (thickness 0.15)) (justify left bottom mirror))
    )
    (fp_text user "${REFERENCE}" (at -0.4 -2.7) (layer "B.Fab") hide
        (effects (font (size 0.7 0.7) (thickness 0.15)) (justify left bottom mirror))
    )
    (pad "1" smd circle (at 0 0 180) (size 0.75 0.75) (layers "B.Cu" "B.Mask")
      (net 115 "/Channel 1/HDMI1_HPDO") (pinfunction "1") (pintype "passive"))
  )

  (footprint "antmicro-footprints:C_0402_1005Metric" (layer "B.Cu")
    (at 139.8 109.1 180)
    (descr "Capacitor SMD 0402")
    (tags "capacitor SMD 0402")
    (property "Author" "Antmicro")
    (property "Dielectric" "X5R")
    (property "License" "Apache-2.0")
    (property "MPN" "GRM155R61H104KE14D")
    (property "Manufacturer" "Murata")
    (property "Public" "False")
    (property "Sheetfile" "channel1.kicad_sch")
    (property "Sheetname" "Channel 1")
    (property "Val" "100n")
    (property "Voltage" "50V")
    (property "ki_description" "SMD Multilayer Ceramic Capacitor, 0.1 µF, 50 V, 0402 [1005 Metric], ± 10%, X5R, GRM Series")
    (property "ki_keywords" "0402, SMT, CAPACITOR, PASSIVE, CERAMIC, MLCC")
    (attr smd)
    (fp_text reference "C2" (at 1.02 -0.25) (layer "B.SilkS")
        (effects (font (size 0.65 0.65) (thickness 0.13)) (justify left bottom mirror))
    )
    (fp_text value "C_100n_0402" (at 0 -1.4) (layer "B.Fab")
        (effects (font (size 0.65 0.65) (thickness 0.13)) (justify left bottom mirror))
    )
    (fp_text user "Author: Antmicro" (at -0.932 -4.17) (layer "B.Fab") hide
        (effects (font (size 0.7 0.7) (thickness 0.15)) (justify left bottom mirror))
    )
    (fp_text user "${REFERENCE}" (at -0.932 -3.168) (layer "B.Fab") hide
        (effects (font (size 0.7 0.7) (thickness 0.15)) (justify left bottom mirror))
    )
    (fp_text user "License: Apache-2.0" (at -0.932 -5.17) (layer "B.Fab") hide
        (effects (font (size 0.7 0.7) (thickness 0.15)) (justify left bottom mirror))
    )
    (fp_rect (start -0.925 0.47) (end 0.925 -0.47)
      (stroke (width 0.05) (type default)) (fill none) (layer "B.CrtYd"))
    (fp_line (start -0.494 -0.248) (end -0.494 0.25)
      (stroke (width 0.15) (type solid)) (layer "B.Fab"))
    (fp_line (start -0.494 0.25) (end 0.504 0.25)
      (stroke (width 0.15) (type solid)) (layer "B.Fab"))
    (fp_line (start 0.504 -0.248) (end -0.494 -0.248)
      (stroke (width 0.15) (type solid)) (layer "B.Fab"))
    (fp_line (start 0.504 0.25) (end 0.504 -0.248)
      (stroke (width 0.15) (type solid)) (layer "B.Fab"))
    (pad "1" smd roundrect (at -0.48 0 180) (size 0.59 0.64) (layers "B.Cu" "B.Paste" "B.Mask") (roundrect_rratio 0.25)
      (net 2 "GND") (pintype "passive"))
    (pad "2" smd roundrect (at 0.48 0 180) (size 0.59 0.64) (layers "B.Cu" "B.Paste" "B.Mask") (roundrect_rratio 0.25)
      (net 3 "Net-(U1C-DAOUT)") (pintype "passive"))
  )

  (footprint "antmicro-footprints:R_0402_1005Metric" (layer "B.Cu")
    (at 155.1 112.25 180)
    (descr "Resistor SMD 0402")
    (tags "resistor SMD 0402")
    (property "Author" "Antmicro")
    (property "License" "Apache-2.0")
    (property "MPN" "CR0402-FX-1002GLF")
    (property "Manufacturer" "Bourns")
    (property "Public" "False")
    (property "Sheetfile" "channel2.kicad_sch")
    (property "Sheetname" "Channel 2")
    (property "Tolerance" "1%")
    (property "Val" "10k")
    (property "ki_description" "SMD Chip Resistor, 10 kohm, ± 1%, 62.5 mW, 0402 [1005 Metric], Thick Film, General Purpose")
    (property "ki_keywords" "0402, SMT, RESISTOR, PASSIVE")
    (attr smd)
    (fp_text reference "R16" (at 0.8 -0.35) (layer "B.SilkS")
        (effects (font (size 0.65 0.65) (thickness 0.13)) (justify left bottom mirror))
    )
    (fp_text value "R_10k_0402" (at 0 -1.4) (layer "B.Fab")
        (effects (font (size 0.65 0.65) (thickness 0.13)) (justify left bottom mirror))
    )
    (fp_text user "${REFERENCE}" (at -0.95 -3.168) (layer "B.Fab") hide
        (effects (font (size 0.7 0.7) (thickness 0.15)) (justify left bottom mirror))
    )
    (fp_text user "Author: Antmicro" (at -0.95 -4.169) (layer "B.Fab") hide
        (effects (font (size 0.7 0.7) (thickness 0.15)) (justify left bottom mirror))
    )
    (fp_text user "License: Apache-2.0" (at -0.95 -5.169) (layer "B.Fab") hide
        (effects (font (size 0.7 0.7) (thickness 0.15)) (justify left bottom mirror))
    )
    (fp_rect (start -0.925 0.47) (end 0.925 -0.47)
      (stroke (width 0.05) (type default)) (fill none) (layer "B.CrtYd"))
    (fp_rect (start -0.5 0.25) (end 0.5 -0.25)
      (stroke (width 0.15) (type solid)) (fill none) (layer "B.Fab"))
    (pad "1" smd roundrect (at -0.48 0 180) (size 0.59 0.64) (layers "B.Cu" "B.Paste" "B.Mask") (roundrect_rratio 0.25)
      (net 107 "/Channel 2/CH2_~{RST}") (pintype "passive"))
    (pad "2" smd roundrect (at 0.48 0 180) (size 0.59 0.64) (layers "B.Cu" "B.Paste" "B.Mask") (roundrect_rratio 0.25)
      (net 9 "+3V3") (pintype "passive"))
  )

  (footprint "antmicro-footprints:Spacer_Drill3.7mm_H6mm_9774060151R" (layer "B.Cu")
    (at 179 131 180)
    (property "Author" "Antmicro")
    (property "License" "Apache-2.0")
    (property "MPN" "9774060151R")
    (property "Manufacturer" "Würth Elektronik")
    (property "Public" "False")
    (property "Sheetfile" "csi.kicad_sch")
    (property "Sheetname" "CSI")
    (property "ki_description" "Spacer, SMT, Non Stop, Steel, Swage Round, 5.1 mm x 6 mm, M2.5 Thread, WA-SMSI Series")
    (property "ki_keywords" "MECHANICAL, SPACER")
    (attr smd)
    (fp_text reference "SP3" (at 0 3.2) (layer "B.SilkS") hide
        (effects (font (size 0.7 0.7) (thickness 0.15)) (justify left bottom mirror))
    )
    (fp_text value "Spacer_Drill3.7mm_H6mm_9774060151R" (at 0 -4) (layer "B.Fab")
        (effects (font (size 0.7 0.7) (thickness 0.15)) (justify left bottom mirror))
    )
    (fp_text user "${REFERENCE}" (at -2.551 -5.25) (layer "B.Fab") hide
        (effects (font (size 0.7 0.7) (thickness 0.15)) (justify left bottom mirror))
    )
    (fp_text user "License: Apache-2.0" (at -2.551 -7.75) (layer "B.Fab") hide
        (effects (font (size 0.7 0.7) (thickness 0.15)) (justify left bottom mirror))
    )
    (fp_text user "Author: Antmicro" (at -2.551 -6.5) (layer "B.Fab") hide
        (effects (font (size 0.7 0.7) (thickness 0.15)) (justify left bottom mirror))
    )
    (fp_circle (center 0 0) (end 3.05 0)
      (stroke (width 0.05) (type solid)) (fill none) (layer "B.CrtYd"))
    (fp_circle (center -0.001 0) (end 2.548 0)
      (stroke (width 0.15) (type solid)) (fill none) (layer "B.Fab"))
    (pad "" smd custom (at -1.71 -1.699 90) (size 0.62 0.62) (layers "B.Paste")
      (thermal_bridge_angle 90)
      (options (clearance outline) (anchor circle))
      (primitives
        (gr_arc (start 1.266786 0.24747) (mid 0.285453 -0.29439) (end -0.250195 -1.279127) (width 0.2))
        (gr_arc (start 1.259603 0.339191) (mid 0.218448 -0.232561) (end -0.34334 -1.279127) (width 0.2))
        (gr_arc (start 1.255279 0.431435) (mid 0.152481 -0.169693) (end -0.436309 -1.279127) (width 0.2))
        (gr_arc (start 1.253811 0.524161) (mid 0.087542 -0.105784) (end -0.529126 -1.279127) (width 0.2))
        (gr_arc (start 1.275473 0.621136) (mid 0.0309 -0.033527) (end -0.621807 -1.279127) (width 0.2))
        (gr_arc (start 1.263664 0.711602) (mid -0.037759 0.026651) (end -0.71437 -1.279127) (width 0.2))
        (gr_arc (start 1.253435 0.802342) (mid -0.105837 0.087395) (end -0.806826 -1.279127) (width 0.2))
        (gr_arc (start 1.267475 0.897258) (mid -0.165236 0.156885) (end -0.899187 -1.279127) (width 0.2))
        (gr_arc (start 1.270645 0.990112) (mid -0.228522 0.222449) (end -0.991463 -1.279127) (width 0.2))
        (gr_arc (start 1.266278 1.081674) (mid -0.294507 0.285313) (end -1.083663 -1.279127) (width 0.2))
        (gr_line (start 1.279127 1.083663) (end 1.279127 0.250195) (width 0.2))
        (gr_line (start -1.083663 -1.279127) (end -0.250195 -1.279127) (width 0.2))
      ))
    (pad "" smd custom (at -1.71 1.71 180) (size 0.62 0.62) (layers "B.Paste")
      (thermal_bridge_angle 90)
      (options (clearance outline) (anchor circle))
      (primitives
        (gr_arc (start 1.266786 0.24747) (mid 0.285453 -0.29439) (end -0.250195 -1.279127) (width 0.2))
        (gr_arc (start 1.259603 0.339191) (mid 0.218448 -0.232561) (end -0.34334 -1.279127) (width 0.2))
        (gr_arc (start 1.255279 0.431435) (mid 0.152481 -0.169693) (end -0.436309 -1.279127) (width 0.2))
        (gr_arc (start 1.253811 0.524161) (mid 0.087542 -0.105784) (end -0.529126 -1.279127) (width 0.2))
        (gr_arc (start 1.275473 0.621136) (mid 0.0309 -0.033527) (end -0.621807 -1.279127) (width 0.2))
        (gr_arc (start 1.263664 0.711602) (mid -0.037759 0.026651) (end -0.71437 -1.279127) (width 0.2))
        (gr_arc (start 1.253435 0.802342) (mid -0.105837 0.087395) (end -0.806826 -1.279127) (width 0.2))
        (gr_arc (start 1.267475 0.897258) (mid -0.165236 0.156885) (end -0.899187 -1.279127) (width 0.2))
        (gr_arc (start 1.270645 0.990112) (mid -0.228522 0.222449) (end -0.991463 -1.279127) (width 0.2))
        (gr_arc (start 1.266278 1.081674) (mid -0.294507 0.285313) (end -1.083663 -1.279127) (width 0.2))
        (gr_line (start 1.279127 1.083663) (end 1.279127 0.250195) (width 0.2))
        (gr_line (start -1.083663 -1.279127) (end -0.250195 -1.279127) (width 0.2))
      ))
    (pad "" smd custom (at 1.699 -1.699) (size 0.62 0.62) (layers "B.Paste")
      (thermal_bridge_angle 90)
      (options (clearance outline) (anchor circle))
      (primitives
        (gr_arc (start 1.266786 0.24747) (mid 0.285453 -0.29439) (end -0.250195 -1.279127) (width 0.2))
        (gr_arc (start 1.259603 0.339191) (mid 0.218448 -0.232561) (end -0.34334 -1.279127) (width 0.2))
        (gr_arc (start 1.255279 0.431435) (mid 0.152481 -0.169693) (end -0.436309 -1.279127) (width 0.2))
        (gr_arc (start 1.253811 0.524161) (mid 0.087542 -0.105784) (end -0.529126 -1.279127) (width 0.2))
        (gr_arc (start 1.275473 0.621136) (mid 0.0309 -0.033527) (end -0.621807 -1.279127) (width 0.2))
        (gr_arc (start 1.263664 0.711602) (mid -0.037759 0.026651) (end -0.71437 -1.279127) (width 0.2))
        (gr_arc (start 1.253435 0.802342) (mid -0.105837 0.087395) (end -0.806826 -1.279127) (width 0.2))
        (gr_arc (start 1.267475 0.897258) (mid -0.165236 0.156885) (end -0.899187 -1.279127) (width 0.2))
        (gr_arc (start 1.270645 0.990112) (mid -0.228522 0.222449) (end -0.991463 -1.279127) (width 0.2))
        (gr_arc (start 1.266278 1.081674) (mid -0.294507 0.285313) (end -1.083663 -1.279127) (width 0.2))
        (gr_line (start 1.279127 1.083663) (end 1.279127 0.250195) (width 0.2))
        (gr_line (start -1.083663 -1.279127) (end -0.250195 -1.279127) (width 0.2))
      ))
    (pad "" smd custom (at 1.699 1.71 270) (size 0.62 0.62) (layers "B.Paste")
      (thermal_bridge_angle 90)
      (options (clearance outline) (anchor circle))
      (primitives
        (gr_arc (start 1.266786 0.24747) (mid 0.285453 -0.29439) (end -0.250195 -1.279127) (width 0.2))
        (gr_arc (start 1.259603 0.339191) (mid 0.218448 -0.232561) (end -0.34334 -1.279127) (width 0.2))
        (gr_arc (start 1.255279 0.431435) (mid 0.152481 -0.169693) (end -0.436309 -1.279127) (width 0.2))
        (gr_arc (start 1.253811 0.524161) (mid 0.087542 -0.105784) (end -0.529126 -1.279127) (width 0.2))
        (gr_arc (start 1.275473 0.621136) (mid 0.0309 -0.033527) (end -0.621807 -1.279127) (width 0.2))
        (gr_arc (start 1.263664 0.711602) (mid -0.037759 0.026651) (end -0.71437 -1.279127) (width 0.2))
        (gr_arc (start 1.253435 0.802342) (mid -0.105837 0.087395) (end -0.806826 -1.279127) (width 0.2))
        (gr_arc (start 1.267475 0.897258) (mid -0.165236 0.156885) (end -0.899187 -1.279127) (width 0.2))
        (gr_arc (start 1.270645 0.990112) (mid -0.228522 0.222449) (end -0.991463 -1.279127) (width 0.2))
        (gr_arc (start 1.266278 1.081674) (mid -0.294507 0.285313) (end -1.083663 -1.279127) (width 0.2))
        (gr_line (start 1.279127 1.083663) (end 1.279127 0.250195) (width 0.2))
        (gr_line (start -1.083663 -1.279127) (end -0.250195 -1.279127) (width 0.2))
      ))
    (pad "1" thru_hole circle (at -0.001 0 180) (size 6 6) (drill 3.7) (layers "*.Cu" "*.Mask")
      (net 2 "GND") (pintype "passive") (solder_paste_margin_ratio -0.05))
  )

  (footprint "antmicro-footprints:C_0402_1005Metric" (layer "B.Cu")
    (at 139.8 108.1 180)
    (descr "Capacitor SMD 0402")
    (tags "capacitor SMD 0402")
    (property "Author" "Antmicro")
    (property "Dielectric" "X5R")
    (property "License" "Apache-2.0")
    (property "MPN" "GRM155R61H104KE14D")
    (property "Manufacturer" "Murata")
    (property "Public" "False")
    (property "Sheetfile" "channel1.kicad_sch")
    (property "Sheetname" "Channel 1")
    (property "Val" "100n")
    (property "Voltage" "50V")
    (property "ki_description" "SMD Multilayer Ceramic Capacitor, 0.1 µF, 50 V, 0402 [1005 Metric], ± 10%, X5R, GRM Series")
    (property "ki_keywords" "0402, SMT, CAPACITOR, PASSIVE, CERAMIC, MLCC")
    (attr smd)
    (fp_text reference "C1" (at 1 -0.4) (layer "B.SilkS")
        (effects (font (size 0.65 0.65) (thickness 0.13)) (justify left bottom mirror))
    )
    (fp_text value "C_100n_0402" (at 0 -1.4) (layer "B.Fab")
        (effects (font (size 0.65 0.65) (thickness 0.13)) (justify left bottom mirror))
    )
    (fp_text user "${REFERENCE}" (at -0.932 -3.168) (layer "B.Fab") hide
        (effects (font (size 0.7 0.7) (thickness 0.15)) (justify left bottom mirror))
    )
    (fp_text user "License: Apache-2.0" (at -0.932 -5.17) (layer "B.Fab") hide
        (effects (font (size 0.7 0.7) (thickness 0.15)) (justify left bottom mirror))
    )
    (fp_text user "Author: Antmicro" (at -0.932 -4.17) (layer "B.Fab") hide
        (effects (font (size 0.7 0.7) (thickness 0.15)) (justify left bottom mirror))
    )
    (fp_rect (start -0.925 0.47) (end 0.925 -0.47)
      (stroke (width 0.05) (type default)) (fill none) (layer "B.CrtYd"))
    (fp_line (start -0.494 -0.248) (end -0.494 0.25)
      (stroke (width 0.15) (type solid)) (layer "B.Fab"))
    (fp_line (start -0.494 0.25) (end 0.504 0.25)
      (stroke (width 0.15) (type solid)) (layer "B.Fab"))
    (fp_line (start 0.504 -0.248) (end -0.494 -0.248)
      (stroke (width 0.15) (type solid)) (layer "B.Fab"))
    (fp_line (start 0.504 0.25) (end 0.504 -0.248)
      (stroke (width 0.15) (type solid)) (layer "B.Fab"))
    (pad "1" smd roundrect (at -0.48 0 180) (size 0.59 0.64) (layers "B.Cu" "B.Paste" "B.Mask") (roundrect_rratio 0.25)
      (net 2 "GND") (pintype "passive"))
    (pad "2" smd roundrect (at 0.48 0 180) (size 0.59 0.64) (layers "B.Cu" "B.Paste" "B.Mask") (roundrect_rratio 0.25)
      (net 1 "Net-(U1C-BIASDA)") (pintype "passive"))
  )

  (footprint "antmicro-footprints:TP_SMD_0.75mm" (layer "B.Cu")
    (at 154.3 103.1 180)
    (property "Author" "Antmicro")
    (property "License" "Apache-2.0")
    (property "MPN" "")
    (property "Manufacturer" "")
    (property "Public" "False")
    (property "Sheetfile" "channel2.kicad_sch")
    (property "Sheetname" "Channel 2")
    (property "exclude_from_bom" "")
    (property "ki_description" "SMT test point")
    (property "ki_keywords" "TESTPOINT")
    (attr exclude_from_pos_files exclude_from_bom)
    (fp_text reference "TP7" (at 0 0.6) (layer "B.SilkS")
        (effects (font (size 0.65 0.65) (thickness 0.13)) (justify left bottom mirror))
    )
    (fp_text value "TP_0.75mm_SMD" (at 0 -1.2) (layer "B.Fab")
        (effects (font (size 0.65 0.65) (thickness 0.13)) (justify left bottom mirror))
    )
    (fp_text user "${REFERENCE}" (at -0.4 -2.7) (layer "B.Fab") hide
        (effects (font (size 0.7 0.7) (thickness 0.15)) (justify left bottom mirror))
    )
    (fp_text user "Author: Antmicro" (at -0.4 -3.901) (layer "B.Fab") hide
        (effects (font (size 0.7 0.7) (thickness 0.15)) (justify left bottom mirror))
    )
    (fp_text user "License: Apache-2.0" (at -0.4 -5.101) (layer "B.Fab") hide
        (effects (font (size 0.7 0.7) (thickness 0.15)) (justify left bottom mirror))
    )
    (pad "1" smd circle (at 0 0 180) (size 0.75 0.75) (layers "B.Cu" "B.Mask")
      (net 119 "/Channel 2/HDMI2_HPDO") (pinfunction "1") (pintype "passive"))
  )

  (footprint "antmicro-footprints:R_0603_1608Metric" (layer "B.Cu")
    (at 130.7 113.6 180)
    (descr "Resistor SMD 0603")
    (tags "resistor SMD 0603")
    (property "Author" "Antmicro")
    (property "Current" "1A")
    (property "License" "Apache-2.0")
    (property "MPN" "CR0603-J/-000ELF")
    (property "Manufacturer" "Bourns")
    (property "Public" "False")
    (property "Sheetfile" "channel1.kicad_sch")
    (property "Sheetname" "Channel 1")
    (property "Tolerance" "")
    (property "Val" "0R")
    (property "ki_description" "Zero Ohm Resistor, Jumper, 0603 [1608 Metric], Thick Film, 100 mW, 1 A, Surface Mount Device, CR")
    (property "ki_keywords" "0603, SMT, RESISTOR, PASSIVE")
    (attr smd)
    (fp_text reference "R7" (at 1 -0.4) (layer "B.SilkS")
        (effects (font (size 0.7 0.7) (thickness 0.15)) (justify left bottom mirror))
    )
    (fp_text value "R_0R_0603" (at 0 -1.6) (layer "B.Fab")
        (effects (font (size 0.7 0.7) (thickness 0.15)) (justify left bottom mirror))
    )
    (fp_text user "Author: Antmicro" (at -1.25 -4.9) (layer "B.Fab") hide
        (effects (font (size 0.7 0.7) (thickness 0.15)) (justify left bottom mirror))
    )
    (fp_text user "License: Apache-2.0" (at -1.25 -5.9) (layer "B.Fab") hide
        (effects (font (size 0.7 0.7) (thickness 0.15)) (justify left bottom mirror))
    )
    (fp_text user "${REFERENCE}" (at -1.25 -3.898) (layer "B.Fab") hide
        (effects (font (size 0.7 0.7) (thickness 0.15)) (justify left bottom mirror))
    )
    (fp_line (start -0.15 -0.4) (end 0.15 -0.4)
      (stroke (width 0.15) (type solid)) (layer "B.SilkS"))
    (fp_line (start -0.15 0.4) (end 0.15 0.4)
      (stroke (width 0.15) (type solid)) (layer "B.SilkS"))
    (fp_rect (start -1.25 0.65) (end 1.25 -0.65)
      (stroke (width 0.05) (type solid)) (fill none) (layer "B.CrtYd"))
    (fp_rect (start -0.8 0.4) (end 0.8 -0.4)
      (stroke (width 0.15) (type solid)) (fill none) (layer "B.Fab"))
    (pad "1" smd roundrect (at -0.7 0 180) (size 0.8 1) (layers "B.Cu" "B.Paste" "B.Mask") (roundrect_rratio 0.2)
      (net 21 "Net-(U1B-VDDIO2)") (pintype "passive"))
    (pad "2" smd roundrect (at 0.7 0 180) (size 0.8 1) (layers "B.Cu" "B.Paste" "B.Mask") (roundrect_rratio 0.2)
      (net 9 "+3V3") (pintype "passive"))
  )

  (footprint "antmicro-footprints:Spacer_Drill3.7mm_H6mm_9774060151R" (layer "B.Cu")
    (at 119 94 180)
    (property "Author" "Antmicro")
    (property "License" "Apache-2.0")
    (property "MPN" "9774060151R")
    (property "Manufacturer" "Würth Elektronik")
    (property "Public" "False")
    (property "Sheetfile" "csi.kicad_sch")
    (property "Sheetname" "CSI")
    (property "ki_description" "Spacer, SMT, Non Stop, Steel, Swage Round, 5.1 mm x 6 mm, M2.5 Thread, WA-SMSI Series")
    (property "ki_keywords" "MECHANICAL, SPACER")
    (attr smd)
    (fp_text reference "SP1" (at 0 3.2) (layer "B.SilkS") hide
        (effects (font (size 0.7 0.7) (thickness 0.15)) (justify left bottom mirror))
    )
    (fp_text value "Spacer_Drill3.7mm_H6mm_9774060151R" (at 0 -4) (layer "B.Fab")
        (effects (font (size 0.7 0.7) (thickness 0.15)) (justify left bottom mirror))
    )
    (fp_text user "${REFERENCE}" (at -2.551 -5.25) (layer "B.Fab") hide
        (effects (font (size 0.7 0.7) (thickness 0.15)) (justify left bottom mirror))
    )
    (fp_text user "Author: Antmicro" (at -2.551 -6.5) (layer "B.Fab") hide
        (effects (font (size 0.7 0.7) (thickness 0.15)) (justify left bottom mirror))
    )
    (fp_text user "License: Apache-2.0" (at -2.551 -7.75) (layer "B.Fab") hide
        (effects (font (size 0.7 0.7) (thickness 0.15)) (justify left bottom mirror))
    )
    (fp_circle (center 0 0) (end 3.05 0)
      (stroke (width 0.05) (type solid)) (fill none) (layer "B.CrtYd"))
    (fp_circle (center -0.001 0) (end 2.548 0)
      (stroke (width 0.15) (type solid)) (fill none) (layer "B.Fab"))
    (pad "" smd custom (at -1.71 -1.699 90) (size 0.62 0.62) (layers "B.Paste")
      (thermal_bridge_angle 90)
      (options (clearance outline) (anchor circle))
      (primitives
        (gr_arc (start 1.266786 0.24747) (mid 0.285453 -0.29439) (end -0.250195 -1.279127) (width 0.2))
        (gr_arc (start 1.259603 0.339191) (mid 0.218448 -0.232561) (end -0.34334 -1.279127) (width 0.2))
        (gr_arc (start 1.255279 0.431435) (mid 0.152481 -0.169693) (end -0.436309 -1.279127) (width 0.2))
        (gr_arc (start 1.253811 0.524161) (mid 0.087542 -0.105784) (end -0.529126 -1.279127) (width 0.2))
        (gr_arc (start 1.275473 0.621136) (mid 0.0309 -0.033527) (end -0.621807 -1.279127) (width 0.2))
        (gr_arc (start 1.263664 0.711602) (mid -0.037759 0.026651) (end -0.71437 -1.279127) (width 0.2))
        (gr_arc (start 1.253435 0.802342) (mid -0.105837 0.087395) (end -0.806826 -1.279127) (width 0.2))
        (gr_arc (start 1.267475 0.897258) (mid -0.165236 0.156885) (end -0.899187 -1.279127) (width 0.2))
        (gr_arc (start 1.270645 0.990112) (mid -0.228522 0.222449) (end -0.991463 -1.279127) (width 0.2))
        (gr_arc (start 1.266278 1.081674) (mid -0.294507 0.285313) (end -1.083663 -1.279127) (width 0.2))
        (gr_line (start 1.279127 1.083663) (end 1.279127 0.250195) (width 0.2))
        (gr_line (start -1.083663 -1.279127) (end -0.250195 -1.279127) (width 0.2))
      ))
    (pad "" smd custom (at -1.71 1.71 180) (size 0.62 0.62) (layers "B.Paste")
      (thermal_bridge_angle 90)
      (options (clearance outline) (anchor circle))
      (primitives
        (gr_arc (start 1.266786 0.24747) (mid 0.285453 -0.29439) (end -0.250195 -1.279127) (width 0.2))
        (gr_arc (start 1.259603 0.339191) (mid 0.218448 -0.232561) (end -0.34334 -1.279127) (width 0.2))
        (gr_arc (start 1.255279 0.431435) (mid 0.152481 -0.169693) (end -0.436309 -1.279127) (width 0.2))
        (gr_arc (start 1.253811 0.524161) (mid 0.087542 -0.105784) (end -0.529126 -1.279127) (width 0.2))
        (gr_arc (start 1.275473 0.621136) (mid 0.0309 -0.033527) (end -0.621807 -1.279127) (width 0.2))
        (gr_arc (start 1.263664 0.711602) (mid -0.037759 0.026651) (end -0.71437 -1.279127) (width 0.2))
        (gr_arc (start 1.253435 0.802342) (mid -0.105837 0.087395) (end -0.806826 -1.279127) (width 0.2))
        (gr_arc (start 1.267475 0.897258) (mid -0.165236 0.156885) (end -0.899187 -1.279127) (width 0.2))
        (gr_arc (start 1.270645 0.990112) (mid -0.228522 0.222449) (end -0.991463 -1.279127) (width 0.2))
        (gr_arc (start 1.266278 1.081674) (mid -0.294507 0.285313) (end -1.083663 -1.279127) (width 0.2))
        (gr_line (start 1.279127 1.083663) (end 1.279127 0.250195) (width 0.2))
        (gr_line (start -1.083663 -1.279127) (end -0.250195 -1.279127) (width 0.2))
      ))
    (pad "" smd custom (at 1.699 -1.699) (size 0.62 0.62) (layers "B.Paste")
      (thermal_bridge_angle 90)
      (options (clearance outline) (anchor circle))
      (primitives
        (gr_arc (start 1.266786 0.24747) (mid 0.285453 -0.29439) (end -0.250195 -1.279127) (width 0.2))
        (gr_arc (start 1.259603 0.339191) (mid 0.218448 -0.232561) (end -0.34334 -1.279127) (width 0.2))
        (gr_arc (start 1.255279 0.431435) (mid 0.152481 -0.169693) (end -0.436309 -1.279127) (width 0.2))
        (gr_arc (start 1.253811 0.524161) (mid 0.087542 -0.105784) (end -0.529126 -1.279127) (width 0.2))
        (gr_arc (start 1.275473 0.621136) (mid 0.0309 -0.033527) (end -0.621807 -1.279127) (width 0.2))
        (gr_arc (start 1.263664 0.711602) (mid -0.037759 0.026651) (end -0.71437 -1.279127) (width 0.2))
        (gr_arc (start 1.253435 0.802342) (mid -0.105837 0.087395) (end -0.806826 -1.279127) (width 0.2))
        (gr_arc (start 1.267475 0.897258) (mid -0.165236 0.156885) (end -0.899187 -1.279127) (width 0.2))
        (gr_arc (start 1.270645 0.990112) (mid -0.228522 0.222449) (end -0.991463 -1.279127) (width 0.2))
        (gr_arc (start 1.266278 1.081674) (mid -0.294507 0.285313) (end -1.083663 -1.279127) (width 0.2))
        (gr_line (start 1.279127 1.083663) (end 1.279127 0.250195) (width 0.2))
        (gr_line (start -1.083663 -1.279127) (end -0.250195 -1.279127) (width 0.2))
      ))
    (pad "" smd custom (at 1.699 1.71 270) (size 0.62 0.62) (layers "B.Paste")
      (thermal_bridge_angle 90)
      (options (clearance outline) (anchor circle))
      (primitives
        (gr_arc (start 1.266786 0.24747) (mid 0.285453 -0.29439) (end -0.250195 -1.279127) (width 0.2))
        (gr_arc (start 1.259603 0.339191) (mid 0.218448 -0.232561) (end -0.34334 -1.279127) (width 0.2))
        (gr_arc (start 1.255279 0.431435) (mid 0.152481 -0.169693) (end -0.436309 -1.279127) (width 0.2))
        (gr_arc (start 1.253811 0.524161) (mid 0.087542 -0.105784) (end -0.529126 -1.279127) (width 0.2))
        (gr_arc (start 1.275473 0.621136) (mid 0.0309 -0.033527) (end -0.621807 -1.279127) (width 0.2))
        (gr_arc (start 1.263664 0.711602) (mid -0.037759 0.026651) (end -0.71437 -1.279127) (width 0.2))
        (gr_arc (start 1.253435 0.802342) (mid -0.105837 0.087395) (end -0.806826 -1.279127) (width 0.2))
        (gr_arc (start 1.267475 0.897258) (mid -0.165236 0.156885) (end -0.899187 -1.279127) (width 0.2))
        (gr_arc (start 1.270645 0.990112) (mid -0.228522 0.222449) (end -0.991463 -1.279127) (width 0.2))
        (gr_arc (start 1.266278 1.081674) (mid -0.294507 0.285313) (end -1.083663 -1.279127) (width 0.2))
        (gr_line (start 1.279127 1.083663) (end 1.279127 0.250195) (width 0.2))
        (gr_line (start -1.083663 -1.279127) (end -0.250195 -1.279127) (width 0.2))
      ))
    (pad "1" thru_hole circle (at -0.001 0 180) (size 6 6) (drill 3.7) (layers "*.Cu" "*.Mask")
      (net 2 "GND") (pintype "passive") (solder_paste_margin_ratio -0.05))
  )

  (footprint "antmicro-footprints:R_0603_1608Metric" (layer "B.Cu")
    (at 130.8 110.9 180)
    (descr "Resistor SMD 0603")
    (tags "resistor SMD 0603")
    (property "Author" "Antmicro")
    (property "Current" "1A")
    (property "License" "Apache-2.0")
    (property "MPN" "CR0603-J/-000ELF")
    (property "Manufacturer" "Bourns")
    (property "Public" "False")
    (property "Sheetfile" "channel1.kicad_sch")
    (property "Sheetname" "Channel 1")
    (property "Tolerance" "")
    (property "Val" "0R")
    (property "ki_description" "Zero Ohm Resistor, Jumper, 0603 [1608 Metric], Thick Film, 100 mW, 1 A, Surface Mount Device, CR")
    (property "ki_keywords" "0603, SMT, RESISTOR, PASSIVE")
    (attr smd)
    (fp_text reference "R6" (at 1 -0.4) (layer "B.SilkS")
        (effects (font (size 0.7 0.7) (thickness 0.15)) (justify left bottom mirror))
    )
    (fp_text value "R_0R_0603" (at 0 -1.6) (layer "B.Fab")
        (effects (font (size 0.7 0.7) (thickness 0.15)) (justify left bottom mirror))
    )
    (fp_text user "${REFERENCE}" (at -1.25 -3.898) (layer "B.Fab") hide
        (effects (font (size 0.7 0.7) (thickness 0.15)) (justify left bottom mirror))
    )
    (fp_text user "License: Apache-2.0" (at -1.25 -5.9) (layer "B.Fab") hide
        (effects (font (size 0.7 0.7) (thickness 0.15)) (justify left bottom mirror))
    )
    (fp_text user "Author: Antmicro" (at -1.25 -4.9) (layer "B.Fab") hide
        (effects (font (size 0.7 0.7) (thickness 0.15)) (justify left bottom mirror))
    )
    (fp_line (start -0.15 -0.4) (end 0.15 -0.4)
      (stroke (width 0.15) (type solid)) (layer "B.SilkS"))
    (fp_line (start -0.15 0.4) (end 0.15 0.4)
      (stroke (width 0.15) (type solid)) (layer "B.SilkS"))
    (fp_rect (start -1.25 0.65) (end 1.25 -0.65)
      (stroke (width 0.05) (type solid)) (fill none) (layer "B.CrtYd"))
    (fp_rect (start -0.8 0.4) (end 0.8 -0.4)
      (stroke (width 0.15) (type solid)) (fill none) (layer "B.Fab"))
    (pad "1" smd roundrect (at -0.7 0 180) (size 0.8 1) (layers "B.Cu" "B.Paste" "B.Mask") (roundrect_rratio 0.2)
      (net 20 "Net-(U1B-VDDIO1)") (pintype "passive"))
    (pad "2" smd roundrect (at 0.7 0 180) (size 0.8 1) (layers "B.Cu" "B.Paste" "B.Mask") (roundrect_rratio 0.2)
      (net 9 "+3V3") (pintype "passive"))
  )

  (footprint "antmicro-footprints:Spacer_Drill3.7mm_H6mm_9774060151R" (layer "B.Cu")
    (at 179 94 180)
    (property "Author" "Antmicro")
    (property "License" "Apache-2.0")
    (property "MPN" "9774060151R")
    (property "Manufacturer" "Würth Elektronik")
    (property "Public" "False")
    (property "Sheetfile" "csi.kicad_sch")
    (property "Sheetname" "CSI")
    (property "ki_description" "Spacer, SMT, Non Stop, Steel, Swage Round, 5.1 mm x 6 mm, M2.5 Thread, WA-SMSI Series")
    (property "ki_keywords" "MECHANICAL, SPACER")
    (attr smd)
    (fp_text reference "SP2" (at 0 3.2) (layer "B.SilkS") hide
        (effects (font (size 0.7 0.7) (thickness 0.15)) (justify left bottom mirror))
    )
    (fp_text value "Spacer_Drill3.7mm_H6mm_9774060151R" (at 0 -4) (layer "B.Fab")
        (effects (font (size 0.7 0.7) (thickness 0.15)) (justify left bottom mirror))
    )
    (fp_text user "License: Apache-2.0" (at -2.551 -7.75) (layer "B.Fab") hide
        (effects (font (size 0.7 0.7) (thickness 0.15)) (justify left bottom mirror))
    )
    (fp_text user "${REFERENCE}" (at -2.551 -5.25) (layer "B.Fab") hide
        (effects (font (size 0.7 0.7) (thickness 0.15)) (justify left bottom mirror))
    )
    (fp_text user "Author: Antmicro" (at -2.551 -6.5) (layer "B.Fab") hide
        (effects (font (size 0.7 0.7) (thickness 0.15)) (justify left bottom mirror))
    )
    (fp_circle (center 0 0) (end 3.05 0)
      (stroke (width 0.05) (type solid)) (fill none) (layer "B.CrtYd"))
    (fp_circle (center -0.001 0) (end 2.548 0)
      (stroke (width 0.15) (type solid)) (fill none) (layer "B.Fab"))
    (pad "" smd custom (at -1.71 -1.699 90) (size 0.62 0.62) (layers "B.Paste")
      (thermal_bridge_angle 90)
      (options (clearance outline) (anchor circle))
      (primitives
        (gr_arc (start 1.266786 0.24747) (mid 0.285453 -0.29439) (end -0.250195 -1.279127) (width 0.2))
        (gr_arc (start 1.259603 0.339191) (mid 0.218448 -0.232561) (end -0.34334 -1.279127) (width 0.2))
        (gr_arc (start 1.255279 0.431435) (mid 0.152481 -0.169693) (end -0.436309 -1.279127) (width 0.2))
        (gr_arc (start 1.253811 0.524161) (mid 0.087542 -0.105784) (end -0.529126 -1.279127) (width 0.2))
        (gr_arc (start 1.275473 0.621136) (mid 0.0309 -0.033527) (end -0.621807 -1.279127) (width 0.2))
        (gr_arc (start 1.263664 0.711602) (mid -0.037759 0.026651) (end -0.71437 -1.279127) (width 0.2))
        (gr_arc (start 1.253435 0.802342) (mid -0.105837 0.087395) (end -0.806826 -1.279127) (width 0.2))
        (gr_arc (start 1.267475 0.897258) (mid -0.165236 0.156885) (end -0.899187 -1.279127) (width 0.2))
        (gr_arc (start 1.270645 0.990112) (mid -0.228522 0.222449) (end -0.991463 -1.279127) (width 0.2))
        (gr_arc (start 1.266278 1.081674) (mid -0.294507 0.285313) (end -1.083663 -1.279127) (width 0.2))
        (gr_line (start 1.279127 1.083663) (end 1.279127 0.250195) (width 0.2))
        (gr_line (start -1.083663 -1.279127) (end -0.250195 -1.279127) (width 0.2))
      ))
    (pad "" smd custom (at -1.71 1.71 180) (size 0.62 0.62) (layers "B.Paste")
      (thermal_bridge_angle 90)
      (options (clearance outline) (anchor circle))
      (primitives
        (gr_arc (start 1.266786 0.24747) (mid 0.285453 -0.29439) (end -0.250195 -1.279127) (width 0.2))
        (gr_arc (start 1.259603 0.339191) (mid 0.218448 -0.232561) (end -0.34334 -1.279127) (width 0.2))
        (gr_arc (start 1.255279 0.431435) (mid 0.152481 -0.169693) (end -0.436309 -1.279127) (width 0.2))
        (gr_arc (start 1.253811 0.524161) (mid 0.087542 -0.105784) (end -0.529126 -1.279127) (width 0.2))
        (gr_arc (start 1.275473 0.621136) (mid 0.0309 -0.033527) (end -0.621807 -1.279127) (width 0.2))
        (gr_arc (start 1.263664 0.711602) (mid -0.037759 0.026651) (end -0.71437 -1.279127) (width 0.2))
        (gr_arc (start 1.253435 0.802342) (mid -0.105837 0.087395) (end -0.806826 -1.279127) (width 0.2))
        (gr_arc (start 1.267475 0.897258) (mid -0.165236 0.156885) (end -0.899187 -1.279127) (width 0.2))
        (gr_arc (start 1.270645 0.990112) (mid -0.228522 0.222449) (end -0.991463 -1.279127) (width 0.2))
        (gr_arc (start 1.266278 1.081674) (mid -0.294507 0.285313) (end -1.083663 -1.279127) (width 0.2))
        (gr_line (start 1.279127 1.083663) (end 1.279127 0.250195) (width 0.2))
        (gr_line (start -1.083663 -1.279127) (end -0.250195 -1.279127) (width 0.2))
      ))
    (pad "" smd custom (at 1.699 -1.699) (size 0.62 0.62) (layers "B.Paste")
      (thermal_bridge_angle 90)
      (options (clearance outline) (anchor circle))
      (primitives
        (gr_arc (start 1.266786 0.24747) (mid 0.285453 -0.29439) (end -0.250195 -1.279127) (width 0.2))
        (gr_arc (start 1.259603 0.339191) (mid 0.218448 -0.232561) (end -0.34334 -1.279127) (width 0.2))
        (gr_arc (start 1.255279 0.431435) (mid 0.152481 -0.169693) (end -0.436309 -1.279127) (width 0.2))
        (gr_arc (start 1.253811 0.524161) (mid 0.087542 -0.105784) (end -0.529126 -1.279127) (width 0.2))
        (gr_arc (start 1.275473 0.621136) (mid 0.0309 -0.033527) (end -0.621807 -1.279127) (width 0.2))
        (gr_arc (start 1.263664 0.711602) (mid -0.037759 0.026651) (end -0.71437 -1.279127) (width 0.2))
        (gr_arc (start 1.253435 0.802342) (mid -0.105837 0.087395) (end -0.806826 -1.279127) (width 0.2))
        (gr_arc (start 1.267475 0.897258) (mid -0.165236 0.156885) (end -0.899187 -1.279127) (width 0.2))
        (gr_arc (start 1.270645 0.990112) (mid -0.228522 0.222449) (end -0.991463 -1.279127) (width 0.2))
        (gr_arc (start 1.266278 1.081674) (mid -0.294507 0.285313) (end -1.083663 -1.279127) (width 0.2))
        (gr_line (start 1.279127 1.083663) (end 1.279127 0.250195) (width 0.2))
        (gr_line (start -1.083663 -1.279127) (end -0.250195 -1.279127) (width 0.2))
      ))
    (pad "" smd custom (at 1.699 1.71 270) (size 0.62 0.62) (layers "B.Paste")
      (thermal_bridge_angle 90)
      (options (clearance outline) (anchor circle))
      (primitives
        (gr_arc (start 1.266786 0.24747) (mid 0.285453 -0.29439) (end -0.250195 -1.279127) (width 0.2))
        (gr_arc (start 1.259603 0.339191) (mid 0.218448 -0.232561) (end -0.34334 -1.279127) (width 0.2))
        (gr_arc (start 1.255279 0.431435) (mid 0.152481 -0.169693) (end -0.436309 -1.279127) (width 0.2))
        (gr_arc (start 1.253811 0.524161) (mid 0.087542 -0.105784) (end -0.529126 -1.279127) (width 0.2))
        (gr_arc (start 1.275473 0.621136) (mid 0.0309 -0.033527) (end -0.621807 -1.279127) (width 0.2))
        (gr_arc (start 1.263664 0.711602) (mid -0.037759 0.026651) (end -0.71437 -1.279127) (width 0.2))
        (gr_arc (start 1.253435 0.802342) (mid -0.105837 0.087395) (end -0.806826 -1.279127) (width 0.2))
        (gr_arc (start 1.267475 0.897258) (mid -0.165236 0.156885) (end -0.899187 -1.279127) (width 0.2))
        (gr_arc (start 1.270645 0.990112) (mid -0.228522 0.222449) (end -0.991463 -1.279127) (width 0.2))
        (gr_arc (start 1.266278 1.081674) (mid -0.294507 0.285313) (end -1.083663 -1.279127) (width 0.2))
        (gr_line (start 1.279127 1.083663) (end 1.279127 0.250195) (width 0.2))
        (gr_line (start -1.083663 -1.279127) (end -0.250195 -1.279127) (width 0.2))
      ))
    (pad "1" thru_hole circle (at -0.001 0 180) (size 6 6) (drill 3.7) (layers "*.Cu" "*.Mask")
      (net 2 "GND") (pintype "passive") (solder_paste_margin_ratio -0.05))
  )

  (footprint "antmicro-footprints:Spacer_Drill3.7mm_H6mm_9774060151R" (layer "B.Cu")
    (at 119 131 180)
    (property "Author" "Antmicro")
    (property "License" "Apache-2.0")
    (property "MPN" "9774060151R")
    (property "Manufacturer" "Würth Elektronik")
    (property "Public" "False")
    (property "Sheetfile" "csi.kicad_sch")
    (property "Sheetname" "CSI")
    (property "ki_description" "Spacer, SMT, Non Stop, Steel, Swage Round, 5.1 mm x 6 mm, M2.5 Thread, WA-SMSI Series")
    (property "ki_keywords" "MECHANICAL, SPACER")
    (attr smd)
    (fp_text reference "SP4" (at 0 3.2) (layer "B.SilkS") hide
        (effects (font (size 0.7 0.7) (thickness 0.15)) (justify left bottom mirror))
    )
    (fp_text value "Spacer_Drill3.7mm_H6mm_9774060151R" (at 0 -4) (layer "B.Fab")
        (effects (font (size 0.7 0.7) (thickness 0.15)) (justify left bottom mirror))
    )
    (fp_text user "Author: Antmicro" (at -2.551 -6.5) (layer "B.Fab") hide
        (effects (font (size 0.7 0.7) (thickness 0.15)) (justify left bottom mirror))
    )
    (fp_text user "License: Apache-2.0" (at -2.551 -7.75) (layer "B.Fab") hide
        (effects (font (size 0.7 0.7) (thickness 0.15)) (justify left bottom mirror))
    )
    (fp_text user "${REFERENCE}" (at -2.551 -5.25) (layer "B.Fab") hide
        (effects (font (size 0.7 0.7) (thickness 0.15)) (justify left bottom mirror))
    )
    (fp_circle (center 0 0) (end 3.05 0)
      (stroke (width 0.05) (type solid)) (fill none) (layer "B.CrtYd"))
    (fp_circle (center -0.001 0) (end 2.548 0)
      (stroke (width 0.15) (type solid)) (fill none) (layer "B.Fab"))
    (pad "" smd custom (at -1.71 -1.699 90) (size 0.62 0.62) (layers "B.Paste")
      (thermal_bridge_angle 90)
      (options (clearance outline) (anchor circle))
      (primitives
        (gr_arc (start 1.266786 0.24747) (mid 0.285453 -0.29439) (end -0.250195 -1.279127) (width 0.2))
        (gr_arc (start 1.259603 0.339191) (mid 0.218448 -0.232561) (end -0.34334 -1.279127) (width 0.2))
        (gr_arc (start 1.255279 0.431435) (mid 0.152481 -0.169693) (end -0.436309 -1.279127) (width 0.2))
        (gr_arc (start 1.253811 0.524161) (mid 0.087542 -0.105784) (end -0.529126 -1.279127) (width 0.2))
        (gr_arc (start 1.275473 0.621136) (mid 0.0309 -0.033527) (end -0.621807 -1.279127) (width 0.2))
        (gr_arc (start 1.263664 0.711602) (mid -0.037759 0.026651) (end -0.71437 -1.279127) (width 0.2))
        (gr_arc (start 1.253435 0.802342) (mid -0.105837 0.087395) (end -0.806826 -1.279127) (width 0.2))
        (gr_arc (start 1.267475 0.897258) (mid -0.165236 0.156885) (end -0.899187 -1.279127) (width 0.2))
        (gr_arc (start 1.270645 0.990112) (mid -0.228522 0.222449) (end -0.991463 -1.279127) (width 0.2))
        (gr_arc (start 1.266278 1.081674) (mid -0.294507 0.285313) (end -1.083663 -1.279127) (width 0.2))
        (gr_line (start 1.279127 1.083663) (end 1.279127 0.250195) (width 0.2))
        (gr_line (start -1.083663 -1.279127) (end -0.250195 -1.279127) (width 0.2))
      ))
    (pad "" smd custom (at -1.71 1.71 180) (size 0.62 0.62) (layers "B.Paste")
      (thermal_bridge_angle 90)
      (options (clearance outline) (anchor circle))
      (primitives
        (gr_arc (start 1.266786 0.24747) (mid 0.285453 -0.29439) (end -0.250195 -1.279127) (width 0.2))
        (gr_arc (start 1.259603 0.339191) (mid 0.218448 -0.232561) (end -0.34334 -1.279127) (width 0.2))
        (gr_arc (start 1.255279 0.431435) (mid 0.152481 -0.169693) (end -0.436309 -1.279127) (width 0.2))
        (gr_arc (start 1.253811 0.524161) (mid 0.087542 -0.105784) (end -0.529126 -1.279127) (width 0.2))
        (gr_arc (start 1.275473 0.621136) (mid 0.0309 -0.033527) (end -0.621807 -1.279127) (width 0.2))
        (gr_arc (start 1.263664 0.711602) (mid -0.037759 0.026651) (end -0.71437 -1.279127) (width 0.2))
        (gr_arc (start 1.253435 0.802342) (mid -0.105837 0.087395) (end -0.806826 -1.279127) (width 0.2))
        (gr_arc (start 1.267475 0.897258) (mid -0.165236 0.156885) (end -0.899187 -1.279127) (width 0.2))
        (gr_arc (start 1.270645 0.990112) (mid -0.228522 0.222449) (end -0.991463 -1.279127) (width 0.2))
        (gr_arc (start 1.266278 1.081674) (mid -0.294507 0.285313) (end -1.083663 -1.279127) (width 0.2))
        (gr_line (start 1.279127 1.083663) (end 1.279127 0.250195) (width 0.2))
        (gr_line (start -1.083663 -1.279127) (end -0.250195 -1.279127) (width 0.2))
      ))
    (pad "" smd custom (at 1.699 -1.699) (size 0.62 0.62) (layers "B.Paste")
      (thermal_bridge_angle 90)
      (options (clearance outline) (anchor circle))
      (primitives
        (gr_arc (start 1.266786 0.24747) (mid 0.285453 -0.29439) (end -0.250195 -1.279127) (width 0.2))
        (gr_arc (start 1.259603 0.339191) (mid 0.218448 -0.232561) (end -0.34334 -1.279127) (width 0.2))
        (gr_arc (start 1.255279 0.431435) (mid 0.152481 -0.169693) (end -0.436309 -1.279127) (width 0.2))
        (gr_arc (start 1.253811 0.524161) (mid 0.087542 -0.105784) (end -0.529126 -1.279127) (width 0.2))
        (gr_arc (start 1.275473 0.621136) (mid 0.0309 -0.033527) (end -0.621807 -1.279127) (width 0.2))
        (gr_arc (start 1.263664 0.711602) (mid -0.037759 0.026651) (end -0.71437 -1.279127) (width 0.2))
        (gr_arc (start 1.253435 0.802342) (mid -0.105837 0.087395) (end -0.806826 -1.279127) (width 0.2))
        (gr_arc (start 1.267475 0.897258) (mid -0.165236 0.156885) (end -0.899187 -1.279127) (width 0.2))
        (gr_arc (start 1.270645 0.990112) (mid -0.228522 0.222449) (end -0.991463 -1.279127) (width 0.2))
        (gr_arc (start 1.266278 1.081674) (mid -0.294507 0.285313) (end -1.083663 -1.279127) (width 0.2))
        (gr_line (start 1.279127 1.083663) (end 1.279127 0.250195) (width 0.2))
        (gr_line (start -1.083663 -1.279127) (end -0.250195 -1.279127) (width 0.2))
      ))
    (pad "" smd custom (at 1.699 1.71 270) (size 0.62 0.62) (layers "B.Paste")
      (thermal_bridge_angle 90)
      (options (clearance outline) (anchor circle))
      (primitives
        (gr_arc (start 1.266786 0.24747) (mid 0.285453 -0.29439) (end -0.250195 -1.279127) (width 0.2))
        (gr_arc (start 1.259603 0.339191) (mid 0.218448 -0.232561) (end -0.34334 -1.279127) (width 0.2))
        (gr_arc (start 1.255279 0.431435) (mid 0.152481 -0.169693) (end -0.436309 -1.279127) (width 0.2))
        (gr_arc (start 1.253811 0.524161) (mid 0.087542 -0.105784) (end -0.529126 -1.279127) (width 0.2))
        (gr_arc (start 1.275473 0.621136) (mid 0.0309 -0.033527) (end -0.621807 -1.279127) (width 0.2))
        (gr_arc (start 1.263664 0.711602) (mid -0.037759 0.026651) (end -0.71437 -1.279127) (width 0.2))
        (gr_arc (start 1.253435 0.802342) (mid -0.105837 0.087395) (end -0.806826 -1.279127) (width 0.2))
        (gr_arc (start 1.267475 0.897258) (mid -0.165236 0.156885) (end -0.899187 -1.279127) (width 0.2))
        (gr_arc (start 1.270645 0.990112) (mid -0.228522 0.222449) (end -0.991463 -1.279127) (width 0.2))
        (gr_arc (start 1.266278 1.081674) (mid -0.294507 0.285313) (end -1.083663 -1.279127) (width 0.2))
        (gr_line (start 1.279127 1.083663) (end 1.279127 0.250195) (width 0.2))
        (gr_line (start -1.083663 -1.279127) (end -0.250195 -1.279127) (width 0.2))
      ))
    (pad "1" thru_hole circle (at -0.001 0 180) (size 6 6) (drill 3.7) (layers "*.Cu" "*.Mask")
      (net 2 "GND") (pintype "passive") (solder_paste_margin_ratio -0.05))
  )

  (footprint "antmicro-footprints:TP_SMD_0.75mm" (layer "B.Cu")
    (at 155.4 115.0508 180)
    (property "Author" "Antmicro")
    (property "License" "Apache-2.0")
    (property "MPN" "")
    (property "Manufacturer" "")
    (property "Public" "False")
    (property "Sheetfile" "channel2.kicad_sch")
    (property "Sheetname" "Channel 2")
    (property "exclude_from_bom" "")
    (property "ki_description" "SMT test point")
    (property "ki_keywords" "TESTPOINT")
    (attr exclude_from_pos_files exclude_from_bom)
    (fp_text reference "TP6" (at -2.65 -0.3692) (layer "B.SilkS")
        (effects (font (size 0.65 0.65) (thickness 0.13)) (justify left bottom mirror))
    )
    (fp_text value "TP_0.75mm_SMD" (at 0 -1.2) (layer "B.Fab")
        (effects (font (size 0.65 0.65) (thickness 0.13)) (justify left bottom mirror))
    )
    (fp_text user "${REFERENCE}" (at -0.4 -2.7) (layer "B.Fab") hide
        (effects (font (size 0.7 0.7) (thickness 0.15)) (justify left bottom mirror))
    )
    (fp_text user "Author: Antmicro" (at -0.4 -3.901) (layer "B.Fab") hide
        (effects (font (size 0.7 0.7) (thickness 0.15)) (justify left bottom mirror))
    )
    (fp_text user "License: Apache-2.0" (at -0.4 -5.101) (layer "B.Fab") hide
        (effects (font (size 0.7 0.7) (thickness 0.15)) (justify left bottom mirror))
    )
    (pad "1" smd circle (at 0 0 180) (size 0.75 0.75) (layers "B.Cu" "B.Mask")
      (net 121 "Net-(U4A-EDID_SCL)") (pinfunction "1") (pintype "passive"))
  )

  (footprint "antmicro-footprints:R_0603_1608Metric" (layer "B.Cu")
    (at 130.8 109.4 180)
    (descr "Resistor SMD 0603")
    (tags "resistor SMD 0603")
    (property "Author" "Antmicro")
    (property "Current" "1A")
    (property "License" "Apache-2.0")
    (property "MPN" "CR0603-J/-000ELF")
    (property "Manufacturer" "Bourns")
    (property "Public" "False")
    (property "Sheetfile" "channel1.kicad_sch")
    (property "Sheetname" "Channel 1")
    (property "Tolerance" "")
    (property "Val" "0R")
    (property "ki_description" "Zero Ohm Resistor, Jumper, 0603 [1608 Metric], Thick Film, 100 mW, 1 A, Surface Mount Device, CR")
    (property "ki_keywords" "0603, SMT, RESISTOR, PASSIVE")
    (attr smd)
    (fp_text reference "R8" (at 1 -0.4) (layer "B.SilkS")
        (effects (font (size 0.7 0.7) (thickness 0.15)) (justify left bottom mirror))
    )
    (fp_text value "R_0R_0603" (at 0 -1.6) (layer "B.Fab")
        (effects (font (size 0.7 0.7) (thickness 0.15)) (justify left bottom mirror))
    )
    (fp_text user "License: Apache-2.0" (at -1.25 -5.9) (layer "B.Fab") hide
        (effects (font (size 0.7 0.7) (thickness 0.15)) (justify left bottom mirror))
    )
    (fp_text user "Author: Antmicro" (at -1.25 -4.9) (layer "B.Fab") hide
        (effects (font (size 0.7 0.7) (thickness 0.15)) (justify left bottom mirror))
    )
    (fp_text user "${REFERENCE}" (at -1.25 -3.898) (layer "B.Fab") hide
        (effects (font (size 0.7 0.7) (thickness 0.15)) (justify left bottom mirror))
    )
    (fp_line (start -0.15 -0.4) (end 0.15 -0.4)
      (stroke (width 0.15) (type solid)) (layer "B.SilkS"))
    (fp_line (start -0.15 0.4) (end 0.15 0.4)
      (stroke (width 0.15) (type solid)) (layer "B.SilkS"))
    (fp_rect (start -1.25 0.65) (end 1.25 -0.65)
      (stroke (width 0.05) (type solid)) (fill none) (layer "B.CrtYd"))
    (fp_rect (start -0.8 0.4) (end 0.8 -0.4)
      (stroke (width 0.15) (type solid)) (fill none) (layer "B.Fab"))
    (pad "1" smd roundrect (at -0.7 0 180) (size 0.8 1) (layers "B.Cu" "B.Paste" "B.Mask") (roundrect_rratio 0.2)
      (net 100 "/Channel 1/CH1_AVDD33") (pintype "passive"))
    (pad "2" smd roundrect (at 0.7 0 180) (size 0.8 1) (layers "B.Cu" "B.Paste" "B.Mask") (roundrect_rratio 0.2)
      (net 9 "+3V3") (pintype "passive"))
  )

  (footprint "antmicro-footprints:TP_SMD_0.75mm" (layer "B.Cu")
    (at 143.7 102.4008 180)
    (property "Author" "Antmicro")
    (property "License" "Apache-2.0")
    (property "MPN" "")
    (property "Manufacturer" "")
    (property "Public" "False")
    (property "Sheetfile" "channel1.kicad_sch")
    (property "Sheetname" "Channel 1")
    (property "exclude_from_bom" "")
    (property "ki_description" "SMT test point")
    (property "ki_keywords" "TESTPOINT")
    (attr exclude_from_pos_files exclude_from_bom)
    (fp_text reference "TP4" (at 0 0.6) (layer "B.SilkS")
        (effects (font (size 0.65 0.65) (thickness 0.13)) (justify left bottom mirror))
    )
    (fp_text value "TP_0.75mm_SMD" (at 0 -1.2) (layer "B.Fab")
        (effects (font (size 0.65 0.65) (thickness 0.13)) (justify left bottom mirror))
    )
    (fp_text user "${REFERENCE}" (at -0.4 -2.7) (layer "B.Fab") hide
        (effects (font (size 0.7 0.7) (thickness 0.15)) (justify left bottom mirror))
    )
    (fp_text user "Author: Antmicro" (at -0.4 -3.901) (layer "B.Fab") hide
        (effects (font (size 0.7 0.7) (thickness 0.15)) (justify left bottom mirror))
    )
    (fp_text user "License: Apache-2.0" (at -0.4 -5.101) (layer "B.Fab") hide
        (effects (font (size 0.7 0.7) (thickness 0.15)) (justify left bottom mirror))
    )
    (pad "1" smd circle (at 0 0 180) (size 0.75 0.75) (layers "B.Cu" "B.Mask")
      (net 118 "Net-(U3-EN)") (pinfunction "1") (pintype "passive"))
  )

  (footprint "antmicro-footprints:R_0603_1608Metric" (layer "B.Cu")
    (at 154.8 109.45 180)
    (descr "Resistor SMD 0603")
    (tags "resistor SMD 0603")
    (property "Author" "Antmicro")
    (property "Current" "1A")
    (property "License" "Apache-2.0")
    (property "MPN" "CR0603-J/-000ELF")
    (property "Manufacturer" "Bourns")
    (property "Public" "False")
    (property "Sheetfile" "channel2.kicad_sch")
    (property "Sheetname" "Channel 2")
    (property "Tolerance" "")
    (property "Val" "0R")
    (property "ki_description" "Zero Ohm Resistor, Jumper, 0603 [1608 Metric], Thick Film, 100 mW, 1 A, Surface Mount Device, CR")
    (property "ki_keywords" "0603, SMT, RESISTOR, PASSIVE")
    (attr smd)
    (fp_text reference "R21" (at 1 -0.35) (layer "B.SilkS")
        (effects (font (size 0.7 0.7) (thickness 0.15)) (justify left bottom mirror))
    )
    (fp_text value "R_0R_0603" (at 0 -1.6) (layer "B.Fab")
        (effects (font (size 0.7 0.7) (thickness 0.15)) (justify left bottom mirror))
    )
    (fp_text user "${REFERENCE}" (at -1.25 -3.898) (layer "B.Fab") hide
        (effects (font (size 0.7 0.7) (thickness 0.15)) (justify left bottom mirror))
    )
    (fp_text user "License: Apache-2.0" (at -1.25 -5.9) (layer "B.Fab") hide
        (effects (font (size 0.7 0.7) (thickness 0.15)) (justify left bottom mirror))
    )
    (fp_text user "Author: Antmicro" (at -1.25 -4.9) (layer "B.Fab") hide
        (effects (font (size 0.7 0.7) (thickness 0.15)) (justify left bottom mirror))
    )
    (fp_line (start -0.15 -0.4) (end 0.15 -0.4)
      (stroke (width 0.15) (type solid)) (layer "B.SilkS"))
    (fp_line (start -0.15 0.4) (end 0.15 0.4)
      (stroke (width 0.15) (type solid)) (layer "B.SilkS"))
    (fp_rect (start -1.25 0.65) (end 1.25 -0.65)
      (stroke (width 0.05) (type solid)) (fill none) (layer "B.CrtYd"))
    (fp_rect (start -0.8 0.4) (end 0.8 -0.4)
      (stroke (width 0.15) (type solid)) (fill none) (layer "B.Fab"))
    (pad "1" smd roundrect (at -0.7 0 180) (size 0.8 1) (layers "B.Cu" "B.Paste" "B.Mask") (roundrect_rratio 0.2)
      (net 108 "/Channel 2/CH2_AVDD33") (pintype "passive"))
    (pad "2" smd roundrect (at 0.7 0 180) (size 0.8 1) (layers "B.Cu" "B.Paste" "B.Mask") (roundrect_rratio 0.2)
      (net 9 "+3V3") (pintype "passive"))
  )

  (footprint "antmicro-footprints:C_0402_1005Metric" (layer "B.Cu")
    (at 163.8 110.15 180)
    (descr "Capacitor SMD 0402")
    (tags "capacitor SMD 0402")
    (property "Author" "Antmicro")
    (property "Dielectric" "X5R")
    (property "License" "Apache-2.0")
    (property "MPN" "GRM155R61H104KE14D")
    (property "Manufacturer" "Murata")
    (property "Public" "False")
    (property "Sheetfile" "channel2.kicad_sch")
    (property "Sheetname" "Channel 2")
    (property "Val" "100n")
    (property "Voltage" "50V")
    (property "ki_description" "SMD Multilayer Ceramic Capacitor, 0.1 µF, 50 V, 0402 [1005 Metric], ± 10%, X5R, GRM Series")
    (property "ki_keywords" "0402, SMT, CAPACITOR, PASSIVE, CERAMIC, MLCC")
    (attr smd)
    (fp_text reference "C26" (at 0.9 -0.3) (layer "B.SilkS")
        (effects (font (size 0.65 0.65) (thickness 0.13)) (justify left bottom mirror))
    )
    (fp_text value "C_100n_0402" (at 0 -1.4) (layer "B.Fab")
        (effects (font (size 0.65 0.65) (thickness 0.13)) (justify left bottom mirror))
    )
    (fp_text user "${REFERENCE}" (at -0.932 -3.168) (layer "B.Fab") hide
        (effects (font (size 0.7 0.7) (thickness 0.15)) (justify left bottom mirror))
    )
    (fp_text user "Author: Antmicro" (at -0.932 -4.17) (layer "B.Fab") hide
        (effects (font (size 0.7 0.7) (thickness 0.15)) (justify left bottom mirror))
    )
    (fp_text user "License: Apache-2.0" (at -0.932 -5.17) (layer "B.Fab") hide
        (effects (font (size 0.7 0.7) (thickness 0.15)) (justify left bottom mirror))
    )
    (fp_rect (start -0.925 0.47) (end 0.925 -0.47)
      (stroke (width 0.05) (type default)) (fill none) (layer "B.CrtYd"))
    (fp_line (start -0.494 -0.248) (end -0.494 0.25)
      (stroke (width 0.15) (type solid)) (layer "B.Fab"))
    (fp_line (start -0.494 0.25) (end 0.504 0.25)
      (stroke (width 0.15) (type solid)) (layer "B.Fab"))
    (fp_line (start 0.504 -0.248) (end -0.494 -0.248)
      (stroke (width 0.15) (type solid)) (layer "B.Fab"))
    (fp_line (start 0.504 0.25) (end 0.504 -0.248)
      (stroke (width 0.15) (type solid)) (layer "B.Fab"))
    (pad "1" smd roundrect (at -0.48 0 180) (size 0.59 0.64) (layers "B.Cu" "B.Paste" "B.Mask") (roundrect_rratio 0.25)
      (net 2 "GND") (pintype "passive"))
    (pad "2" smd roundrect (at 0.48 0 180) (size 0.59 0.64) (layers "B.Cu" "B.Paste" "B.Mask") (roundrect_rratio 0.25)
      (net 18 "Net-(U4C-PCKIN)") (pintype "passive"))
  )
  (gr_rect (start 115 90) (end 183 135)
    (stroke (width 0.12) (type solid)) (fill none) (layer "Edge.Cuts"))

  (segment (start 137.7 110.075) (end 137.375 109.75) (width 0.3) (layer "F.Cu") (net 1))
  (segment (start 137.375 109.75) (end 137.360527 109.75) (width 0.3) (layer "F.Cu") (net 1))
  (via (at 137.360527 109.75) (size 0.4) (drill 0.15) (layers "F.Cu" "B.Cu") (net 1))
  (segment (start 139 108.1) (end 139.315 108.1) (width 0.3) (layer "B.Cu") (net 1))
  (segment (start 137.360527 109.75) (end 137.360527 109.178076) (width 0.3) (layer "B.Cu") (net 1))
  (segment (start 137.360527 109.178076) (end 137.856801 108.681802) (width 0.3) (layer "B.Cu") (net 1))
  (segment (start 137.856801 108.681802) (end 137.856801 108.456802) (width 0.3) (layer "B.Cu") (net 1))
  (segment (start 138.413603 107.9) (end 138.8 107.9) (width 0.3) (layer "B.Cu") (net 1))
  (segment (start 137.856801 108.456802) (end 138.413603 107.9) (width 0.3) (layer "B.Cu") (net 1))
  (segment (start 138.8 107.9) (end 139 108.1) (width 0.3) (layer "B.Cu") (net 1))
  (segment (start 129.9 107.2) (end 129.9 106.475) (width 0.4) (layer "F.Cu") (net 2))
  (segment (start 153.9 107.25) (end 153.84 107.25) (width 0.1) (layer "F.Cu") (net 2))
  (segment (start 140.14 103.99) (end 139.53 104.6) (width 0.4) (layer "F.Cu") (net 2))
  (segment (start 155.75 130.1) (end 155.75 129.25) (width 0.3) (layer "F.Cu") (net 2))
  (segment (start 154.515 114.485) (end 154.515 113.45) (width 0.4) (layer "F.Cu") (net 2))
  (segment (start 162.125 109.475) (end 162.15 109.5) (width 0.1) (layer "F.Cu") (net 2))
  (segment (start 129.6 112.4) (end 129.1 112.9) (width 0.4) (layer "F.Cu") (net 2))
  (segment (start 135.1 110.075) (end 134.775 110.4) (width 0.1) (layer "F.Cu") (net 2))
  (segment (start 159.1 111.425) (end 158.775 111.75) (width 0.1) (layer "F.Cu") (net 2))
  (segment (start 172.35 119) (end 172.35 119.75) (width 0.4) (layer "F.Cu") (net 2))
  (segment (start 164.15 114.35) (end 164.4 114.6) (width 0.3) (layer "F.Cu") (net 2))
  (segment (start 144.77 106.25) (end 144.95 106.43) (width 0.3) (layer "F.Cu") (net 2))
  (segment (start 140.97 109.6) (end 140.85 109.48) (width 0.4) (layer "F.Cu") (net 2))
  (segment (start 148 110.735) (end 148 111.45) (width 0.4) (layer "F.Cu") (net 2))
  (segment (start 165.410294 106.9495) (end 165.329794 107.03) (width 0.4) (layer "F.Cu") (net 2))
  (segment (start 130.515 114.215) (end 130.515 113.4) (width 0.4) (layer "F.Cu") (net 2))
  (segment (start 134.5 104.325) (end 134.5 105.35) (width 0.1) (layer "F.Cu") (net 2))
  (segment (start 154.299999 112.750001) (end 154.515 112.535) (width 0.4) (layer "F.Cu") (net 2))
  (segment (start 160.4 110.775) (end 160.075 111.1) (width 0.1) (layer "F.Cu") (net 2))
  (segment (start 148 110.735) (end 147 110.735) (width 0.4) (layer "F.Cu") (net 2))
  (segment (start 164.164265 103.915735) (end 163.39 104.69) (width 0.4) (layer "F.Cu") (net 2))
  (segment (start 135.75 111.375) (end 135.425 111.7) (width 0.1) (layer "F.Cu") (net 2))
  (segment (start 129.34 107.2) (end 128.94 107.6) (width 0.4) (layer "F.Cu") (net 2))
  (segment (start 161.5 104.375) (end 161.5 105.4) (width 0.1) (layer "F.Cu") (net 2))
  (segment (start 153.9 107.25) (end 153.9 106.525) (width 0.4) (layer "F.Cu") (net 2))
  (segment (start 165.5 119.25) (end 166.15 119.25) (width 0.4) (layer "F.Cu") (net 2))
  (segment (start 160 98.599999) (end 160 97.85) (width 0.1) (layer "F.Cu") (net 2))
  (segment (start 141 108.06) (end 140.91 108.15) (width 0.4) (layer "F.Cu") (net 2))
  (segment (start 161.95 108.825) (end 162.175 109.05) (width 0.1) (layer "F.Cu") (net 2))
  (segment (start 140.91 108.15) (end 140.12 108.15) (width 0.4) (layer "F.Cu") (net 2))
  (segment (start 148 110.735) (end 148.485 110.735) (width 0.4) (layer "F.Cu") (net 2))
  (segment (start 129.9 107.2) (end 129.34 107.2) (width 0.4) (layer "F.Cu") (net 2))
  (segment (start 161.7 109.475) (end 162.125 109.475) (width 0.1) (layer "F.Cu") (net 2))
  (segment (start 161.7 108.825) (end 161.95 108.825) (width 0.1) (layer "F.Cu") (net 2))
  (segment (start 168.285 106.05) (end 169.28 106.05) (width 0.3) (layer "F.Cu") (net 2))
  (segment (start 159.75 111.425) (end 159.425 111.75) (width 0.1) (layer "F.Cu") (net 2))
  (segment (start 148.3 118.3) (end 148.25 118.25) (width 0.4) (layer "F.Cu") (net 2))
  (segment (start 123 110.685) (end 123 111.4) (width 0.4) (layer "F.Cu") (net 2))
  (segment (start 157 104.375) (end 157 105.4) (width 0.1) (layer "F.Cu") (net 2))
  (segment (start 123 104.915) (end 123 104.2) (width 0.4) (layer "F.Cu") (net 2))
  (segment (start 141.4995 109.6) (end 140.97 109.6) (width 0.4) (layer "F.Cu") (net 2))
  (segment (start 164.89 108.21) (end 164.27 108.21) (width 0.4) (layer "F.Cu") (net 2))
  (segment (start 139.53 104.6) (end 139.28 104.6) (width 0.4) (layer "F.Cu") (net 2))
  (segment (start 172.35 113.05) (end 172.35 114) (width 0.4) (layer "F.Cu") (net 2))
  (segment (start 164.285 111.85) (end 164.9 111.85) (width 0.4) (layer "F.Cu") (net 2))
  (segment (start 138.125 109.425) (end 138.15 109.45) (width 0.1) (layer "F.Cu") (net 2))
  (segment (start 137.7 108.775) (end 137.95 108.775) (width 0.1) (layer "F.Cu") (net 2))
  (segment (start 164.285 110.85) (end 164.9 110.85) (width 0.4) (layer "F.Cu") (net 2))
  (segment (start 133.15 112.675) (end 132.8 113.025) (width 0.1) (layer "F.Cu") (net 2))
  (segment (start 142.35 105.2125) (end 142.35 104.55) (width 0.4) (layer "F.Cu") (net 2))
  (segment (start 165.329794 107.03) (end 164.64 107.03) (width 0.4) (layer "F.Cu") (net 2))
  (segment (start 128.94 107.6) (end 128.94 108.16) (width 0.4) (layer "F.Cu") (net 2))
  (segment (start 166.35 105.2625) (end 166.35 104.6) (width 0.4) (layer "F.Cu") (net 2))
  (segment (start 141.4095 106.97) (end 140.66 106.97) (width 0.4) (layer "F.Cu") (net 2))
  (segment (start 168.15 120.45) (end 168.15 121.35) (width 0.4) (layer "F.Cu") (net 2))
  (segment (start 160.4 110.125) (end 160.075 110.45) (width 0.1) (layer "F.Cu") (net 2))
  (segment (start 172.25 117.3) (end 172.25 118.2) (width 0.4) (layer "F.Cu") (net 2))
  (segment (start 156.999999 98.599999) (end 157 97.85) (width 0.1) (layer "F.Cu") (net 2))
  (segment (start 124.635 110.685) (end 125.243336 111.293336) (width 0.4) (layer "F.Cu") (net 2))
  (segment (start 129.3 108.7) (end 130 109.4) (width 0.4) (layer "F.Cu") (net 2))
  (segment (start 135.1 111.375) (end 134.775 111.7) (width 0.1) (layer "F.Cu") (net 2))
  (segment (start 158.5 104.375) (end 158.5 105.4) (width 0.1) (layer "F.Cu") (net 2))
  (segment (start 164.499999 98.599999) (end 164.5 97.85) (width 0.1) (layer "F.Cu") (net 2))
  (segment (start 124 110.685) (end 124.635 110.685) (width 0.4) (layer "F.Cu") (net 2))
  (segment (start 134.500001 98.549999) (end 134.5 97.8) (width 0.1) (layer "F.Cu") (net 2))
  (segment (start 172.25 118.2) (end 172.25 118.9) (width 0.4) (layer "F.Cu") (net 2))
  (segment (start 142.35 105.2125) (end 142.35 105.85) (width 0.1) (layer "F.Cu") (net 2))
  (segment (start 159.75 110.125) (end 159.425 110.45) (width 0.1) (layer "F.Cu") (net 2))
  (segment (start 154.515 108.45) (end 153.9 108.45) (width 0.4) (layer "F.Cu") (net 2))
  (segment (start 148.25 117.3) (end 148.25 118.25) (width 0.4) (layer "F.Cu") (net 2))
  (segment (start 152.75 130.1) (end 152.75 129.25) (width 0.3) (layer "F.Cu") (net 2))
  (segment (start 152.99 107.62) (end 152.99 108.1) (width 0.4) (layer "F.Cu") (net 2))
  (segment (start 136.4 110.725) (end 136.075 111.05) (width 0.1) (layer "F.Cu") (net 2))
  (segment (start 169.2 114.65) (end 169.2 115) (width 0.4) (layer "F.Cu") (net 2))
  (segment (start 154.25 130.1) (end 154.25 129.25) (width 0.3) (layer "F.Cu") (net 2))
  (segment (start 136.4 110.075) (end 136.075 110.4) (width 0.1) (layer "F.Cu") (net 2))
  (segment (start 135.1 109.425) (end 134.775 109.75) (width 0.1) (layer "F.Cu") (net 2))
  (segment (start 153.6 112.45) (end 153.1 112.95) (width 0.4) (layer "F.Cu") (net 2))
  (segment (start 148.05 114) (end 148.1 114.05) (width 0.4) (layer "F.Cu") (net 2))
  (segment (start 142.35 104.55) (end 141.6 103.8) (width 0.4) (layer "F.Cu") (net 2))
  (segment (start 141.3 119.2) (end 142.15 119.2) (width 0.4) (layer "F.Cu") (net 2))
  (segment (start 137.5 104.325) (end 137.5 105.35) (width 0.1) (layer "F.Cu") (net 2))
  (segment (start 159.1 109.475) (end 158.775 109.8) (width 0.1) (layer "F.Cu") (net 2))
  (segment (start 140.045574 114.3) (end 139.785 114.3) (width 0.3) (layer "F.Cu") (net 2))
  (segment (start 147 104.965) (end 147 104.25) (width 0.4) (layer "F.Cu") (net 2))
  (segment (start 148 104.965) (end 148 104.25) (width 0.4) (layer "F.Cu") (net 2))
  (segment (start 137.95 108.775) (end 138.175 109) (width 0.1) (layer "F.Cu") (net 2))
  (segment (start 147 110.735) (end 147 111.45) (width 0.4) (layer "F.Cu") (net 2))
  (segment (start 130.7 114.4) (end 130.515 114.215) (width 0.4) (layer "F.Cu") (net 2))
  (segment (start 144.285 106.25) (end 144.77 106.25) (width 0.3) (layer "F.Cu") (net 2))
  (segment (start 125.243336 111.293336) (end 125.6907 111.293336) (width 0.4) (layer "F.Cu") (net 2))
  (segment (start 137.5 98.549999) (end 137.5 97.8) (width 0.1) (layer "F.Cu") (net 2))
  (segment (start 148.485 110.735) (end 149.71 111.96) (width 0.4) (layer "F.Cu") (net 2))
  (segment (start 165.46 107.64) (end 164.89 108.21) (width 0.4) (layer "F.Cu") (net 2))
  (segment (start 157.15 112.725) (end 156.8 113.075) (width 0.1) (layer "F.Cu") (net 2))
  (segment (start 160 104.375) (end 160 105.4) (width 0.1) (layer "F.Cu") (net 2))
  (segment (start 148.3 118.95) (end 148.3 119.25) (width 0.4) (layer "F.Cu") (net 2))
  (segment (start 164.164265 103.804265) (end 164.164265 103.915735) (width 0.4) (layer "F.Cu") (net 2))
  (segment (start 163.785 114.35) (end 164.15 114.35) (width 0.3) (layer "F.Cu") (net 2))
  (segment (start 136 104.325) (end 136 105.35) (width 0.1) (layer "F.Cu") (net 2))
  (segment (start 153.309666 108.957317) (end 153.802349 109.45) (width 0.4) (layer "F.Cu") (net 2))
  (segment (start 169.28 106.05) (end 169.29 106.04) (width 0.3) (layer "F.Cu") (net 2))
  (segment (start 158.500001 98.599999) (end 158.5 97.85) (width 0.1) (layer "F.Cu") (net 2))
  (segment (start 143.95 120.45) (end 143.95 121.35) (width 0.4) (layer "F.Cu") (net 2))
  (segment (start 124 104.915) (end 124 104.2) (width 0.4) (layer "F.Cu") (net 2))
  (segment (start 132.999999 98.549999) (end 133 97.8) (width 0.1) (layer "F.Cu") (net 2))
  (segment (start 141.48 106.8995) (end 141.4095 106.97) (width 0.4) (layer "F.Cu") (net 2))
  (segment (start 135.75 110.725) (end 135.425 111.05) (width 0.1) (layer "F.Cu") (net 2))
  (segment (start 170.9 100.55) (end 171 100.65) (width 0.4) (layer "F.Cu") (net 2))
  (segment (start 168.9 114.35) (end 169.2 114.65) (width 0.4) (layer "F.Cu") (net 2))
  (segment (start 148.3 119.25) (end 147.95 119.6) (width 0.4) (layer "F.Cu") (net 2))
  (segment (start 157.25 130.1) (end 157.25 129.25) (width 0.3) (layer "F.Cu") (net 2))
  (segment (start 154.5 114.5) (end 154.515 114.485) (width 0.4) (layer "F.Cu") (net 2))
  (segment (start 129.800854 112.700001) (end 130.299999 112.700001) (width 0.4) (layer "F.Cu") (net 2))
  (segment (start 135.75 110.075) (end 135.425 110.4) (width 0.1) (layer "F.Cu") (net 2))
  (segment (start 164.9 109.65) (end 165.4995 109.65) (width 0.4) (layer "F.Cu") (net 2))
  (segment (start 159.1 110.125) (end 158.775 110.45) (width 0.1) (layer "F.Cu") (net 2))
  (segment (start 133 104.325) (end 133 105.35) (width 0.1) (layer "F.Cu") (net 2))
  (segment (start 153.802349 109.45) (end 154.515 109.45) (width 0.4) (layer "F.Cu") (net 2))
  (segment (start 140.285 111.8) (end 140.9 111.8) (width 0.4) (layer "F.Cu") (net 2))
  (segment (start 153.209686 110.45) (end 154.515 110.45) (width 0.4) (layer "F.Cu") (net 2))
  (segment (start 130.515 108.4) (end 129.9 108.4) (width 0.4) (layer "F.Cu") (net 2))
  (segment (start 124 110.685) (end 123 110.685) (width 0.4) (layer "F.Cu") (net 2))
  (segment (start 129.3 110.4) (end 129.2 110.5) (width 0.4) (layer "F.Cu") (net 2))
  (segment (start 140.9 111) (end 140.7 110.8) (width 0.4) (layer "F.Cu") (net 2))
  (segment (start 124 110.685) (end 124 111.4) (width 0.4) (layer "F.Cu") (net 2))
  (segment (start 153.36 107.25) (end 152.99 107.62) (width 0.4) (layer "F.Cu") (net 2))
  (segment (start 153.84 107.25) (end 153.36 107.25) (width 0.4) (layer "F.Cu") (net 2))
  (segment (start 153.197796 110.43811) (end 153.209686 110.45) (width 0.4) (layer "F.Cu") (net 2))
  (segment (start 159.75 110.775) (end 159.425 111.1) (width 0.1) (layer "F.Cu") (net 2))
  (segment (start 135.1 110.725) (end 134.775 111.05) (width 0.1) (layer "F.Cu") (net 2))
  (segment (start 170.2 100.55) (end 170.9 100.55) (width 0.4) (layer "F.Cu") (net 2))
  (segment (start 130 109.4) (end 130.515 109.4) (width 0.4) (layer "F.Cu") (net 2))
  (segment (start 148.05 113.05) (end 148.05 114) (width 0.4) (layer "F.Cu") (net 2))
  (segment (start 166.35 104.6) (end 165.6 103.85) (width 0.4) (layer "F.Cu") (net 2))
  (segment (start 153.92 112.750001) (end 154.299999 112.750001) (width 0.4) (layer "F.Cu") (net 2))
  (segment (start 137.7 109.425) (end 138.125 109.425) (width 0.1) (layer "F.Cu") (net 2))
  (segment (start 130.515 110.4) (end 129.3 110.4) (width 0.4) (layer "F.Cu") (net 2))
  (segment (start 148.3 118.95) (end 148.3 118.3) (width 0.4) (layer "F.Cu") (net 2))
  (segment (start 145.2 114.6995) (end 145.2 115) (width 0.4) (layer "F.Cu") (net 2))
  (segment (start 140.417765 114.672191) (end 140.045574 114.3) (width 0.3) (layer "F.Cu") (net 2))
  (segment (start 140.499999 98.549999) (end 140.5 97.8) (width 0.1) (layer "F.Cu") (net 2))
  (segment (start 140.9 113) (end 141.6 113) (width 0.4) (layer "F.Cu") (net 2))
  (segment (start 159.1 110.775) (end 158.775 111.1) (width 0.1) (layer "F.Cu") (net 2))
  (segment (start 144.90025 114.39975) (end 145.2 114.6995) (width 0.4) (layer "F.Cu") (net 2))
  (segment (start 164.9 113.05) (end 165.6 113.05) (width 0.4) (layer "F.Cu") (net 2))
  (segment (start 153.6 112.335) (end 153.6 112.45) (width 0.4) (layer "F.Cu") (net 2))
  (segment (start 161.5 98.599999) (end 161.5 97.85) (width 0.1) (layer "F.Cu") (net 2))
  (segment (start 129.6 112.285) (end 129.6 112.4) (width 0.4) (layer "F.Cu") (net 2))
  (segment (start 130.299999 112.700001) (end 130.515 112.485) (width 0.4) (layer "F.Cu") (net 2))
  (segment (start 136 98.549999) (end 136 97.8) (width 0.1) (layer "F.Cu") (net 2))
  (segment (start 140.7 110.8) (end 140.285 110.8) (width 0.4) (layer "F.Cu") (net 2))
  (segment (start 166.35 105.2625) (end 166.35 105.9) (width 0.1) (layer "F.Cu") (net 2))
  (via (at 168.15 121.35) (size 0.6) (drill 0.2) (layers "F.Cu" "B.Cu") (net 2))
  (via (at 135.425 111.7) (size 0.4) (drill 0.15) (layers "F.Cu" "B.Cu") (net 2))
  (via (at 140.5 97.8) (size 0.4) (drill 0.15) (layers "F.Cu" "B.Cu") (net 2))
  (via (at 116 107) (size 0.6) (drill 0.2) (layers "F.Cu" "B.Cu") (free) (net 2))
  (via (at 138.175 109) (size 0.4) (drill 0.15) (layers "F.Cu" "B.Cu") (net 2))
  (via (at 149 91) (size 0.6) (drill 0.2) (layers "F.Cu" "B.Cu") (free) (net 2))
  (via (at 148.25 118.25) (size 0.6) (drill 0.2) (layers "F.Cu" "B.Cu") (net 2))
  (via (at 122 91) (size 0.6) (drill 0.2) (layers "F.Cu" "B.Cu") (free) (net 2))
  (via (at 156.35 117.45) (size 0.4) (drill 0.15) (layers "F.Cu" "B.Cu") (free) (net 2))
  (via (at 155 91) (size 0.6) (drill 0.2) (layers "F.Cu" "B.Cu") (free) (net 2))
  (via (at 141.4995 109.6) (size 0.6) (drill 0.2) (layers "F.Cu" "B.Cu") (net 2))
  (via (at 134.775 110.4) (size 0.4) (drill 0.15) (layers "F.Cu" "B.Cu") (net 2))
  (via (at 154.25 129.25) (size 0.4) (drill 0.15) (layers "F.Cu" "B.Cu") (net 2))
  (via (at 157.1 118.15) (size 0.4) (drill 0.15) (layers "F.Cu" "B.Cu") (free) (net 2))
  (via (at 164.5 97.85) (size 0.4) (drill 0.15) (layers "F.Cu" "B.Cu") (net 2))
  (via (at 148 111.45) (size 0.6) (drill 0.2) (layers "F.Cu" "B.Cu") (net 2))
  (via (at 134.775 109.75) (size 0.4) (drill 0.15) (layers "F.Cu" "B.Cu") (net 2))
  (via (at 158.5 97.85) (size 0.4) (drill 0.15) (layers "F.Cu" "B.Cu") (net 2))
  (via (at 173 91) (size 0.6) (drill 0.2) (layers "F.Cu" "B.Cu") (free) (net 2))
  (via (at 165.6 113.05) (size 0.6) (drill 0.2) (layers "F.Cu" "B.Cu") (net 2))
  (via (at 124 111.4) (size 0.6) (drill 0.2) (layers "F.Cu" "B.Cu") (net 2))
  (via (at 158.5 105.4) (size 0.4) (drill 0.15) (layers "F.Cu" "B.Cu") (net 2))
  (via (at 161 91) (size 0.6) (drill 0.2) (layers "F.Cu" "B.Cu") (free) (net 2))
  (via (at 153.92 112.750001) (size 0.6) (drill 0.2) (layers "F.Cu" "B.Cu") (net 2))
  (via (at 129.2 110.5) (size 0.6) (drill 0.2) (layers "F.Cu" "B.Cu") (net 2))
  (via (at 166.15 119.25) (size 0.6) (drill 0.2) (layers "F.Cu" "B.Cu") (net 2))
  (via (at 172.55 97.7) (size 0.6) (drill 0.2) (layers "F.Cu" "B.Cu") (free) (net 2))
  (via (at 158.775 109.8) (size 0.4) (drill 0.15) (layers "F.Cu" "B.Cu") (net 2))
  (via (at 143 134) (size 0.6) (drill 0.2) (layers "F.Cu" "B.Cu") (free) (net 2))
  (via (at 140 91) (size 0.6) (drill 0.2) (layers "F.Cu" "B.Cu") (free) (net 2))
  (via (at 155 134) (size 0.6) (drill 0.2) (layers "F.Cu" "B.Cu") (free) (net 2))
  (via (at 123 104.2) (size 0.6) (drill 0.2) (layers "F.Cu" "B.Cu") (net 2))
  (via (at 134 134) (size 0.6) (drill 0.2) (layers "F.Cu" "B.Cu") (free) (net 2))
  (via (at 148 104.25) (size 0.6) (drill 0.2) (layers "F.Cu" "B.Cu") (net 2))
  (via (at 158 134) (size 0.6) (drill 0.2) (layers "F.Cu" "B.Cu") (free) (net 2))
  (via (at 160.075 111.1) (size 0.4) (drill 0.15) (layers "F.Cu" "B.Cu") (net 2))
  (via (at 138.15 109.45) (size 0.4) (drill 0.15) (layers "F.Cu" "B.Cu") (net 2))
  (via (at 176 91) (size 0.6) (drill 0.2) (layers "F.Cu" "B.Cu") (free) (net 2))
  (via (at 116 125) (size 0.6) (drill 0.2) (layers "F.Cu" "B.Cu") (free) (net 2))
  (via (at 158.775 111.1) (size 0.4) (drill 0.15) (layers "F.Cu" "B.Cu") (net 2))
  (via (at 160.075 110.45) (size 0.4) (drill 0.15) (layers "F.Cu" "B.Cu") (net 2))
  (via (at 162.15 109.5) (size 0.4) (drill 0.15) (layers "F.Cu" "B.Cu") (net 2))
  (via (at 125 91) (size 0.6) (drill 0.2) (layers "F.Cu" "B.Cu") (free) (net 2))
  (via (at 165.46 107.64) (size 0.6) (drill 0.2) (layers "F.Cu" "B.Cu") (net 2))
  (via (at 167 91) (size 0.6) (drill 0.2) (layers "F.Cu" "B.Cu") (free) (net 2))
  (via (at 149 134) (size 0.6) (drill 0.2) (layers "F.Cu" "B.Cu") (free) (net 2))
  (via (at 116 116) (size 0.6) (drill 0.2) (layers "F.Cu" "B.Cu") (free) (net 2))
  (via (at 143 91) (size 0.6) (drill 0.2) (layers "F.Cu" "B.Cu") (free) (net 2))
  (via (at 141.6 113) (size 0.6) (drill 0.2) (layers "F.Cu" "B.Cu") (net 2))
  (via (at 116 122) (size 0.6) (drill 0.2) (layers "F.Cu" "B.Cu") (free) (net 2))
  (via (at 147 104.25) (size 0.6) (drill 0.2) (layers "F.Cu" "B.Cu") (net 2))
  (via (at 123 111.4) (size 0.6) (drill 0.2) (layers "F.Cu" "B.Cu") (net 2))
  (via (at 164.164265 103.804265) (size 0.6) (drill 0.2) (layers "F.Cu" "B.Cu") (net 2))
  (via (at 146 91) (size 0.6) (drill 0.2) (layers "F.Cu" "B.Cu") (free) (net 2))
  (via (at 147.95 119.6) (size 0.6) (drill 0.2) (layers "F.Cu" "B.Cu") (net 2))
  (via (at 140.9 111) (size 0.6) (drill 0.2) (layers "F.Cu" "B.Cu") (net 2))
  (via (at 143.95 121.35) (size 0.6) (drill 0.2) (layers "F.Cu" "B.Cu") (net 2))
  (via (at 129.9 106.475) (size 0.6) (drill 0.2) (layers "F.Cu" "B.Cu") (net 2))
  (via (at 161.5 97.85) (size 0.4) (drill 0.15) (layers "F.Cu" "B.Cu") (net 2))
  (via (at 144.95 106.43) (size 0.6) (drill 0.2) (layers "F.Cu" "B.Cu") (net 2))
  (via (at 133 97.8) (size 0.4) (drill 0.15) (layers "F.Cu" "B.Cu") (net 2))
  (via (at 172.55 100.7) (size 0.6) (drill 0.2) (layers "F.Cu" "B.Cu") (free) (net 2))
  (via (at 164 134) (size 0.6) (drill 0.2) (layers "F.Cu" "B.Cu") (free) (net 2))
  (via (at 159.425 111.1) (size 0.4) (drill 0.15) (layers "F.Cu" "B.Cu") (net 2))
  (via (at 157 105.4) (size 0.4) (drill 0.15) (layers "F.Cu" "B.Cu") (net 2))
  (via (at 170 91) (size 0.6) (drill 0.2) (layers "F.Cu" "B.Cu") (free) (net 2))
  (via (at 152 134) (size 0.6) (drill 0.2) (layers "F.Cu" "B.Cu") (free) (net 2))
  (via (at 174 129) (size 0.6) (drill 0.2) (layers "F.Cu" "B.Cu") (free) (net 2))
  (via (at 116 134) (size 0.6) (drill 0.2) (layers "F.Cu" "B.Cu") (free) (net 2))
  (via (at 137 134) (size 0.6) (drill 0.2) (layers "F.Cu" "B.Cu") (free) (net 2))
  (via (at 157.25 129.25) (size 0.4) (drill 0.15) (layers "F.Cu" "B.Cu") (net 2))
  (via (at 116 119) (size 0.6) (drill 0.2) (layers "F.Cu" "B.Cu") (free) (net 2))
  (via (at 131 91) (size 0.6) (drill 0.2) (layers "F.Cu" "B.Cu") (free) (net 2))
  (via (at 164.9 111.85) (size 0.6) (drill 0.2) (layers "F.Cu" "B.Cu") (net 2))
  (via (at 137 91) (size 0.6) (drill 0.2) (layers "F.Cu" "B.Cu") (free) (net 2))
  (via (at 172.25 118.2) (size 0.6) (drill 0.2) (layers "F.Cu" "B.Cu") (net 2))
  (via (at 161 134) (size 0.6) (drill 0.2) (layers "F.Cu" "B.Cu") (free) (net 2))
  (via (at 171.75 127.75) (size 0.6) (drill 0.2) (layers "F.Cu" "B.Cu") (free) (net 2))
  (via (at 176 134) (size 0.6) (drill 0.2) (layers "F.Cu" "B.Cu") (free) (net 2))
  (via (at 152.75 129.25) (size 0.4) (drill 0.15) (layers "F.Cu" "B.Cu") (net 2))
  (via (at 130.7 114.4) (size 0.6) (drill 0.2) (layers "F.Cu" "B.Cu") (net 2))
  (via (at 152 91) (size 0.6) (drill 0.2) (layers "F.Cu" "B.Cu") (free) (net 2))
  (via (at 116 110) (size 0.6) (drill 0.2) (layers "F.Cu" "B.Cu") (free) (net 2))
  (via (at 129.1 112.9) (size 0.6) (drill 0.2) (layers "F.Cu" "B.Cu") (net 2))
  (via (at 140 134) (size 0.6) (drill 0.2) (layers "F.Cu" "B.Cu") (free) (net 2))
  (via (at 160 97.85) (size 0.4) (drill 0.15) (layers "F.Cu" "B.Cu") (net 2))
  (via (at 124 104.2) (size 0.6) (drill 0.2) (layers "F.Cu" "B.Cu") (net 2))
  (via (at 160.15 117.3) (size 0.4) (drill 0.15) (layers "F.Cu" "B.Cu") (free) (net 2))
  (via (at 140.9 111.8) (size 0.6) (drill 0.2) (layers "F.Cu" "B.Cu") (net 2))
  (via (at 164.4 114.6) (size 0.6) (drill 0.2) (layers "F.Cu" "B.Cu") (net 2))
  (via (at 172.55 109.7) (size 0.6) (drill 0.2) (layers "F.Cu" "B.Cu") (free) (net 2))
  (via (at 153.1 112.95) (size 0.6) (drill 0.2) (layers "F.Cu" "B.Cu") (net 2))
  (via (at 157 97.85) (size 0.4) (drill 0.15) (layers "F.Cu" "B.Cu") (net 2))
  (via (at 172.35 114) (size 0.6) (drill 0.2) (layers "F.Cu" "B.Cu") (net 2))
  (via (at 158.775 111.75) (size 0.4) (drill 0.15) (layers "F.Cu" "B.Cu") (net 2))
  (via (at 135.425 110.4) (size 0.4) (drill 0.15) (layers "F.Cu" "B.Cu") (net 2))
  (via (at 172.55 103.7) (size 0.6) (drill 0.2) (layers "F.Cu" "B.Cu") (free) (net 2))
  (via (at 158.775 110.45) (size 0.4) (drill 0.15) (layers "F.Cu" "B.Cu") (net 2))
  (via (at 147 111.45) (size 0.6) (drill 0.2) (layers "F.Cu" "B.Cu") (net 2))
  (via (at 148.25 129.2) (size 0.4) (drill 0.15) (layers "F.Cu" "B.Cu") (free) (net 2))
  (via (at 153.197796 110.43811) (size 0.6) (drill 0.2) (layers "F.Cu" "B.Cu") (net 2))
  (via (at 171.75 124.75) (size 0.6) (drill 0.2) (layers "F.Cu" "B.Cu") (free) (net 2))
  (via (at 172.55 106.7) (size 0.6) (drill 0.2) (layers "F.Cu" "B.Cu") (free) (net 2))
  (via (at 128 134) (size 0.6) (drill 0.2) (layers "F.Cu" "B.Cu") (free) (net 2))
  (via (at 136 105.35) (size 0.4) (drill 0.15) (layers "F.Cu" "B.Cu") (net 2))
  (via (at 160 105.4) (size 0.4) (drill 0.15) (layers "F.Cu" "B.Cu") (net 2))
  (via (at 170 134) (size 0.6) (drill 0.2) (layers "F.Cu" "B.Cu") (free) (net 2))
  (via (at 169.29 106.04) (size 0.6) (drill 0.2) (layers "F.Cu" "B.Cu") (net 2))
  (via (at 116 113) (size 0.6) (drill 0.2) (layers "F.Cu" "B.Cu") (free) (net 2))
  (via (at 148.1 114.05) (size 0.6) (drill 0.2) (layers "F.Cu" "B.Cu") (net 2))
  (via (at 131 134) (size 0.6) (drill 0.2) (layers "F.Cu" "B.Cu") (free) (net 2))
  (via (at 156.8 113.075) (size 0.4) (drill 0.15) (layers "F.Cu" "B.Cu") (net 2))
  (via (at 142.35 105.85) (size 0.4) (drill 0.15) (layers "F.Cu" "B.Cu") (net 2))
  (via (at 116.16 91.71) (size 0.6) (drill 0.2) (layers "F.Cu" "B.Cu") (free) (net 2))
  (via (at 122 134) (size 0.6) (drill 0.2) (layers "F.Cu" "B.Cu") (free) (net 2))
  (via (at 132.8 113.025) (size 0.4) (drill 0.15) (layers "F.Cu" "B.Cu") (net 2))
  (via (at 162.175 109.05) (size 0.4) (drill 0.15) (layers "F.Cu" "B.Cu") (net 2))
  (via (at 134.775 111.05) (size 0.4) (drill 0.15) (layers "F.Cu" "B.Cu") (net 2))
  (via (at 159.425 110.45) (size 0.4) (drill 0.15) (layers "F.Cu" "B.Cu") (net 2))
  (via (at 166.35 105.9) (size 0.4) (drill 0.15) (layers "F.Cu" "B.Cu") (net 2))
  (via (at 164.9 110.85) (size 0.6) (drill 0.2) (layers "F.Cu" "B.Cu") (net 2))
  (via (at 147.8 125.35) (size 0.4) (drill 0.15) (layers "F.Cu" "B.Cu") (free) (net 2))
  (via (at 140.14 103.99) (size 0.6) (drill 0.2) (layers "F.Cu" "B.Cu") (net 2))
  (via (at 171.75 121.75) (size 0.6) (drill 0.2) (layers "F.Cu" "B.Cu") (free) (net 2))
  (via (at 133 105.35) (size 0.4) (drill 0.15) (layers "F.Cu" "B.Cu") (net 2))
  (via (at 134.775 111.7) (size 0.4) (drill 0.15) (layers "F.Cu" "B.Cu") (net 2))
  (via (at 172.35 119.75) (size 0.6) (drill 0.2) (layers "F.Cu" "B.Cu") (net 2))
  (via (at 136 97.8) (size 0.4) (drill 0.15) (layers "F.Cu" "B.Cu") (net 2))
  (via (at 141.48 106.8995) (size 0.6) (drill 0.2) (layers "F.Cu" "B.Cu") (net 2))
  (via (at 144.90025 114.39975) (size 0.6) (drill 0.2) (layers "F.Cu" "B.Cu") (net 2))
  (via (at 141 108.06) (size 0.6) (drill 0.2) (layers "F.Cu" "B.Cu") (net 2))
  (via (at 116 98) (size 0.6) (drill 0.2) (layers "F.Cu" "B.Cu") (free) (net 2))
  (via (at 116 101) (size 0.6) (drill 0.2) (layers "F.Cu" "B.Cu") (free) (net 2))
  (via (at 140.417765 114.672191) (size 0.6) (drill 0.2) (layers "F.Cu" "B.Cu") (net 2))
  (via (at 153.9 108.45) (size 0.6) (drill 0.2) (layers "F.Cu" "B.Cu") (net 2))
  (via (at 158 91) (size 0.6) (drill 0.2) (layers "F.Cu" "B.Cu") (free) (net 2))
  (via (at 167 134) (size 0.6) (drill 0.2) (layers "F.Cu" "B.Cu") (free) (net 2))
  (via (at 116 128) (size 0.6) (drill 0.2) (layers "F.Cu" "B.Cu") (free) (net 2))
  (via (at 171 100.65) (size 0.4) (drill 0.15) (layers "F.Cu" "B.Cu") (net 2))
  (via (at 161.5 105.4) (size 0.4) (drill 0.15) (layers "F.Cu" "B.Cu") (net 2))
  (via (at 154.5 114.5) (size 0.6) (drill 0.2) (layers "F.Cu" "B.Cu") (net 2))
  (via (at 137.5 105.35) (size 0.4) (drill 0.15) (layers "F.Cu" "B.Cu") (net 2))
  (via (at 129.3 108.7) (size 0.6) (drill 0.2) (layers "F.Cu" "B.Cu") (net 2))
  (via (at 153.309666 108.957317) (size 0.6) (drill 0.2) (layers "F.Cu" "B.Cu") (net 2))
  (via (at 137.5 97.8) (size 0.4) (drill 0.15) (layers "F.Cu" "B.Cu") (net 2))
  (via (at 159.425 111.75) (size 0.4) (drill 0.15) (layers "F.Cu" "B.Cu") (net 2))
  (via (at 125 134) (size 0.6) (drill 0.2) (layers "F.Cu" "B.Cu") (free) (net 2))
  (via (at 146.7 129.15) (size 0.4) (drill 0.15) (layers "F.Cu" "B.Cu") (free) (net 2))
  (via (at 129.9 108.4) (size 0.6) (drill 0.2) (layers "F.Cu" "B.Cu") (net 2))
  (via (at 153.9 106.525) (size 0.6) (drill 0.2) (layers "F.Cu" "B.Cu") (net 2))
  (via (at 134 91) (size 0.6) (drill 0.2) (layers "F.Cu" "B.Cu") (free) (net 2))
  (via (at 134.5 105.35) (size 0.4) (drill 0.15) (layers "F.Cu" "B.Cu") (net 2))
  (via (at 146.7 126.45) (size 0.4) (drill 0.15) (layers "F.Cu" "B.Cu") (free) (net 2))
  (via (at 142.15 119.2) (size 0.6) (drill 0.2) (layers "F.Cu" "B.Cu") (net 2))
  (via (at 146 134) (size 0.6) (drill 0.2) (layers "F.Cu" "B.Cu") (free) (net 2))
  (via (at 136.075 111.05) (size 0.4) (drill 0.15) (layers "F.Cu" "B.Cu") (net 2))
  (via (at 136.075 110.4) (size 0.4) (drill 0.15) (layers "F.Cu" "B.Cu") (net 2))
  (via (at 165.410294 106.9495) (size 0.6) (drill 0.2) (layers "F.Cu" "B.Cu") (net 2))
  (via (at 116 104) (size 0.6) (drill 0.2) (layers "F.Cu" "B.Cu") (free) (net 2))
  (via (at 164 91) (size 0.6) (drill 0.2) (layers "F.Cu" "B.Cu") (free) (net 2))
  (via (at 165.4995 109.65) (size 0.6) (drill 0.2) (layers "F.Cu" "B.Cu") (net 2))
  (via (at 173 134) (size 0.6) (drill 0.2) (layers "F.Cu" "B.Cu") (free) (net 2))
  (via (at 128 91) (size 0.6) (drill 0.2) (layers "F.Cu" "B.Cu") (free) (net 2))
  (via (at 159.55 116.15) (size 0.4) (drill 0.15) (layers "F.Cu" "B.Cu") (free) (net 2))
  (via (at 147 100.6) (size 0.6) (drill 0.2) (layers "F.Cu" "B.Cu") (net 2))
  (via (at 182 134) (size 0.6) (drill 0.2) (layers "F.Cu" "B.Cu") (free) (net 2))
  (via (at 155.75 129.25) (size 0.4) (drill 0.15) (layers "F.Cu" "B.Cu") (net 2))
  (via (at 168.9 114.35) (size 0.6) (drill 0.2) (layers "F.Cu" "B.Cu") (net 2))
  (via (at 129.800854 112.700001) (size 0.6) (drill 0.2) (layers "F.Cu" "B.Cu") (net 2))
  (via (at 134.5 97.8) (size 0.4) (drill 0.15) (layers "F.Cu" "B.Cu") (net 2))
  (via (at 135.425 111.05) (size 0.4) (drill 0.15) (layers "F.Cu" "B.Cu") (net 2))
  (segment (start 140.4 109.1) (end 140.285 109.1) (width 0.4) (layer "B.Cu") (net 2))
  (segment (start 164.9 109.65) (end 164.4 109.15) (width 0.4) (layer "B.Cu") (net 2))
  (segment (start 165.46 107.64) (end 164.95 108.15) (width 0.4) (layer "B.Cu") (net 2))
  (segment (start 165.4995 109.65) (end 164.9 109.65) (width 0.4) (layer "B.Cu") (net 2))
  (segment (start 164.4 109.15) (end 164.285 109.15) (width 0.4) (layer "B.Cu") (net 2))
  (segment (start 140.9 110.8) (end 140.285 110.185) (width 0.4) (layer "B.Cu") (net 2))
  (segment (start 140.96 108.1) (end 140.285 108.1) (width 0.4) (layer "B.Cu") (net 2))
  (segment (start 140.9 109.6) (end 140.4 109.1) (width 0.4) (layer "B.Cu") (net 2))
  (segment (start 164.285 108.15) (end 164.285 109.15) (width 0.4) (layer "B.Cu") (net 2))
  (segment (start 140.285 108.1) (end 140.285 109.1) (width 0.4) (layer "B.Cu") (net 2))
  (segment (start 164.285 109.15) (end 164.285 110.15) (width 0.4) (layer "B.Cu") (net 2))
  (segment (start 164.285 110.235) (end 164.9 110.85) (width 0.4) (layer "B.Cu") (net 2))
  (segment (start 140.9 111) (end 140.9 110.8) (width 0.4) (layer "B.Cu") (net 2))
  (segment (start 140.285 109.1) (end 140.285 110.1) (width 0.4) (layer "B.Cu") (net 2))
  (segment (start 141.4995 109.6) (end 140.9 109.6) (width 0.4) (layer "B.Cu") (net 2))
  (segment (start 164.95 108.15) (end 164.285 108.15) (width 0.4) (layer "B.Cu") (net 2))
  (segment (start 141 108.06) (end 140.96 108.1) (width 0.4) (layer "B.Cu") (net 2))
  (segment (start 138.7 109.725) (end 138.7 109.1) (width 0.3) (layer "F.Cu") (net 3))
  (segment (start 137.7 110.725) (end 138.7 109.725) (width 0.3) (layer "F.Cu") (net 3))
  (via (at 138.7 109.1) (size 0.4) (drill 0.15) (layers "F.Cu" "B.Cu") (net 3))
  (segment (start 138.7 109.1) (end 139.315 109.1) (width 0.3) (layer "B.Cu") (net 3))
  (segment (start 137.374468 111.036221) (end 137.374468 111.050532) (width 0.3) (layer "F.Cu") (net 4))
  (segment (start 137.374468 111.050532) (end 137.05 111.375) (width 0.3) (layer "F.Cu") (net 4))
  (via (at 137.374468 111.036221) (size 0.4) (drill 0.15) (layers "F.Cu" "B.Cu") (net 4))
  (segment (start 137.463779 111.036221) (end 138.4 110.1) (width 0.4) (layer "B.Cu") (net 4))
  (segment (start 137.374468 111.036221) (end 137.463779 111.036221) (width 0.4) (layer "B.Cu") (net 4))
  (segment (start 138.4 110.1) (end 139.315 110.1) (width 0.4) (layer "B.Cu") (net 4))
  (segment (start 140.2 110.23) (end 141.03 110.23) (width 0.3) (layer "F.Cu") (net 5))
  (segment (start 139.315 110.8) (end 139.315 109.615) (width 0.4) (layer "F.Cu") (net 5))
  (segment (start 138.6 110.8) (end 139.315 110.8) (width 0.4) (layer "F.Cu") (net 5))
  (segment (start 139.45 109.48) (end 140.2 110.23) (width 0.3) (layer "F.Cu") (net 5))
  (segment (start 137.05 110.725) (end 137.375 110.4) (width 0.3) (layer "F.Cu") (net 5))
  (segment (start 141.03 110.23) (end 142.35 111.55) (width 0.3) (layer "F.Cu") (net 5))
  (segment (start 139.315 109.615) (end 139.45 109.48) (width 0.4) (layer "F.Cu") (net 5))
  (via (at 137.375 110.4) (size 0.4) (drill 0.15) (layers "F.Cu" "B.Cu") (net 5))
  (via (at 138.6 110.8) (size 0.4) (drill 0.15) (layers "F.Cu" "B.Cu") (net 5))
  (segment (start 138.6 110.8) (end 138.2 110.4) (width 0.4) (layer "In2.Cu") (net 5))
  (segment (start 138.2 110.4) (end 137.375 110.4) (width 0.4) (layer "In2.Cu") (net 5))
  (segment (start 139.16 108.15) (end 139.26 108.05) (width 0.4) (layer "F.Cu") (net 6))
  (segment (start 142.6 109.75) (end 141.57 108.72) (width 0.3) (layer "F.Cu") (net 6))
  (segment (start 135.75 109.439473) (end 135.444097 109.745376) (width 0.1) (layer "F.Cu") (net 6))
  (segment (start 139.26 108.05) (end 139.26 106.97) (width 0.4) (layer "F.Cu") (net 6))
  (segment (start 139.73 108.72) (end 139.16 108.15) (width 0.3) (layer "F.Cu") (net 6))
  (segment (start 141.57 108.72) (end 139.73 108.72) (width 0.3) (layer "F.Cu") (net 6))
  (segment (start 135.444097 109.745376) (end 135.414298 109.745376) (width 0.1) (layer "F.Cu") (net 6))
  (segment (start 139.16 108.15) (end 138.952868 108.357132) (width 0.4) (layer "F.Cu") (net 6))
  (segment (start 138.952868 108.357132) (end 138.592869 108.357132) (width 0.4) (layer "F.Cu") (net 6))
  (segment (start 137.05 108.775) (end 137.375 108.45) (width 0.1) (layer "F.Cu") (net 6))
  (via (at 135.414298 109.745376) (size 0.4) (drill 0.15) (layers "F.Cu" "B.Cu") (net 6))
  (via (at 138.592869 108.357132) (size 0.4) (drill 0.15) (layers "F.Cu" "B.Cu") (net 6))
  (via (at 137.375 108.45) (size 0.4) (drill 0.15) (layers "F.Cu" "B.Cu") (net 6))
  (segment (start 135.414298 109.745376) (end 135.414298 109.185702) (width 0.4) (layer "In2.Cu") (net 6))
  (segment (start 138.464239 108.357132) (end 138.382107 108.275) (width 0.4) (layer "In2.Cu") (net 6))
  (segment (start 136.15 108.45) (end 137.375 108.45) (width 0.4) (layer "In2.Cu") (net 6))
  (segment (start 138.592869 108.357132) (end 138.464239 108.357132) (width 0.4) (layer "In2.Cu") (net 6))
  (segment (start 138.382107 108.275) (end 137.55 108.275) (width 0.4) (layer "In2.Cu") (net 6))
  (segment (start 137.55 108.275) (end 137.375 108.45) (width 0.4) (layer "In2.Cu") (net 6))
  (segment (start 135.414298 109.185702) (end 136.15 108.45) (width 0.4) (layer "In2.Cu") (net 6))
  (segment (start 134.45 111.375) (end 134.125 111.7) (width 0.1) (layer "F.Cu") (net 7))
  (segment (start 139.5 113) (end 140.3 113.8) (width 0.4) (layer "F.Cu") (net 7))
  (segment (start 136.4 111.375) (end 136.075 111.7) (width 0.3) (layer "F.Cu") (net 7))
  (segment (start 139.315 111.8) (end 138.6 111.8) (width 0.4) (layer "F.Cu") (net 7))
  (segment (start 139.315 112.815) (end 139.5 113) (width 0.4) (layer "F.Cu") (net 7))
  (segment (start 141.45 115.5) (end 141.45 114.55) (width 0.4) (layer "F.Cu") (net 7))
  (segment (start 140.3 113.8) (end 140.7 113.8) (width 0.4) (layer "F.Cu") (net 7))
  (segment (start 141.45 114.55) (end 140.7 113.8) (width 0.4) (layer "F.Cu") (net 7))
  (segment (start 139.315 111.8) (end 139.315 112.815) (width 0.4) (layer "F.Cu") (net 7))
  (via (at 136.075 111.7) (size 0.4) (drill 0.15) (layers "F.Cu" "B.Cu") (net 7))
  (via (at 134.125 111.7) (size 0.4) (drill 0.15) (layers "F.Cu" "B.Cu") (net 7))
  (via (at 138.6 111.8) (size 0.4) (drill 0.15) (layers "F.Cu" "B.Cu") (net 7))
  (segment (start 138.2 112.2) (end 136.575 112.2) (width 0.4) (layer "In2.Cu") (net 7))
  (segment (start 134.125 111.757107) (end 134.567893 112.2) (width 0.4) (layer "In2.Cu") (net 7))
  (segment (start 135.7 112.2) (end 136.075 111.825) (width 0.4) (layer "In2.Cu") (net 7))
  (segment (start 136.575 112.2) (end 136.075 111.7) (width 0.4) (layer "In2.Cu") (net 7))
  (segment (start 136.075 111.825) (end 136.075 111.7) (width 0.4) (layer "In2.Cu") (net 7))
  (segment (start 134.567893 112.2) (end 135.7 112.2) (width 0.4) (layer "In2.Cu") (net 7))
  (segment (start 134.125 111.7) (end 134.125 111.757107) (width 0.4) (layer "In2.Cu") (net 7))
  (segment (start 138.6 111.8) (end 138.2 112.2) (width 0.4) (layer "In2.Cu") (net 7))
  (segment (start 133.786397 108.775) (end 133.505698 108.494301) (width 0.4) (layer "F.Cu") (net 8))
  (segment (start 133.8 108.775) (end 133.786397 108.775) (width 0.4) (layer "F.Cu") (net 8))
  (segment (start 131.485 108.4) (end 132 108.4) (width 0.4) (layer "F.Cu") (net 8))
  (segment (start 131.3 107.2) (end 131.3 108.215) (width 0.4) (layer "F.Cu") (net 8))
  (segment (start 131.3 107.2) (end 131.3 106.25) (width 0.4) (layer "F.Cu") (net 8))
  (segment (start 131.3 106.25) (end 130.45 105.4) (width 0.4) (layer "F.Cu") (net 8))
  (segment (start 139.8 117.5) (end 139.8 116.8) (width 0.4) (layer "F.Cu") (net 8))
  (segment (start 131.3 108.215) (end 131.485 108.4) (width 0.4) (layer "F.Cu") (net 8))
  (via (at 139.8 117.5) (size 0.6) (drill 0.2) (layers "F.Cu" "B.Cu") (net 8))
  (via (at 132 108.4) (size 0.4) (drill 0.15) (layers "F.Cu" "B.Cu") (net 8))
  (via (at 133.505698 108.494301) (size 0.4) (drill 0.15) (layers "F.Cu" "B.Cu") (net 8))
  (segment (start 132.094301 108.494301) (end 132 108.4) (width 0.4) (layer "In2.Cu") (net 8))
  (segment (start 133.505698 108.494301) (end 132.094301 108.494301) (width 0.4) (layer "In2.Cu") (net 8))
  (segment (start 132 108.4) (end 131.3 109.1) (width 0.4) (layer "In2.Cu") (net 8))
  (segment (start 131.3 109.1) (end 131.3 114.6) (width 0.4) (layer "In2.Cu") (net 8))
  (segment (start 131.3 114.6) (end 134.2 117.5) (width 0.4) (layer "In2.Cu") (net 8))
  (segment (start 134.2 117.5) (end 139.8 117.5) (width 0.4) (layer "In2.Cu") (net 8))
  (segment (start 141.3 120.6) (end 142.85 120.6) (width 0.4) (layer "F.Cu") (net 9))
  (segment (start 142.85 120.6) (end 143 120.45) (width 0.4) (layer "F.Cu") (net 9))
  (segment (start 124.75 105.85) (end 124.035 105.85) (width 0.4) (layer "F.Cu") (net 9))
  (segment (start 167.2 121.5) (end 167.1 121.6) (width 0.4) (layer "F.Cu") (net 9))
  (segment (start 167.2 120.45) (end 167.2 121.5) (width 0.4) (layer "F.Cu") (net 9))
  (segment (start 147.55 116.5) (end 149 116.5) (width 0.4) (layer "F.Cu") (net 9))
  (segment (start 167.4 119.65) (end 168.9 119.65) (width 0.4) (layer "F.Cu") (net 9))
  (segment (start 146.9 117.7) (end 146.75 117.7) (width 0.4) (layer "F.Cu") (net 9))
  (segment (start 144.1 108.57) (end 145.1 108.57) (width 0.3) (layer "F.Cu") (net 9))
  (segment (start 164.318374 104.610156) (end 164.318374 104.729374) (width 0.1) (layer "F.Cu") (net 9))
  (segment (start 143.315 106.25) (end 142.8 106.25) (width 0.4) (layer "F.Cu") (net 9))
  (segment (start 123 105.885) (end 123 106.4) (width 0.4) (layer "F.Cu") (net 9))
  (segment (start 148 105.935) (end 147 105.935) (width 0.4) (layer "F.Cu") (net 9))
  (segment (start 144.45 119.65) (end 144.9 120.1) (width 0.4) (layer "F.Cu") (net 9))
  (segment (start 171.3 116.65) (end 171.5 116.45) (width 0.4) (layer "F.Cu") (net 9))
  (segment (start 169.15 108.435) (end 169.15 109.15) (width 0.4) (layer "F.Cu") (net 9))
  (segment (start 144.1 108.57) (end 144.1 108.95) (width 0.4) (layer "F.Cu") (net 9))
  (segment (start 144.9 120.45) (end 144.9 121.55) (width 0.4) (layer "F.Cu") (net 9))
  (segment (start 144.9 120.1) (end 144.9 120.45) (width 0.4) (layer "F.Cu") (net 9))
  (segment (start 147.3 116.75) (end 147.55 116.5) (width 0.4) (layer "F.Cu") (net 9))
  (segment (start 169.1 121.5) (end 169.15 121.55) (width 0.4) (layer "F.Cu") (net 9))
  (segment (start 147.8 107.125) (end 147.8 106.135) (width 0.4) (layer "F.Cu") (net 9))
  (segment (start 123.8 107.075) (end 123.8 106.085) (width 0.4) (layer "F.Cu") (net 9))
  (segment (start 173.2 116.65) (end 173.2 117.3) (width 0.4) (layer "F.Cu") (net 9))
  (segment (start 144.1 108.95) (end 144.4 109.25) (width 0.4) (layer "F.Cu") (net 9))
  (segment (start 170.95 119.9) (end 170.9 119.95) (width 0.4) (layer "F.Cu") (net 9))
  (segment (start 165.5 120.65) (end 167 120.65) (width 0.4) (layer "F.Cu") (net 9))
  (segment (start 170.95 117.65) (end 170.5 117.65) (width 0.4) (layer "F.Cu") (net 9))
  (segment (start 146.9 118.95) (end 146.9 117.7) (width 0.4) (layer "F.Cu") (net 9))
  (segment (start 147.8 106.135) (end 148 105.935) (width 0.4) (layer "F.Cu") (net 9))
  (segment (start 133.75 102.475) (end 133.75 101.45) (width 0.1) (layer "F.Cu") (net 9))
  (segment (start 136.75 102.475) (end 136.75 101.4495) (width 0.1) (layer "F.Cu") (net 9))
  (segment (start 170.95 117.65) (end 171.3 117.3) (width 0.4) (layer "F.Cu") (net 9))
  (segment (start 149 116.5) (end 149.2 116.7) (width 0.4) (layer "F.Cu") (net 9))
  (segment (start 167.2 119.85) (end 167.4 119.65) (width 0.4) (layer "F.Cu") (net 9))
  (segment (start 137.75 129.45) (end 138 129.2) (width 0.3) (layer "F.Cu") (net 9))
  (segment (start 138 128.8) (end 138 128.4) (width 0.3) (layer "F.Cu") (net 9))
  (segment (start 157.75 102.525) (end 157.75 101.5) (width 0.1) (layer "F.Cu") (net 9))
  (segment (start 149.2 117.3) (end 149.5 117.3) (width 0.4) (layer "F.Cu") (net 9))
  (segment (start 169.1 120.45) (end 169.1 121.5) (width 0.4) (layer "F.Cu") (net 9))
  (segment (start 143 120.45) (end 143 121.5) (width 0.4) (layer "F.Cu") (net 9))
  (segment (start 160.75 102.525) (end 160.75 101.4995) (width 0.1) (layer "F.Cu") (net 9))
  (segment (start 170.5 117.65) (end 170.45 117.7) (width 0.4) (layer "F.Cu") (net 9))
  (segment (start 124 105.885) (end 123 105.885) (width 0.4) (layer "F.Cu") (net 9))
  (segment (start 173 116.45) (end 173.2 116.65) (width 0.4) (layer "F.Cu") (net 9))
  (segment (start 145.1 108.57) (end 145.1 109.2) (width 0.4) (layer "F.Cu") (net 9))
  (segment (start 171.3 117.3) (end 171.3 117.65) (width 0.4) (layer "F.Cu") (net 9))
  (segment (start 137.75 130.1) (end 137.75 129.45) (width 0.3) (layer "F.Cu") (net 9))
  (segment (start 142.8 106.25) (end 142.75 106.3) (width 0.4) (layer "F.Cu") (net 9))
  (segment (start 138.25 130.1) (end 138.25 129.45) (width 0.3) (layer "F.Cu") (net 9))
  (segment (start 167.2 120.45) (end 167.2 119.85) (width 0.4) (layer "F.Cu") (net 9))
  (segment (start 147 105.935) (end 147 106.45) (width 0.4) (layer "F.Cu") (net 9))
  (segment (start 164.85 105.261) (end 164.85 105.2625) (width 0.1) (layer "F.Cu") (net 9))
  (segment (start 143.25 119.65) (end 144.45 119.65) (width 0.4) (layer "F.Cu") (net 9))
  (segment (start 138.25 129.45) (end 138 129.2) (width 0.3) (layer "F.Cu") (net 9))
  (segment (start 168.1 108.435) (end 169.15 108.435) (width 0.3) (layer "F.Cu") (net 9))
  (segment (start 170.95 119) (end 170.95 117.65) (width 0.4) (layer "F.Cu") (net 9))
  (segment (start 168.9 119.65) (end 169.1 119.85) (width 0.4) (layer "F.Cu") (net 9))
  (segment (start 167 120.65) (end 167.2 120.45) (width 0.4) (layer "F.Cu") (net 9))
  (segment (start 164.318374 104.729374) (end 164.85 105.261) (width 0.1) (layer "F.Cu") (net 9))
  (segment (start 138 129.2) (end 138 128.8) (width 0.3) (layer "F.Cu") (net 9))
  (segment (start 171.3 117.3) (end 171.3 116.65) (width 0.4) (layer "F.Cu") (net 9))
  (segment (start 166.842845 106.4005) (end 167.193345 106.05) (width 0.4) (layer "F.Cu") (net 9))
  (segment (start 173.2 117.3) (end 173.2 118) (width 0.4) (layer "F.Cu") (net 9))
  (segment (start 171.5 116.45) (end 173 116.45) (width 0.4) (layer "F.Cu") (net 9))
  (segment (start 143 119.9) (end 143.25 119.65) (width 0.4) (layer "F.Cu") (net 9))
  (segment (start 169.1 119.85) (end 169.1 120.45) (width 0.4) (layer "F.Cu") (net 9))
  (segment (start 146.75 117.7) (end 146.5 117.45) (width 0.4) (layer "F.Cu") (net 9))
  (segment (start 147 106.45) (end 146.8 106.65) (width 0.4) (layer "F.Cu") (net 9))
  (segment (start 148.615 105.935) (end 148.65 105.9) (width 0.4) (layer "F.Cu") (net 9))
  (segment (start 149.5 117.3) (end 149.85 116.95) (width 0.4) (layer "F.Cu") (net 9))
  (segment (start 149.2 116.7) (end 149.2 117.3) (width 0.4) (layer "F.Cu") (net 9))
  (segment (start 146.9 117.7) (end 147.3 117.3) (width 0.4) (layer "F.Cu") (net 9))
  (segment (start 148 105.935) (end 148.615 105.935) (width 0.4) (layer "F.Cu") (net 9))
  (segment (start 147.3 117.3) (end 147.3 116.75) (width 0.4) (layer "F.Cu") (net 9))
  (segment (start 140.6025 105.2125) (end 140.85 105.2125) (width 0.1) (layer "F.Cu") (net 9))
  (segment (start 170.95 119) (end 170.95 119.9) (width 0.4) (layer "F.Cu") (net 9))
  (segment (start 167.193345 106.05) (end 167.315 106.05) (width 0.4) (layer "F.Cu") (net 9))
  (segment (start 173.2 118) (end 173.45 118.25) (width 0.4) (layer "F.Cu") (net 9))
  (segment (start 123 106.4) (end 122.8 106.6) (width 0.4) (layer "F.Cu") (net 9))
  (segment (start 140.184265 104.794265) (end 140.6025 105.2125) (width 0.1) (layer "F.Cu") (net 9))
  (segment (start 123.8 106.085) (end 124 105.885) (width 0.4) (layer "F.Cu") (net 9))
  (segment (start 168.1 109.15) (end 168.1 108.435) (width 0.4) (layer "F.Cu") (net 9))
  (segment (start 143 120.45) (end 143 119.9) (width 0.4) (layer "F.Cu") (net 9))
  (via (at 146.5 117.45) (size 0.6) (drill 0.2) (layers "F.Cu" "B.Cu") (net 9))
  (via (at 149.85 116.95) (size 0.6) (drill 0.2) (layers "F.Cu" "B.Cu") (net 9))
  (via (at 146.8 106.65) (size 0.6) (drill 0.2) (layers "F.Cu" "B.Cu") (net 9))
  (via (at 152.9 109.78) (size 0.6) (drill 0.2) (layers "F.Cu" "B.Cu") (net 9))
  (via (at 129 109.7) (size 0.6) (drill 0.2) (layers "F.Cu" "B.Cu") (net 9))
  (via (at 144.9 121.55) (size 0.6) (drill 0.2) (layers "F.Cu" "B.Cu") (net 9))
  (via (at 138 128.8) (size 0.4) (drill 0.15) (layers "F.Cu" "B.Cu") (net 9))
  (via (at 170.9 119.95) (size 0.6) (drill 0.2) (layers "F.Cu" "B.Cu") (net 9))
  (via (at 170.45 117.7) (size 0.6) (drill 0.2) (layers "F.Cu" "B.Cu") (net 9))
  (via (at 167.1 121.6) (size 0.6) (drill 0.2) (layers "F.Cu" "B.Cu") (net 9))
  (via (at 160.75 101.4995) (size 0.4) (drill 0.15) (layers "F.Cu" "B.Cu") (net 9))
  (via (at 157.75 101.5) (size 0.4) (drill 0.15) (layers "F.Cu" "B.Cu") (net 9))
  (via (at 173.45 118.25) (size 0.6) (drill 0.2) (layers "F.Cu" "B.Cu") (net 9))
  (via (at 145.1 109.2) (size 0.6) (drill 0.2) (layers "F.Cu" "B.Cu") (net 9))
  (via (at 152.916839 111.983471) (size 0.6) (drill 0.2) (layers "F.Cu" "B.Cu") (net 9))
  (via (at 144.4 109.25) (size 0.6) (drill 0.2) (layers "F.Cu" "B.Cu") (net 9))
  (via (at 138 128.4) (size 0.4) (drill 0.15) (layers "F.Cu" "B.Cu") (net 9))
  (via (at 138 129.2) (size 0.4) (drill 0.15) (layers "F.Cu" "B.Cu") (net 9))
  (via (at 164.318374 104.610156) (size 0.6) (drill 0.2) (layers "F.Cu" "B.Cu") (net 9))
  (via (at 142.75 106.3) (size 0.6) (drill 0.2) (layers "F.Cu" "B.Cu") (net 9))
  (via (at 143 121.5) (size 0.6) (drill 0.2) (layers "F.Cu" "B.Cu") (net 9))
  (via (at 122.8 106.6) (size 0.6) (drill 0.2) (layers "F.Cu" "B.Cu") (net 9))
  (via (at 169.15 121.55) (size 0.6) (drill 0.2) (layers "F.Cu" "B.Cu") (net 9))
  (via (at 140.184265 104.794265) (size 0.6) (drill 0.2) (layers "F.Cu" "B.Cu") (net 9))
  (via (at 129.1 113.65) (size 0.6) (drill 0.2) (layers "F.Cu" "B.Cu") (net 9))
  (via (at 128.889002 111.849869) (size 0.6) (drill 0.2) (layers "F.Cu" "B.Cu") (net 9))
  (via (at 136.75 101.4495) (size 0.4) (drill 0.15) (layers "F.Cu" "B.Cu") (net 9))
  (via (at 124.75 105.85) (size 0.6) (drill 0.2) (layers "F.Cu" "B.Cu") (net 9))
  (via (at 168.1 109.15) (size 0.6) (drill 0.2) (layers "F.Cu" "B.Cu") (net 9))
  (via (at 169.15 109.15) (size 0.6) (drill 0.2) (layers "F.Cu" "B.Cu") (net 9))
  (via (at 133.75 101.45) (size 0.4) (drill 0.15) (layers "F.Cu" "B.Cu") (net 9))
  (via (at 166.842845 106.4005) (size 0.6) (drill 0.2) (layers "F.Cu" "B.Cu") (net 9))
  (via (at 153.4 114.4) (size 0.6) (drill 0.2) (layers "F.Cu" "B.Cu") (net 9))
  (via (at 148.65 105.9) (size 0.6) (drill 0.2) (layers "F.Cu" "B.Cu") (net 9))
  (segment (start 154.1 111.735) (end 154.615 112.25) (width 0.4) (layer "B.Cu") (net 9))
  (segment (start 130.107107 113.6) (end 130 113.6) (width 0.4) (layer "B.Cu") (net 9))
  (segment (start 154.1 110.95) (end 154.1 111.735) (width 0.4) (layer "B.Cu") (net 9))
  (segment (start 154.1 109.45) (end 153.7 109.85) (width 0.4) (layer "B.Cu") (net 9))
  (segment (start 154.1 110.25) (end 153.7 109.85) (width 0.4) (layer "B.Cu") (net 9))
  (segment (start 153.63 109.78) (end 153.7 109.85) (width 0.4) (layer "B.Cu") (net 9))
  (segment (start 154 113.8) (end 153.4 114.4) (width 0.4) (layer "B.Cu") (net 9))
  (segment (start 130.1 109.4) (end 129.7 109.8) (width 0.4) (layer "B.Cu") (net 9))
  (segment (start 129.7 109.8) (end 129.1 109.8) (width 0.4) (layer "B.Cu") (net 9))
  (segment (start 138 129.2) (end 138 128.4) (width 0.4) (layer "B.Cu") (net 9))
  (segment (start 152.9 109.78) (end 153.63 109.78) (width 0.4) (layer "B.Cu") (net 9))
  (segment (start 152.916839 111.983471) (end 153.016529 111.983471) (width 0.4) (layer "B.Cu") (net 9))
  (segment (start 130.615 113.092107) (end 130.107107 113.6) (width 0.4) (layer "B.Cu") (net 9))
  (segment (start 154.615 112.25) (end 154.615 113.142107) (width 0.4) (layer "B.Cu") (net 9))
  (segment (start 154.107107 113.65) (end 154 113.65) (width 0.4) (layer "B.Cu") (net 9))
  (segment (start 130 113.6) (end 129.15 113.6) (width 0.4) (layer "B.Cu") (net 9))
  (segment (start 153.016529 111.983471) (end 154.1 110.9) (width 0.4) (layer "B.Cu") (net 9))
  (segment (start 154.615 113.142107) (end 154.107107 113.65) (width 0.4) (layer "B.Cu") (net 9))
  (segment (start 129.838871 110.9) (end 130.1 110.9) (width 0.4) (layer "B.Cu") (net 9))
  (segment (start 130.1 111.685) (end 130.615 112.2) (width 0.4) (layer "B.Cu") (net 9))
  (segment (start 130.615 112.2) (end 130.615 113.092107) (width 0.4) (layer "B.Cu") (net 9))
  (segment (start 130.1 110.9) (end 130.1 111.685) (width 0.4) (layer "B.Cu") (net 9))
  (segment (start 130.1 110.2) (end 129.7 109.8) (width 0.4) (layer "B.Cu") (net 9))
  (segment (start 129.15 113.6) (end 129.1 113.65) (width 0.4) (layer "B.Cu") (net 9))
  (segment (start 130.1 110.9) (end 130.1 110.2) (width 0.4) (layer "B.Cu") (net 9))
  (segment (start 128.889002 111.849869) (end 129.838871 110.9) (width 0.4) (layer "B.Cu") (net 9))
  (segment (start 154.1 110.95) (end 154.1 110.25) (width 0.4) (layer "B.Cu") (net 9))
  (segment (start 129.1 109.8) (end 129 109.7) (width 0.4) (layer "B.Cu") (net 9))
  (segment (start 123 109.715) (end 124 109.715) (width 0.4) (layer "F.Cu") (net 10))
  (segment (start 125.107364 108.17) (end 125.462364 108.525) (width 0.4) (layer "F.Cu") (net 10))
  (segment (start 125.6907 108.753336) (end 127.8907 108.753336) (width 0.4) (layer "F.Cu") (net 10))
  (segment (start 124 109.715) (end 124 108.725) (width 0.4) (layer "F.Cu") (net 10))
  (segment (start 123.8 108.525) (end 124.155 108.17) (width 0.4) (layer "F.Cu") (net 10))
  (segment (start 124.155 108.17) (end 125.107364 108.17) (width 0.4) (layer "F.Cu") (net 10))
  (segment (start 147.3 113.7) (end 146.65 113.05) (width 0.4) (layer "F.Cu") (net 11))
  (segment (start 145.2 113.65) (end 142.6 113.65) (width 0.4) (layer "F.Cu") (net 11))
  (segment (start 147.3 114.6) (end 146.15 114.6) (width 0.4) (layer "F.Cu") (net 11))
  (segment (start 146.15 114.6) (end 145.2 113.65) (width 0.4) (layer "F.Cu") (net 11))
  (segment (start 147.3 114.6) (end 147.3 113.7) (width 0.4) (layer "F.Cu") (net 11))
  (segment (start 143.55 117.2) (end 143 117.75) (width 0.4) (layer "F.Cu") (net 12))
  (segment (start 144.45 116.4) (end 143.55 115.5) (width 0.4) (layer "F.Cu") (net 12))
  (segment (start 143.8 114.45) (end 143.8 115.25) (width 0.4) (layer "F.Cu") (net 12))
  (segment (start 145.2 116.4) (end 144.45 116.4) (width 0.4) (layer "F.Cu") (net 12))
  (segment (start 143.55 115.5) (end 143.55 117.2) (width 0.4) (layer "F.Cu") (net 12))
  (segment (start 142.6 108.65) (end 142.6 107.65) (width 0.4) (layer "F.Cu") (net 12))
  (segment (start 128.35 105.4) (end 127.2 105.4) (width 0.4) (layer "F.Cu") (net 12))
  (via (at 143.8 114.45) (size 0.6) (drill 0.2) (layers "F.Cu" "B.Cu") (net 12))
  (via (at 142.6 108.65) (size 0.6) (drill 0.2) (layers "F.Cu" "B.Cu") (net 12))
  (via (at 127.2 105.4) (size 0.6) (drill 0.2) (layers "F.Cu" "B.Cu") (net 12))
  (segment (start 129.545 111.26) (end 129.578336 111.293336) (width 0.1) (layer "F.Cu") (net 13))
  (segment (start 129.6 111.315) (end 130.43 111.315) (width 0.1) (layer "F.Cu") (net 13))
  (segment (start 127.8907 111.293336) (end 127.924036 111.26) (width 0.1) (layer "F.Cu") (net 13))
  (segment (start 127.924036 111.26) (end 129.545 111.26) (width 0.1) (layer "F.Cu") (net 13))
  (segment (start 163.73 103.09) (end 163.39 102.75) (width 0.4) (layer "F.Cu") (net 14))
  (segment (start 139.735 103.185) (end 139.28 103.64) (width 0.4) (layer "F.Cu") (net 14))
  (segment (start 164.85 102.4375) (end 164.2625 102.4375) (width 0.3) (layer "F.Cu") (net 14))
  (segment (start 164.08 103.09) (end 164.03 103.09) (width 0.4) (layer "F.Cu") (net 14))
  (segment (start 140.25 103.185) (end 140.25 102.4) (width 0.3) (layer "F.Cu") (net 14))
  (segment (start 164.25 102.92) (end 164.25 102.45) (width 0.3) (layer "F.Cu") (net 14))
  (segment (start 139.28 102.7) (end 139.28 102.69) (width 0.3) (layer "F.Cu") (net 14))
  (segment (start 140.25 103.185) (end 139.775 103.185) (width 0.4) (layer "F.Cu") (net 14))
  (segment (start 139.775 103.185) (end 139.28 102.69) (width 0.4) (layer "F.Cu") (net 14))
  (segment (start 136.75 129.45) (end 136.75 130.1) (width 0.3) (layer "F.Cu") (net 14))
  (segment (start 164.08 103.09) (end 164.25 102.92) (width 0.3) (layer "F.Cu") (net 14))
  (segment (start 137.25 129.45) (end 137 129.2) (width 0.3) (layer "F.Cu") (net 14))
  (segment (start 137 128.8) (end 137 128.4) (width 0.4) (layer "F.Cu") (net 14))
  (segment (start 137 129.2) (end 137 128.8) (width 0.4) (layer "F.Cu") (net 14))
  (segment (start 140.2625 102.3875) (end 140.25 102.4) (width 0.3) (layer "F.Cu") (net 14))
  (segment (start 164.2625 102.4375) (end 164.25 102.45) (width 0.3) (layer "F.Cu") (net 14))
  (segment (start 169.28 105.33) (end 168.925 105.33) (width 0.3) (layer "F.Cu") (net 14))
  (segment (start 144.355 104.59) (end 144.355 104.845) (width 0.4) (layer "F.Cu") (net 14))
  (segment (start 139.28 103.64) (end 139.28 102.7) (width 0.5) (layer "F.Cu") (net 14))
  (segment (start 140.85 102.3875) (end 140.2625 102.3875) (width 0.3) (layer "F.Cu") (net 14))
  (segment (start 163.39 103.73) (end 163.39 102.75) (width 0.5) (layer "F.Cu") (net 14))
  (segment (start 164.03 103.09) (end 163.39 103.73) (width 0.4) (layer "F.Cu") (net 14))
  (segment (start 144.355 104.845) (end 143.8 105.4) (width 0.4) (layer "F.Cu") (net 14))
  (segment (start 168.925 105.33) (end 168.405 104.81) (width 0.3) (layer "F.Cu") (net 14))
  (segment (start 140.25 103.185) (end 139.735 103.185) (width 0.4) (layer "F.Cu") (net 14))
  (segment (start 137 129.2) (end 136.75 129.45) (width 0.3) (layer "F.Cu") (net 14))
  (segment (start 164.08 103.09) (end 163.73 103.09) (width 0.4) (layer "F.Cu") (net 14))
  (segment (start 137.25 130.1) (end 137.25 129.45) (width 0.3) (layer "F.Cu") (net 14))
  (via (at 137 128.4) (size 0.4) (drill 0.15) (layers "F.Cu" "B.Cu") (net 14))
  (via (at 137 129.2) (size 0.4) (drill 0.15) (layers "F.Cu" "B.Cu") (net 14))
  (via (at 164.08 103.09) (size 0.6) (drill 0.2) (layers "F.Cu" "B.Cu") (net 14))
  (via (at 164.25 102.45) (size 0.6) (drill 0.2) (layers "F.Cu" "B.Cu") (net 14))
  (via (at 137 128.8) (size 0.4) (drill 0.15) (layers "F.Cu" "B.Cu") (net 14))
  (via (at 140.25 102.4) (size 0.6) (drill 0.2) (layers "F.Cu" "B.Cu") (net 14))
  (via (at 169.28 105.33) (size 0.6) (drill 0.2) (layers "F.Cu" "B.Cu") (net 14))
  (via (at 140.25 103.185) (size 0.6) (drill 0.2) (layers "F.Cu" "B.Cu") (net 14))
  (via (at 143.8 105.4) (size 0.6) (drill 0.2) (layers "F.Cu" "B.Cu") (net 14))
  (segment (start 131.485 111.4) (end 131.485 112.4) (width 0.1) (layer "F.Cu") (net 15))
  (segment (start 132.375 110.725) (end 131.7 111.4) (width 0.1) (layer "F.Cu") (net 15))
  (segment (start 133.15 110.725) (end 132.375 110.725) (width 0.1) (layer "F.Cu") (net 15))
  (segment (start 161.375 109.8) (end 161.7 110.125) (width 0.3) (layer "F.Cu") (net 16))
  (segment (start 161.375 109.785528) (end 161.375 109.8) (width 0.3) (layer "F.Cu") (net 16))
  (via (at 161.375 109.785528) (size 0.4) (drill 0.15) (layers "F.Cu" "B.Cu") (net 16))
  (segment (start 161.375 109.785528) (end 161.375 109.213603) (width 0.3) (layer "B.Cu") (net 16))
  (segment (start 162.8 107.95) (end 163 108.15) (width 0.3) (layer "B.Cu") (net 16))
  (segment (start 161.375 109.213603) (end 161.856801 108.731802) (width 0.3) (layer "B.Cu") (net 16))
  (segment (start 161.856801 108.506802) (end 162.413603 107.95) (width 0.3) (layer "B.Cu") (net 16))
  (segment (start 161.856801 108.731802) (end 161.856801 108.506802) (width 0.3) (layer "B.Cu") (net 16))
  (segment (start 162.413603 107.95) (end 162.8 107.95) (width 0.3) (layer "B.Cu") (net 16))
  (segment (start 163 108.15) (end 163.315 108.15) (width 0.3) (layer "B.Cu") (net 16))
  (segment (start 162.7 109.15) (end 162.7 109.775) (width 0.3) (layer "F.Cu") (net 17))
  (segment (start 162.7 109.775) (end 161.7 110.775) (width 0.3) (layer "F.Cu") (net 17))
  (via (at 162.7 109.15) (size 0.4) (drill 0.15) (layers "F.Cu" "B.Cu") (net 17))
  (segment (start 162.7 109.15) (end 163.315 109.15) (width 0.3) (layer "B.Cu") (net 17))
  (segment (start 161.371674 111.089016) (end 161.371674 111.103326) (width 0.3) (layer "F.Cu") (net 18))
  (segment (start 161.371674 111.103326) (end 161.05 111.425) (width 0.3) (layer "F.Cu") (net 18))
  (via (at 161.371674 111.089016) (size 0.4) (drill 0.15) (layers "F.Cu" "B.Cu") (net 18))
  (segment (start 161.371674 111.089016) (end 161.460984 111.089016) (width 0.4) (layer "B.Cu") (net 18))
  (segment (start 162.4 110.15) (end 163.315 110.15) (width 0.4) (layer "B.Cu") (net 18))
  (segment (start 161.460984 111.089016) (end 162.4 110.15) (width 0.4) (layer "B.Cu") (net 18))
  (segment (start 138.815 113.915) (end 138.4 113.5) (width 0.3) (layer "F.Cu") (net 19))
  (segment (start 139.8 115.4) (end 139.3 115.4) (width 0.4) (layer "F.Cu") (net 19))
  (segment (start 139.3 115.4) (end 138.815 114.915) (width 0.4) (layer "F.Cu") (net 19))
  (segment (start 138.815 114.915) (end 138.815 114.3) (width 0.4) (layer "F.Cu") (net 19))
  (segment (start 138.815 114.3) (end 138.815 113.915) (width 0.3) (layer "F.Cu") (net 19))
  (segment (start 134.45 110.725) (end 134.125 111.05) (width 0.1) (layer "F.Cu") (net 19))
  (segment (start 136.4 109.425) (end 136.075 109.75) (width 0.1) (layer "F.Cu") (net 19))
  (via (at 136.075 109.75) (size 0.4) (drill 0.15) (layers "F.Cu" "B.Cu") (net 19))
  (via (at 134.125 111.05) (size 0.4) (drill 0.15) (layers "F.Cu" "B.Cu") (net 19))
  (via (at 138.4 113.5) (size 0.4) (drill 0.15) (layers "F.Cu" "B.Cu") (net 19))
  (segment (start 136.7 111.2) (end 137.2 111.7) (width 0.4) (layer "In2.Cu") (net 19))
  (segment (start 139.1 111.5) (end 139.1 112.8) (width 0.4) (layer "In2.Cu") (net 19))
  (segment (start 137.2 111.7) (end 137.992893 111.7) (width 0.4) (layer "In2.Cu") (net 19))
  (segment (start 136.25 109.75) (end 136.7 110.2) (width 0.4) (layer "In2.Cu") (net 19))
  (segment (start 133.625 111.492893) (end 133.625 113.125) (width 0.4) (layer "In2.Cu") (net 19))
  (segment (start 134 113.5) (end 138.4 113.5) (width 0.4) (layer "In2.Cu") (net 19))
  (segment (start 138.9 111.3) (end 139.1 111.5) (width 0.4) (layer "In2.Cu") (net 19))
  (segment (start 133.625 113.125) (end 134 113.5) (width 0.4) (layer "In2.Cu") (net 19))
  (segment (start 136.7 110.2) (end 136.7 111.2) (width 0.4) (layer "In2.Cu") (net 19))
  (segment (start 136.075 109.75) (end 136.25 109.75) (width 0.4) (layer "In2.Cu") (net 19))
  (segment (start 139.1 112.8) (end 138.4 113.5) (width 0.4) (layer "In2.Cu") (net 19))
  (segment (start 137.992893 111.7) (end 138.392893 111.3) (width 0.4) (layer "In2.Cu") (net 19))
  (segment (start 134.067893 111.05) (end 133.625 111.492893) (width 0.4) (layer "In2.Cu") (net 19))
  (segment (start 134.125 111.05) (end 134.067893 111.05) (width 0.4) (layer "In2.Cu") (net 19))
  (segment (start 138.392893 111.3) (end 138.9 111.3) (width 0.4) (layer "In2.Cu") (net 19))
  (segment (start 131.485 110.4) (end 132.2 110.4) (width 0.4) (layer "F.Cu") (net 20))
  (segment (start 134.45 110.075) (end 134.15 110.375) (width 0.1) (layer "F.Cu") (net 20))
  (via (at 132.2 110.4) (size 0.4) (drill 0.15) (layers "F.Cu" "B.Cu") (net 20))
  (via (at 134.15 110.375) (size 0.4) (drill 0.15) (layers "F.Cu" "B.Cu") (net 20))
  (segment (start 132.225 110.375) (end 132.2 110.4) (width 0.4) (layer "In2.Cu") (net 20))
  (segment (start 134.15 110.375) (end 132.225 110.375) (width 0.4) (layer "In2.Cu") (net 20))
  (segment (start 131.5 110.9) (end 131.7 110.9) (width 0.4) (layer "B.Cu") (net 20))
  (segment (start 131.7 110.9) (end 132.2 110.4) (width 0.4) (layer "B.Cu") (net 20))
  (segment (start 132.937868 112.025) (end 132.2 112.762868) (width 0.4) (layer "F.Cu") (net 21))
  (segment (start 131.8 113.4) (end 131.485 113.4) (width 0.4) (layer "F.Cu") (net 21))
  (segment (start 132.05 113.15) (end 131.8 113.4) (width 0.4) (layer "F.Cu") (net 21))
  (segment (start 133.15 112.025) (end 132.937868 112.025) (width 0.4) (layer "F.Cu") (net 21))
  (segment (start 132.2 112.762868) (end 132.2 113) (width 0.4) (layer "F.Cu") (net 21))
  (segment (start 132.2 113) (end 132.05 113.15) (width 0.4) (layer "F.Cu") (net 21))
  (via (at 132.05 113.15) (size 0.4) (drill 0.15) (layers "F.Cu" "B.Cu") (net 21))
  (segment (start 131.4 113.6) (end 131.6 113.6) (width 0.4) (layer "B.Cu") (net 21))
  (segment (start 131.6 113.6) (end 132.05 113.15) (width 0.4) (layer "B.Cu") (net 21))
  (segment (start 162.815 114.965) (end 162.815 114.35) (width 0.4) (layer "F.Cu") (net 22))
  (segment (start 162.815 114.35) (end 162.815 113.965) (width 0.3) (layer "F.Cu") (net 22))
  (segment (start 162.815 113.965) (end 162.4 113.55) (width 0.3) (layer "F.Cu") (net 22))
  (segment (start 160.4 109.475) (end 160.075 109.8) (width 0.1) (layer "F.Cu") (net 22))
  (segment (start 163.3 115.45) (end 162.815 114.965) (width 0.4) (layer "F.Cu") (net 22))
  (segment (start 163.8 115.45) (end 163.3 115.45) (width 0.4) (layer "F.Cu") (net 22))
  (segment (start 158.45 110.775) (end 158.125 111.1) (width 0.1) (layer "F.Cu") (net 22))
  (via (at 162.4 113.55) (size 0.4) (drill 0.15) (layers "F.Cu" "B.Cu") (net 22))
  (via (at 158.125 111.1) (size 0.4) (drill 0.15) (layers "F.Cu" "B.Cu") (net 22))
  (via (at 160.075 109.8) (size 0.4) (drill 0.15) (layers "F.Cu" "B.Cu") (net 22))
  (segment (start 161.992893 111.75) (end 162.392893 111.35) (width 0.4) (layer "In2.Cu") (net 22))
  (segment (start 162.392893 111.35) (end 162.9 111.35) (width 0.4) (layer "In2.Cu") (net 22))
  (segment (start 160.25 109.8) (end 160.7 110.25) (width 0.4) (layer "In2.Cu") (net 22))
  (segment (start 158 113.55) (end 162.4 113.55) (width 0.4) (layer "In2.Cu") (net 22))
  (segment (start 163.1 111.55) (end 163.1 112.85) (width 0.4) (layer "In2.Cu") (net 22))
  (segment (start 158.125 111.1) (end 158.067893 111.1) (width 0.4) (layer "In2.Cu") (net 22))
  (segment (start 157.625 113.175) (end 158 113.55) (width 0.4) (layer "In2.Cu") (net 22))
  (segment (start 160.075 109.8) (end 160.25 109.8) (width 0.4) (layer "In2.Cu") (net 22))
  (segment (start 161.2 111.75) (end 161.992893 111.75) (width 0.4) (layer "In2.Cu") (net 22))
  (segment (start 163.1 112.85) (end 162.4 113.55) (width 0.4) (layer "In2.Cu") (net 22))
  (segment (start 157.625 111.542893) (end 157.625 113.175) (width 0.4) (layer "In2.Cu") (net 22))
  (segment (start 158.067893 111.1) (end 157.625 111.542893) (width 0.4) (layer "In2.Cu") (net 22))
  (segment (start 160.7 111.25) (end 161.2 111.75) (width 0.4) (layer "In2.Cu") (net 22))
  (segment (start 160.7 110.25) (end 160.7 111.25) (width 0.4) (layer "In2.Cu") (net 22))
  (segment (start 162.9 111.35) (end 163.1 111.55) (width 0.4) (layer "In2.Cu") (net 22))
  (segment (start 155.485 110.45) (end 156.2 110.45) (width 0.4) (layer "F.Cu") (net 23))
  (segment (start 158.45 110.125) (end 158.15 110.425) (width 0.1) (layer "F.Cu") (net 23))
  (via (at 156.2 110.45) (size 0.4) (drill 0.15) (layers "F.Cu" "B.Cu") (net 23))
  (via (at 158.15 110.425) (size 0.4) (drill 0.15) (layers "F.Cu" "B.Cu") (net 23))
  (segment (start 158.15 110.425) (end 156.225 110.425) (width 0.4) (layer "In2.Cu") (net 23))
  (segment (start 156.225 110.425) (end 156.2 110.45) (width 0.4) (layer "In2.Cu") (net 23))
  (segment (start 155.7 110.95) (end 156.2 110.45) (width 0.4) (layer "B.Cu") (net 23))
  (segment (start 155.5 110.95) (end 155.7 110.95) (width 0.4) (layer "B.Cu") (net 23))
  (segment (start 170.425 114.6) (end 171.3 114.6) (width 0.4) (layer "F.Cu") (net 24))
  (segment (start 170.95 113.05) (end 170.95 114.25) (width 0.4) (layer "F.Cu") (net 24))
  (segment (start 170.95 114.25) (end 171.3 114.6) (width 0.4) (layer "F.Cu") (net 24))
  (segment (start 169.525 113.7) (end 170.425 114.6) (width 0.4) (layer "F.Cu") (net 24))
  (segment (start 166.6 113.7) (end 169.525 113.7) (width 0.4) (layer "F.Cu") (net 24))
  (segment (start 169.2 116.4) (end 168.4 116.4) (width 0.4) (layer "F.Cu") (net 25))
  (segment (start 168.4 116.4) (end 167.55 115.55) (width 0.4) (layer "F.Cu") (net 25))
  (segment (start 166.6 108.75) (end 166.6 107.7) (width 0.4) (layer "F.Cu") (net 25))
  (segment (start 167.55 115.55) (end 167.55 117.4) (width 0.4) (layer "F.Cu") (net 25))
  (segment (start 167.55 117.4) (end 167.2 117.75) (width 0.4) (layer "F.Cu") (net 25))
  (segment (start 152.35 105.45) (end 151.2 105.45) (width 0.4) (layer "F.Cu") (net 25))
  (segment (start 167.9 114.55) (end 167.9 115.2) (width 0.4) (layer "F.Cu") (net 25))
  (via (at 166.6 108.75) (size 0.6) (drill 0.2) (layers "F.Cu" "B.Cu") (net 25))
  (via (at 167.9 114.55) (size 0.6) (drill 0.2) (layers "F.Cu" "B.Cu") (net 25))
  (via (at 151.2 105.45) (size 0.6) (drill 0.2) (layers "F.Cu" "B.Cu") (net 25))
  (segment (start 155.8 113.45) (end 155.485 113.45) (width 0.4) (layer "F.Cu") (net 26))
  (segment (start 157.15 112.075) (end 156.937868 112.075) (width 0.4) (layer "F.Cu") (net 26))
  (segment (start 156.937868 112.075) (end 156.2 112.812868) (width 0.4) (layer "F.Cu") (net 26))
  (segment (start 156.2 112.812868) (end 156.2 113.05) (width 0.4) (layer "F.Cu") (net 26))
  (segment (start 156.2 113.05) (end 156.05 113.2) (width 0.4) (layer "F.Cu") (net 26))
  (segment (start 156.05 113.2) (end 155.8 113.45) (width 0.4) (layer "F.Cu") (net 26))
  (via (at 156.05 113.2) (size 0.4) (drill 0.15) (layers "F.Cu" "B.Cu") (net 26))
  (segment (start 155.6 113.65) (end 156.05 113.2) (width 0.4) (layer "B.Cu") (net 26))
  (segment (start 155.4 113.65) (end 155.6 113.65) (width 0.4) (layer "B.Cu") (net 26))
  (segment (start 155.485 111.45) (end 155.485 112.45) (width 0.1) (layer "F.Cu") (net 27))
  (segment (start 157.15 110.775) (end 156.375 110.775) (width 0.1) (layer "F.Cu") (net 27))
  (segment (start 156.375 110.775) (end 155.7 111.45) (width 0.1) (layer "F.Cu") (net 27))
  (segment (start 146.2 99.1) (end 144.749996 99.1) (width 0.4) (layer "F.Cu") (net 28))
  (segment (start 144.249999 98.600003) (end 144.249999 92.640002) (width 0.4) (layer "B.Cu") (net 28))
  (segment (start 144.249999 92.640002) (end 129.75 92.640002) (width 0.4) (layer "B.Cu") (net 28))
  (segment (start 129.75 98.600003) (end 129.75 92.640002) (width 0.4) (layer "B.Cu") (net 28))
  (segment (start 170.2 99.15) (end 168.749996 99.15) (width 0.4) (layer "F.Cu") (net 29))
  (segment (start 153.75 92.665002) (end 168.249999 92.665002) (width 0.4) (layer "B.Cu") (net 29))
  (segment (start 168.249999 92.665002) (end 168.249999 98.625003) (width 0.4) (layer "B.Cu") (net 29))
  (segment (start 153.75 98.625003) (end 153.75 92.665002) (width 0.4) (layer "B.Cu") (net 29))
  (segment (start 147.8 108.575) (end 148.205 108.17) (width 0.4) (layer "F.Cu") (net 30))
  (segment (start 149.057364 108.17) (end 149.462364 108.575) (width 0.4) (layer "F.Cu") (net 30))
  (segment (start 147 109.765) (end 148 109.765) (width 0.4) (layer "F.Cu") (net 30))
  (segment (start 148 109.765) (end 148 108.775) (width 0.4) (layer "F.Cu") (net 30))
  (segment (start 148.205 108.17) (end 149.057364 108.17) (width 0.4) (layer "F.Cu") (net 30))
  (segment (start 149.6907 108.803336) (end 151.8907 108.803336) (width 0.4) (layer "F.Cu") (net 30))
  (segment (start 151.8907 111.89) (end 152.4057 111.375) (width 0.1) (layer "F.Cu") (net 31))
  (segment (start 153.6 111.365) (end 154.43 111.365) (width 0.1) (layer "F.Cu") (net 31))
  (segment (start 152.4057 111.375) (end 153.6 111.375) (width 0.1) (layer "F.Cu") (net 31))
  (segment (start 153.6 111.375) (end 153.6 111.365) (width 0.1) (layer "F.Cu") (net 31))
  (segment (start 153.6 111.365) (end 153.578336 111.343336) (width 0.1) (layer "F.Cu") (net 31))
  (segment (start 161.05 110.775) (end 161.375 110.45) (width 0.3) (layer "F.Cu") (net 32))
  (segment (start 164.16 110.28) (end 165.18 110.28) (width 0.3) (layer "F.Cu") (net 32))
  (segment (start 162.6 110.85) (end 163.41 110.85) (width 0.4) (layer "F.Cu") (net 32))
  (segment (start 163.41 110.85) (end 163.5 110.76) (width 0.4) (layer "F.Cu") (net 32))
  (segment (start 165.18 110.28) (end 166.35 111.45) (width 0.3) (layer "F.Cu") (net 32))
  (segment (start 163.5 110.76) (end 163.5 109.65) (width 0.4) (layer "F.Cu") (net 32))
  (segment (start 163.41 109.53) (end 164.16 110.28) (width 0.3) (layer "F.Cu") (net 32))
  (via (at 162.6 110.85) (size 0.4) (drill 0.15) (layers "F.Cu" "B.Cu") (net 32))
  (via (at 161.375 110.45) (size 0.4) (drill 0.15) (layers "F.Cu" "B.Cu") (net 32))
  (segment (start 162.2 110.45) (end 161.375 110.45) (width 0.4) (layer "In2.Cu") (net 32))
  (segment (start 162.6 110.85) (end 162.2 110.45) (width 0.4) (layer "In2.Cu") (net 32))
  (segment (start 155.3 106.3) (end 154.45 105.45) (width 0.4) (layer "F.Cu") (net 33))
  (segment (start 163.8 117.55) (end 163.8 116.85) (width 0.4) (layer "F.Cu") (net 33))
  (segment (start 155.3 107.25) (end 155.3 106.3) (width 0.4) (layer "F.Cu") (net 33))
  (segment (start 157.786397 108.825) (end 157.505698 108.544301) (width 0.4) (layer "F.Cu") (net 33))
  (segment (start 155.3 107.25) (end 155.3 108.265) (width 0.4) (layer "F.Cu") (net 33))
  (segment (start 155.485 108.45) (end 156 108.45) (width 0.4) (layer "F.Cu") (net 33))
  (segment (start 155.3 108.265) (end 155.485 108.45) (width 0.4) (layer "F.Cu") (net 33))
  (segment (start 157.8 108.825) (end 157.786397 108.825) (width 0.4) (layer "F.Cu") (net 33))
  (via (at 156 108.45) (size 0.4) (drill 0.15) (layers "F.Cu" "B.Cu") (net 33))
  (via (at 163.8 117.55) (size 0.6) (drill 0.2) (layers "F.Cu" "B.Cu") (net 33))
  (via (at 157.505698 108.544301) (size 0.4) (drill 0.15) (layers "F.Cu" "B.Cu") (net 33))
  (segment (start 162.15 119.2) (end 163.8 117.55) (width 0.4) (layer "In2.Cu") (net 33))
  (segment (start 156 108.45) (end 155.3 109.15) (width 0.4) (layer "In2.Cu") (net 33))
  (segment (start 155.3 119.2) (end 162.15 119.2) (width 0.4) (layer "In2.Cu") (net 33))
  (segment (start 156.094301 108.544301) (end 156 108.45) (width 0.4) (layer "In2.Cu") (net 33))
  (segment (start 155.3 109.15) (end 155.3 119.2) (width 0.4) (layer "In2.Cu") (net 33))
  (segment (start 157.505698 108.544301) (end 156.094301 108.544301) (width 0.4) (layer "In2.Cu") (net 33))
  (segment (start 161.89 112.265) (end 161.89 112.46) (width 0.1) (layer "F.Cu") (net 34))
  (segment (start 160.725 123.575) (end 160.9 123.575) (width 0.1) (layer "F.Cu") (net 34))
  (segment (start 161.175 121.175) (end 161.275 121.175) (width 0.1) (layer "F.Cu") (net 34))
  (segment (start 160.9 122.375) (end 161.275 122.375) (width 0.1) (layer "F.Cu") (net 34))
  (segment (start 161.1 123.175) (end 160.725 123.175) (width 0.1) (layer "F.Cu") (net 34))
  (segment (start 161.1 127.50045) (end 161.1 129.049999) (width 0.1) (layer "F.Cu") (net 34))
  (segment (start 161.9 119.341422) (end 161.1 120.141422) (width 0.1) (layer "F.Cu") (net 34))
  (segment (start 161.1 125.05) (end 161.1 127.50045) (width 0.1) (layer "F.Cu") (net 34))
  (segment (start 160.65 122.05) (end 160.65 122.3) (width 0.1) (layer "F.Cu") (net 34))
  (segment (start 161.275 124.375) (end 161.1 124.375) (width 0.1) (layer "F.Cu") (net 34))
  (segment (start 160.65 124.45) (end 160.65 124.7) (width 0.1) (layer "F.Cu") (net 34))
  (segment (start 161.7 112.075) (end 161.89 112.265) (width 0.1) (layer "F.Cu") (net 34))
  (segment (start 161.175 121.975) (end 160.725 121.975) (width 0.1) (layer "F.Cu") (net 34))
  (segment (start 161.275 121.975) (end 161.175 121.975) (width 0.1) (layer "F.Cu") (net 34))
  (segment (start 160.9 123.575) (end 161.275 123.575) (width 0.1) (layer "F.Cu") (net 34))
  (segment (start 161.89 112.46) (end 162.01 112.58) (width 0.1) (layer "F.Cu") (net 34))
  (segment (start 161.1 129.049999) (end 161.25 129.199999) (width 0.1) (layer "F.Cu") (net 34))
  (segment (start 161.1 120.141422) (end 161.1 121.1) (width 0.1) (layer "F.Cu") (net 34))
  (segment (start 160.725 124.775) (end 160.825 124.775) (width 0.1) (layer "F.Cu") (net 34))
  (segment (start 161.55 123.85) (end 161.55 124.1) (width 0.1) (layer "F.Cu") (net 34))
  (segment (start 161.1 124.375) (end 160.725 124.375) (width 0.1) (layer "F.Cu") (net 34))
  (segment (start 161.55 121.45) (end 161.55 121.7) (width 0.1) (layer "F.Cu") (net 34))
  (segment (start 161.55 122.65) (end 161.55 122.9) (width 0.1) (layer "F.Cu") (net 34))
  (segment (start 160.725 122.375) (end 160.9 122.375) (width 0.1) (layer "F.Cu") (net 34))
  (segment (start 161.25 129.199999) (end 161.25 130.1) (width 0.1) (layer "F.Cu") (net 34))
  (segment (start 162.01 112.58) (end 162.01 112.839265) (width 0.1) (layer "F.Cu") (net 34))
  (segment locked (start 161.9 112.949265) (end 161.9 119.341422) (width 0.1) (layer "F.Cu") (net 34))
  (segment (start 162.01 112.839265) (end 161.9 112.949265) (width 0.1) (layer "F.Cu") (net 34))
  (segment (start 161.275 123.175) (end 161.1 123.175) (width 0.1) (layer "F.Cu") (net 34))
  (segment (start 160.65 123.25) (end 160.65 123.5) (width 0.1) (layer "F.Cu") (net 34))
  (arc (start 160.725 121.975) (mid 160.671967 121.996967) (end 160.65 122.05) (width 0.1) (layer "F.Cu") (net 34))
  (arc (start 161.275 121.175) (mid 161.469454 121.255546) (end 161.55 121.45) (width 0.1) (layer "F.Cu") (net 34))
  (arc (start 160.725 123.175) (mid 160.671967 123.196967) (end 160.65 123.25) (width 0.1) (layer "F.Cu") (net 34))
  (arc (start 160.65 124.7) (mid 160.671967 124.753033) (end 160.725 124.775) (width 0.1) (layer "F.Cu") (net 34))
  (arc (start 161.1 121.1) (mid 161.121967 121.153033) (end 161.175 121.175) (width 0.1) (layer "F.Cu") (net 34))
  (arc (start 160.725 124.375) (mid 160.671967 124.396967) (end 160.65 124.45) (width 0.1) (layer "F.Cu") (net 34))
  (arc (start 160.825 124.775) (mid 161.019454 124.855546) (end 161.1 125.05) (width 0.1) (layer "F.Cu") (net 34))
  (arc (start 161.275 123.575) (mid 161.469454 123.655546) (end 161.55 123.85) (width 0.1) (layer "F.Cu") (net 34))
  (arc (start 161.55 121.7) (mid 161.469454 121.894454) (end 161.275 121.975) (width 0.1) (layer "F.Cu") (net 34))
  (arc (start 160.65 122.3) (mid 160.671967 122.353033) (end 160.725 122.375) (width 0.1) (layer "F.Cu") (net 34))
  (arc (start 161.55 122.9) (mid 161.469454 123.094454) (end 161.275 123.175) (width 0.1) (layer "F.Cu") (net 34))
  (arc (start 160.65 123.5) (mid 160.671967 123.553033) (end 160.725 123.575) (width 0.1) (layer "F.Cu") (net 34))
  (arc (start 161.55 124.1) (mid 161.469454 124.294454) (end 161.275 124.375) (width 0.1) (layer "F.Cu") (net 34))
  (arc (start 161.275 122.375) (mid 161.469454 122.455546) (end 161.55 122.65) (width 0.1) (layer "F.Cu") (net 34))
  (segment (start 160.45 122.05) (end 160.45 122.3) (width 0.1) (layer "F.Cu") (net 35))
  (segment (start 161.512197 113.437802) (end 161.512197 113.5) (width 0.1) (layer "F.Cu") (net 35))
  (segment (start 160.725 124.975) (end 160.825 124.975) (width 0.1) (layer "F.Cu") (net 35))
  (segment (start 160.45 123.25) (end 160.45 123.5) (width 0.1) (layer "F.Cu") (net 35))
  (segment (start 161.1 124.175) (end 160.725 124.175) (width 0.1) (layer "F.Cu") (net 35))
  (segment (start 161.1 122.975) (end 160.725 122.975) (width 0.1) (layer "F.Cu") (net 35))
  (segment (start 161.606098 114.593901) (end 161.606099 114.593901) (width 0.1) (layer "F.Cu") (net 35))
  (segment (start 160.9 125.05) (end 160.9 127.50045) (width 0.1) (layer "F.Cu") (net 35))
  (segment (start 161.7 114.187802) (end 161.7 114.25) (width 0.1) (layer "F.Cu") (net 35))
  (segment (start 161.175 121.775) (end 160.725 121.775) (width 0.1) (layer "F.Cu") (net 35))
  (segment (start 161.7 114.687802) (end 161.7 114.75) (width 0.1) (layer "F.Cu") (net 35))
  (segment (start 161.7 112.725) (end 161.7 113.25) (width 0.1) (layer "F.Cu") (net 35))
  (segment (start 160.725 123.775) (end 160.9 123.775) (width 0.1) (layer "F.Cu") (net 35))
  (segment (start 160.9 122.575) (end 161.275 122.575) (width 0.1) (layer "F.Cu") (net 35))
  (segment (start 161.606098 115.093901) (end 161.606099 115.093901) (width 0.1) (layer "F.Cu") (net 35))
  (segment (start 161.275 124.175) (end 161.1 124.175) (width 0.1) (layer "F.Cu") (net 35))
  (segment (start 161.606099 114.843901) (end 161.606098 114.843901) (width 0.1) (layer "F.Cu") (net 35))
  (segment (start 161.606099 113.843901) (end 161.606098 113.843901) (width 0.1) (layer "F.Cu") (net 35))
  (segment (start 161.7 115.25) (end 161.7 119.258578) (width 0.1) (layer "F.Cu") (net 35))
  (segment (start 160.9 120.058578) (end 160.9 121.1) (width 0.1) (layer "F.Cu") (net 35))
  (segment (start 161.512197 114.437802) (end 161.512197 114.5) (width 0.1) (layer "F.Cu") (net 35))
  (segment (start 161.606099 114.343901) (end 161.606098 114.343901) (width 0.1) (layer "F.Cu") (net 35))
  (segment (start 160.9 127.50045) (end 160.9 129.049999) (width 0.1) (layer "F.Cu") (net 35))
  (segment (start 161.7 113.687802) (end 161.7 113.75) (width 0.1) (layer "F.Cu") (net 35))
  (segment (start 161.606098 114.093901) (end 161.606099 114.093901) (width 0.1) (layer "F.Cu") (net 35))
  (segment (start 161.275 121.775) (end 161.175 121.775) (width 0.1) (layer "F.Cu") (net 35))
  (segment (start 160.9 123.775) (end 161.275 123.775) (width 0.1) (layer "F.Cu") (net 35))
  (segment (start 160.75 129.199999) (end 160.75 130.1) (width 0.1) (layer "F.Cu") (net 35))
  (segment (start 161.35 122.65) (end 161.35 122.9) (width 0.1) (layer "F.Cu") (net 35))
  (segment (start 161.275 122.975) (end 161.1 122.975) (width 0.1) (layer "F.Cu") (net 35))
  (segment (start 161.35 123.85) (end 161.35 124.1) (width 0.1) (layer "F.Cu") (net 35))
  (segment (start 161.606098 113.593901) (end 161.606099 113.593901) (width 0.1) (layer "F.Cu") (net 35))
  (segment (start 160.9 129.049999) (end 160.75 129.199999) (width 0.1) (layer "F.Cu") (net 35))
  (segment (start 161.7 119.258578) (end 160.9 120.058578) (width 0.1) (layer "F.Cu") (net 35))
  (segment (start 161.7 115.187802) (end 161.7 115.25) (width 0.1) (layer "F.Cu") (net 35))
  (segment (start 161.512197 114.937802) (end 161.512197 115) (width 0.1) (layer "F.Cu") (net 35))
  (segment (start 160.45 124.45) (end 160.45 124.7) (width 0.1) (layer "F.Cu") (net 35))
  (segment (start 161.512197 113.937802) (end 161.512197 114) (width 0.1) (layer "F.Cu") (net 35))
  (segment (start 161.175 121.375) (end 161.275 121.375) (width 0.1) (layer "F.Cu") (net 35))
  (segment (start 161.35 121.45) (end 161.35 121.7) (width 0.1) (layer "F.Cu") (net 35))
  (segment (start 160.725 122.575) (end 160.9 122.575) (width 0.1) (layer "F.Cu") (net 35))
  (segment (start 161.606099 113.343901) (end 161.606098 113.343901) (width 0.1) (layer "F.Cu") (net 35))
  (arc (start 161.512197 114.5) (mid 161.5397 114.566398) (end 161.606098 114.593901) (width 0.1) (layer "F.Cu") (net 35))
  (arc (start 161.606098 114.343901) (mid 161.5397 114.371404) (end 161.512197 114.437802) (width 0.1) (layer "F.Cu") (net 35))
  (arc (start 161.606099 113.593901) (mid 161.672497 113.621404) (end 161.7 113.687802) (width 0.1) (layer "F.Cu") (net 35))
  (arc (start 160.45 123.5) (mid 160.530546 123.694454) (end 160.725 123.775) (width 0.1) (layer "F.Cu") (net 35))
  (arc (start 161.7 114.25) (mid 161.672497 114.316398) (end 161.606099 114.343901) (width 0.1) (layer "F.Cu") (net 35))
  (arc (start 160.45 122.3) (mid 160.530546 122.494454) (end 160.725 122.575) (width 0.1) (layer "F.Cu") (net 35))
  (arc (start 161.606098 113.843901) (mid 161.5397 113.871404) (end 161.512197 113.937802) (width 0.1) (layer "F.Cu") (net 35))
  (arc (start 161.275 121.375) (mid 161.328033 121.396967) (end 161.35 121.45) (width 0.1) (layer "F.Cu") (net 35))
  (arc (start 161.275 122.575) (mid 161.328033 122.596967) (end 161.35 122.65) (width 0.1) (layer "F.Cu") (net 35))
  (arc (start 161.7 114.75) (mid 161.672497 114.816398) (end 161.606099 114.843901) (width 0.1) (layer "F.Cu") (net 35))
  (arc (start 161.35 121.7) (mid 161.328033 121.753033) (end 161.275 121.775) (width 0.1) (layer "F.Cu") (net 35))
  (arc (start 160.725 121.775) (mid 160.530546 121.855546) (end 160.45 122.05) (width 0.1) (layer "F.Cu") (net 35))
  (arc (start 160.45 124.7) (mid 160.530546 124.894454) (end 160.725 124.975) (width 0.1) (layer "F.Cu") (net 35))
  (arc (start 161.7 113.75) (mid 161.672497 113.816398) (end 161.606099 113.843901) (width 0.1) (layer "F.Cu") (net 35))
  (arc (start 161.275 123.775) (mid 161.328033 123.796967) (end 161.35 123.85) (width 0.1) (layer "F.Cu") (net 35))
  (arc (start 161.606099 115.093901) (mid 161.672497 115.121404) (end 161.7 115.187802) (width 0.1) (layer "F.Cu") (net 35))
  (arc (start 160.9 121.1) (mid 160.980546 121.294454) (end 161.175 121.375) (width 0.1) (layer "F.Cu") (net 35))
  (arc (start 160.825 124.975) (mid 160.878033 124.996967) (end 160.9 125.05) (width 0.1) (layer "F.Cu") (net 35))
  (arc (start 161.606098 113.343901) (mid 161.5397 113.371404) (end 161.512197 113.437802) (width 0.1) (layer "F.Cu") (net 35))
  (arc (start 161.7 113.25) (mid 161.672497 113.316398) (end 161.606099 113.343901) (width 0.1) (layer "F.Cu") (net 35))
  (arc (start 161.35 124.1) (mid 161.328033 124.153033) (end 161.275 124.175) (width 0.1) (layer "F.Cu") (net 35))
  (arc (start 160.725 122.975) (mid 160.530546 123.055546) (end 160.45 123.25) (width 0.1) (layer "F.Cu") (net 35))
  (arc (start 160.725 124.175) (mid 160.530546 124.255546) (end 160.45 124.45) (width 0.1) (layer "F.Cu") (net 35))
  (arc (start 161.606098 114.843901) (mid 161.5397 114.871404) (end 161.512197 114.937802) (width 0.1) (layer "F.Cu") (net 35))
  (arc (start 161.512197 115) (mid 161.5397 115.066398) (end 161.606098 115.093901) (width 0.1) (layer "F.Cu") (net 35))
  (arc (start 161.512197 113.5) (mid 161.5397 113.566398) (end 161.606098 113.593901) (width 0.1) (layer "F.Cu") (net 35))
  (arc (start 161.512197 114) (mid 161.5397 114.066398) (end 161.606098 114.093901) (width 0.1) (layer "F.Cu") (net 35))
  (arc (start 161.606099 114.593901) (mid 161.672497 114.621404) (end 161.7 114.687802) (width 0.1) (layer "F.Cu") (net 35))
  (arc (start 161.606099 114.093901) (mid 161.672497 114.121404) (end 161.7 114.187802) (width 0.1) (layer "F.Cu") (net 35))
  (arc (start 161.35 122.9) (mid 161.328033 122.953033) (end 161.275 122.975) (width 0.1) (layer "F.Cu") (net 35))
  (segment (start 161.25 117.441422) (end 160.995711 117.695711) (width 0.1) (layer "F.Cu") (net 36))
  (segment (start 160.3 120.891422) (end 160.2 120.891422) (width 0.1) (layer "F.Cu") (net 36))
  (segment (start 160.500737 118.544241) (end 160.500736 118.544241) (width 0.1) (layer "F.Cu") (net 36))
  (segment (start 161.25 112.275) (end 161.25 112.47) (width 0.1) (layer "F.Cu") (net 36))
  (segment (start 159.7 119.191422) (end 159.8 119.191422) (width 0.1) (layer "F.Cu") (net 36))
  (segment (start 160.1 129.049999) (end 160.25 129.199999) (width 0.1) (layer "F.Cu") (net 36))
  (segment (start 160.6 119.491422) (end 160.6 119.591422) (width 0.1) (layer "F.Cu") (net 36))
  (segment (start 159.8 118.891422) (end 159.7 118.891422) (width 0.1) (layer "F.Cu") (net 36))
  (segment (start 159.6 119.991422) (end 159.6 120.091422) (width 0.1) (layer "F.Cu") (net 36))
  (segment (start 159.9 120.191422) (end 160.3 120.191422) (width 0.1) (layer "F.Cu") (net 36))
  (segment (start 159.7 120.191422) (end 159.9 120.191422) (width 0.1) (layer "F.Cu") (net 36))
  (segment locked (start 161.25 112.949265) (end 161.25 117.441422) (width 0.1) (layer "F.Cu") (net 36))
  (segment (start 161.066423 118.473529) (end 161.066421 118.47353) (width 0.1) (layer "F.Cu") (net 36))
  (segment (start 159.6 118.991422) (end 159.6 119.091422) (width 0.1) (layer "F.Cu") (net 36))
  (segment (start 161.36 112.839265) (end 161.25 112.949265) (width 0.1) (layer "F.Cu") (net 36))
  (segment (start 161.066421 118.47353) (end 160.995712 118.54424) (width 0.1) (layer "F.Cu") (net 36))
  (segment (start 160.25 129.199999) (end 160.25 130.1) (width 0.1) (layer "F.Cu") (net 36))
  (segment (start 160.500736 118.544241) (end 160.430026 118.473531) (width 0.1) (layer "F.Cu") (net 36))
  (segment (start 160.6 120.491422) (end 160.6 120.591422) (width 0.1) (layer "F.Cu") (net 36))
  (segment (start 160.3 119.891422) (end 160.1 119.891422) (width 0.1) (layer "F.Cu") (net 36))
  (segment (start 160.217894 118.473531) (end 160.1 118.591422) (width 0.1) (layer "F.Cu") (net 36))
  (segment (start 161.25 112.47) (end 161.36 112.58) (width 0.1) (layer "F.Cu") (net 36))
  (segment (start 160.995711 117.907843) (end 161.066422 117.978554) (width 0.1) (layer "F.Cu") (net 36))
  (segment (start 161.36 112.58) (end 161.36 112.839265) (width 0.1) (layer "F.Cu") (net 36))
  (segment (start 159.8 119.191422) (end 160.3 119.191422) (width 0.1) (layer "F.Cu") (net 36))
  (segment (start 160.1 121.749774) (end 160.1 129.049999) (width 0.1) (layer "F.Cu") (net 36))
  (segment (start 160.1 120.991422) (end 160.1 121.749774) (width 0.1) (layer "F.Cu") (net 36))
  (segment (start 160.1 119.891422) (end 159.7 119.891422) (width 0.1) (layer "F.Cu") (net 36))
  (segment (start 161.05 112.075) (end 161.25 112.275) (width 0.1) (layer "F.Cu") (net 36))
  (arc (start 160.3 120.191422) (mid 160.512132 120.27929) (end 160.6 120.491422) (width 0.1) (layer "F.Cu") (net 36))
  (arc (start 159.6 120.091422) (mid 159.629289 120.162133) (end 159.7 120.191422) (width 0.1) (layer "F.Cu") (net 36))
  (arc (start 161.066422 117.978554) (mid 161.168935 118.226041) (end 161.066423 118.473529) (width 0.1) (layer "F.Cu") (net 36))
  (arc (start 159.7 119.891422) (mid 159.629289 119.920711) (end 159.6 119.991422) (width 0.1) (layer "F.Cu") (net 36))
  (arc (start 160.6 119.591422) (mid 160.512132 119.803554) (end 160.3 119.891422) (width 0.1) (layer "F.Cu") (net 36))
  (arc (start 160.3 119.191422) (mid 160.512132 119.27929) (end 160.6 119.491422) (width 0.1) (layer "F.Cu") (net 36))
  (arc (start 160.430026 118.473531) (mid 160.32396 118.429597) (end 160.217894 118.473531) (width 0.1) (layer "F.Cu") (net 36))
  (arc (start 160.2 120.891422) (mid 160.129289 120.920711) (end 160.1 120.991422) (width 0.1) (layer "F.Cu") (net 36))
  (arc (start 160.995712 118.54424) (mid 160.748225 118.646753) (end 160.500737 118.544241) (width 0.1) (layer "F.Cu") (net 36))
  (arc (start 159.6 119.091422) (mid 159.629289 119.162133) (end 159.7 119.191422) (width 0.1) (layer "F.Cu") (net 36))
  (arc (start 160.1 118.591422) (mid 160.012132 118.803554) (end 159.8 118.891422) (width 0.1) (layer "F.Cu") (net 36))
  (arc (start 159.7 118.891422) (mid 159.629289 118.920711) (end 159.6 118.991422) (width 0.1) (layer "F.Cu") (net 36))
  (arc (start 160.6 120.591422) (mid 160.512132 120.803554) (end 160.3 120.891422) (width 0.1) (layer "F.Cu") (net 36))
  (arc (start 160.995711 117.695711) (mid 160.951777 117.801777) (end 160.995711 117.907843) (width 0.1) (layer "F.Cu") (net 36))
  (segment (start 160.95618 115.843819) (end 160.956181 115.843819) (width 0.1) (layer "F.Cu") (net 37))
  (segment (start 160.862361 114.887638) (end 160.862361 115.05) (width 0.1) (layer "F.Cu") (net 37))
  (segment (start 159.8 119.391422) (end 160.3 119.391422) (width 0.1) (layer "F.Cu") (net 37))
  (segment (start 160.862361 114.187638) (end 160.862361 114.35) (width 0.1) (layer "F.Cu") (net 37))
  (segment (start 161.05 115.937638) (end 161.05 117.358578) (width 0.1) (layer "F.Cu") (net 37))
  (segment (start 159.4 119.991422) (end 159.4 120.091422) (width 0.1) (layer "F.Cu") (net 37))
  (segment (start 159.7 119.391422) (end 159.8 119.391422) (width 0.1) (layer "F.Cu") (net 37))
  (segment (start 161.05 114.537638) (end 161.05 114.7) (width 0.1) (layer "F.Cu") (net 37))
  (segment (start 160.4 119.491422) (end 160.4 119.591422) (width 0.1) (layer "F.Cu") (net 37))
  (segment (start 160.076474 118.332108) (end 159.9 118.508578) (width 0.1) (layer "F.Cu") (net 37))
  (segment (start 159.8 118.691422) (end 159.7 118.691422) (width 0.1) (layer "F.Cu") (net 37))
  (segment (start 161.05 113.837638) (end 161.05 114) (width 0.1) (layer "F.Cu") (net 37))
  (segment (start 160.95618 113.743819) (end 160.956181 113.743819) (width 0.1) (layer "F.Cu") (net 37))
  (segment (start 160.862361 115.587638) (end 160.862361 115.75) (width 0.1) (layer "F.Cu") (net 37))
  (segment (start 159.7 120.391422) (end 159.9 120.391422) (width 0.1) (layer "F.Cu") (net 37))
  (segment (start 159.9 118.508578) (end 159.9 118.591422) (width 0.1) (layer "F.Cu") (net 37))
  (segment (start 160.956181 114.793819) (end 160.95618 114.793819) (width 0.1) (layer "F.Cu") (net 37))
  (segment (start 160.1 119.691422) (end 159.7 119.691422) (width 0.1) (layer "F.Cu") (net 37))
  (segment (start 160.3 120.691422) (end 160.2 120.691422) (width 0.1) (layer "F.Cu") (net 37))
  (segment (start 159.75 129.199999) (end 159.75 130.1) (width 0.1) (layer "F.Cu") (net 37))
  (segment (start 159.9 120.991422) (end 159.9 121.749774) (width 0.1) (layer "F.Cu") (net 37))
  (segment (start 160.95618 114.443819) (end 160.956181 114.443819) (width 0.1) (layer "F.Cu") (net 37))
  (segment (start 161.05 112.725) (end 161.05 113.3) (width 0.1) (layer "F.Cu") (net 37))
  (segment (start 160.956181 113.393819) (end 160.95618 113.393819) (width 0.1) (layer "F.Cu") (net 37))
  (segment (start 161.05 115.237638) (end 161.05 115.4) (width 0.1) (layer "F.Cu") (net 37))
  (segment (start 160.956181 115.493819) (end 160.95618 115.493819) (width 0.1) (layer "F.Cu") (net 37))
  (segment (start 159.4 118.991422) (end 159.4 119.091422) (width 0.1) (layer "F.Cu") (net 37))
  (segment (start 160.854289 118.049266) (end 160.925 118.119977) (width 0.1) (layer "F.Cu") (net 37))
  (segment (start 160.862361 113.487638) (end 160.862361 113.65) (width 0.1) (layer "F.Cu") (net 37))
  (segment (start 159.9 129.049999) (end 159.75 129.199999) (width 0.1) (layer "F.Cu") (net 37))
  (segment (start 159.9 121.749774) (end 159.9 129.049999) (width 0.1) (layer "F.Cu") (net 37))
  (segment (start 159.9 120.391422) (end 160.3 120.391422) (width 0.1) (layer "F.Cu") (net 37))
  (segment (start 160.3 119.691422) (end 160.1 119.691422) (width 0.1) (layer "F.Cu") (net 37))
  (segment (start 160.85429 118.049264) (end 160.854289 118.049266) (width 0.1) (layer "F.Cu") (net 37))
  (segment (start 160.642159 118.402819) (end 160.571449 118.332109) (width 0.1) (layer "F.Cu") (net 37))
  (segment (start 160.956181 114.093819) (end 160.95618 114.093819) (width 0.1) (layer "F.Cu") (net 37))
  (segment (start 160.925 118.332109) (end 160.854291 118.402819) (width 0.1) (layer "F.Cu") (net 37))
  (segment (start 160.95618 115.143819) (end 160.956181 115.143819) (width 0.1) (layer "F.Cu") (net 37))
  (segment (start 160.4 120.491422) (end 160.4 120.591422) (width 0.1) (layer "F.Cu") (net 37))
  (segment (start 161.05 117.358578) (end 160.85429 117.55429) (width 0.1) (layer "F.Cu") (net 37))
  (arc (start 161.05 113.3) (mid 161.022521 113.36634) (end 160.956181 113.393819) (width 0.1) (layer "F.Cu") (net 37))
  (arc (start 160.862361 115.05) (mid 160.88984 115.11634) (end 160.95618 115.143819) (width 0.1) (layer "F.Cu") (net 37))
  (arc (start 160.956181 115.143819) (mid 161.022521 115.171298) (end 161.05 115.237638) (width 0.1) (layer "F.Cu") (net 37))
  (arc (start 160.925 118.119977) (mid 160.968934 118.226043) (end 160.925 118.332109) (width 0.1) (layer "F.Cu") (net 37))
  (arc (start 160.956181 115.843819) (mid 161.022521 115.871298) (end 161.05 115.937638) (width 0.1) (layer "F.Cu") (net 37))
  (arc (start 159.9 118.591422) (mid 159.870711 118.662133) (end 159.8 118.691422) (width 0.1) (layer "F.Cu") (net 37))
  (arc (start 161.05 114) (mid 161.022521 114.06634) (end 160.956181 114.093819) (width 0.1) (layer "F.Cu") (net 37))
  (arc (start 161.05 115.4) (mid 161.022521 115.46634) (end 160.956181 115.493819) (width 0.1) (layer "F.Cu") (net 37))
  (arc (start 160.4 119.591422) (mid 160.370711 119.662133) (end 160.3 119.691422) (width 0.1) (layer "F.Cu") (net 37))
  (arc (start 160.95618 115.493819) (mid 160.88984 115.521298) (end 160.862361 115.587638) (width 0.1) (layer "F.Cu") (net 37))
  (arc (start 160.95618 114.793819) (mid 160.88984 114.821298) (end 160.862361 114.887638) (width 0.1) (layer "F.Cu") (net 37))
  (arc (start 160.571449 118.332109) (mid 160.323962 118.229596) (end 160.076474 118.332108) (width 0.1) (layer "F.Cu") (net 37))
  (arc (start 160.85429 117.55429) (mid 160.751777 117.801778) (end 160.85429 118.049264) (width 0.1) (layer "F.Cu") (net 37))
  (arc (start 160.95618 113.393819) (mid 160.88984 113.421298) (end 160.862361 113.487638) (width 0.1) (layer "F.Cu") (net 37))
  (arc (start 160.95618 114.093819) (mid 160.88984 114.121298) (end 160.862361 114.187638) (width 0.1) (layer "F.Cu") (net 37))
  (arc (start 160.862361 115.75) (mid 160.88984 115.81634) (end 160.95618 115.843819) (width 0.1) (layer "F.Cu") (net 37))
  (arc (start 159.7 118.691422) (mid 159.487868 118.77929) (end 159.4 118.991422) (width 0.1) (layer "F.Cu") (net 37))
  (arc (start 160.956181 113.743819) (mid 161.022521 113.771298) (end 161.05 113.837638) (width 0.1) (layer "F.Cu") (net 37))
  (arc (start 160.956181 114.443819) (mid 161.022521 114.471298) (end 161.05 114.537638) (width 0.1) (layer "F.Cu") (net 37))
  (arc (start 160.3 120.391422) (mid 160.370711 120.420711) (end 160.4 120.491422) (width 0.1) (layer "F.Cu") (net 37))
  (arc (start 161.05 114.7) (mid 161.022521 114.76634) (end 160.956181 114.793819) (width 0.1) (layer "F.Cu") (net 37))
  (arc (start 160.862361 113.65) (mid 160.88984 113.71634) (end 160.95618 113.743819) (width 0.1) (layer "F.Cu") (net 37))
  (arc (start 159.7 119.691422) (mid 159.487868 119.77929) (end 159.4 119.991422) (width 0.1) (layer "F.Cu") (net 37))
  (arc (start 160.854291 118.402819) (mid 160.748225 118.446753) (end 160.642159 118.402819) (width 0.1) (layer "F.Cu") (net 37))
  (arc (start 159.4 119.091422) (mid 159.487868 119.303554) (end 159.7 119.391422) (width 0.1) (layer "F.Cu") (net 37))
  (arc (start 160.4 120.591422) (mid 160.370711 120.662133) (end 160.3 120.691422) (width 0.1) (layer "F.Cu") (net 37))
  (arc (start 160.3 119.391422) (mid 160.370711 119.420711) (end 160.4 119.491422) (width 0.1) (layer "F.Cu") (net 37))
  (arc (start 160.862361 114.35) (mid 160.88984 114.41634) (end 160.95618 114.443819) (width 0.1) (layer "F.Cu") (net 37))
  (arc (start 160.2 120.691422) (mid 159.987868 120.77929) (end 159.9 120.991422) (width 0.1) (layer "F.Cu") (net 37))
  (arc (start 159.4 120.091422) (mid 159.487868 120.303554) (end 159.7 120.391422) (width 0.1) (layer "F.Cu") (net 37))
  (segment (start 159.1 127.125) (end 158.775 127.125) (width 0.1) (layer "F.Cu") (net 38))
  (segment (start 159.45 123.65) (end 159.45 124.1) (width 0.1) (layer "F.Cu") (net 38))
  (segment (start 158.775 123.425) (end 158.875 123.425) (width 0.1) (layer "F.Cu") (net 38))
  (segment locked (start 159.95 112.949265) (end 159.95 115.091422) (width 0.1) (layer "F.Cu") (net 38))
  (segment (start 159.45 125.05) (end 159.45 125.5) (width 0.1) (layer "F.Cu") (net 38))
  (segment (start 159.45 126.45) (end 159.45 126.9) (width 0.1) (layer "F.Cu") (net 38))
  (segment (start 159.25 129.199999) (end 159.25 130.1) (width 0.1) (layer "F.Cu") (net 38))
  (segment (start 159.75 112.075) (end 159.91 112.235) (width 0.1) (layer "F.Cu") (net 38))
  (segment (start 159.95 115.091422) (end 159.1 115.941422) (width 0.1) (layer "F.Cu") (net 38))
  (segment (start 158.75 122.95) (end 158.75 123.4) (width 0.1) (layer "F.Cu") (net 38))
  (segment (start 158.775 127.625) (end 158.875 127.625) (width 0.1) (layer "F.Cu") (net 38))
  (segment (start 160.08 112.6) (end 160.08 112.819265) (width 0.1) (layer "F.Cu") (net 38))
  (segment (start 160.08 112.819265) (end 159.95 112.949265) (width 0.1) (layer "F.Cu") (net 38))
  (segment (start 159.225 124.325) (end 159.1 124.325) (width 0.1) (layer "F.Cu") (net 38))
  (segment (start 159.225 125.725) (end 159.1 125.725) (width 0.1) (layer "F.Cu") (net 38))
  (segment (start 158.9 126.225) (end 159.225 126.225) (width 0.1) (layer "F.Cu") (net 38))
  (segment (start 158.875 122.925) (end 158.775 122.925) (width 0.1) (layer "F.Cu") (net 38))
  (segment (start 158.75 127.15) (end 158.75 127.6) (width 0.1) (layer "F.Cu") (net 38))
  (segment (start 158.775 126.225) (end 158.9 126.225) (width 0.1) (layer "F.Cu") (net 38))
  (segment (start 158.75 124.35) (end 158.75 124.8) (width 0.1) (layer "F.Cu") (net 38))
  (segment (start 159.225 127.125) (end 159.1 127.125) (width 0.1) (layer "F.Cu") (net 38))
  (segment (start 159.91 112.235) (end 159.91 112.43) (width 0.1) (layer "F.Cu") (net 38))
  (segment (start 158.775 124.825) (end 158.9 124.825) (width 0.1) (layer "F.Cu") (net 38))
  (segment (start 159.1 129.049999) (end 159.25 129.199999) (width 0.1) (layer "F.Cu") (net 38))
  (segment (start 159.1 124.325) (end 158.775 124.325) (width 0.1) (layer "F.Cu") (net 38))
  (segment (start 159.1 127.85) (end 159.1 129.049999) (width 0.1) (layer "F.Cu") (net 38))
  (segment (start 158.75 125.75) (end 158.75 126.2) (width 0.1) (layer "F.Cu") (net 38))
  (segment (start 158.875 123.425) (end 159.225 123.425) (width 0.1) (layer "F.Cu") (net 38))
  (segment (start 159.1 115.941422) (end 159.1 122.7) (width 0.1) (layer "F.Cu") (net 38))
  (segment (start 159.91 112.43) (end 160.08 112.6) (width 0.1) (layer "F.Cu") (net 38))
  (segment (start 159.1 125.725) (end 158.775 125.725) (width 0.1) (layer "F.Cu") (net 38))
  (segment (start 158.9 124.825) (end 159.225 124.825) (width 0.1) (layer "F.Cu") (net 38))
  (arc (start 158.875 127.625) (mid 159.034099 127.690901) (end 159.1 127.85) (width 0.1) (layer "F.Cu") (net 38))
  (arc (start 159.1 122.7) (mid 159.034099 122.859099) (end 158.875 122.925) (width 0.1) (layer "F.Cu") (net 38))
  (arc (start 159.225 124.825) (mid 159.384099 124.890901) (end 159.45 125.05) (width 0.1) (layer "F.Cu") (net 38))
  (arc (start 158.75 127.6) (mid 158.757322 127.617678) (end 158.775 127.625) (width 0.1) (layer "F.Cu") (net 38))
  (arc (start 158.75 126.2) (mid 158.757322 126.217678) (end 158.775 126.225) (width 0.1) (layer "F.Cu") (net 38))
  (arc (start 158.775 125.725) (mid 158.757322 125.732322) (end 158.75 125.75) (width 0.1) (layer "F.Cu") (net 38))
  (arc (start 159.225 126.225) (mid 159.384099 126.290901) (end 159.45 126.45) (width 0.1) (layer "F.Cu") (net 38))
  (arc (start 158.775 124.325) (mid 158.757322 124.332322) (end 158.75 124.35) (width 0.1) (layer "F.Cu") (net 38))
  (arc (start 159.45 126.9) (mid 159.384099 127.059099) (end 159.225 127.125) (width 0.1) (layer "F.Cu") (net 38))
  (arc (start 159.45 124.1) (mid 159.384099 124.259099) (end 159.225 124.325) (width 0.1) (layer "F.Cu") (net 38))
  (arc (start 158.75 124.8) (mid 158.757322 124.817678) (end 158.775 124.825) (width 0.1) (layer "F.Cu") (net 38))
  (arc (start 159.225 123.425) (mid 159.384099 123.490901) (end 159.45 123.65) (width 0.1) (layer "F.Cu") (net 38))
  (arc (start 159.45 125.5) (mid 159.384099 125.659099) (end 159.225 125.725) (width 0.1) (layer "F.Cu") (net 38))
  (arc (start 158.75 123.4) (mid 158.757322 123.417678) (end 158.775 123.425) (width 0.1) (layer "F.Cu") (net 38))
  (arc (start 158.775 122.925) (mid 158.757322 122.932322) (end 158.75 122.95) (width 0.1) (layer "F.Cu") (net 38))
  (arc (start 158.775 127.125) (mid 158.757322 127.132322) (end 158.75 127.15) (width 0.1) (layer "F.Cu") (net 38))
  (segment (start 158.55 124.35) (end 158.55 124.8) (width 0.1) (layer "F.Cu") (net 39))
  (segment (start 159.75 112.725) (end 159.75 113.25) (width 0.1) (layer "F.Cu") (net 39))
  (segment (start 158.75 129.199999) (end 158.75 130.1) (width 0.1) (layer "F.Cu") (net 39))
  (segment (start 158.9 126.425) (end 159.225 126.425) (width 0.1) (layer "F.Cu") (net 39))
  (segment (start 158.9 129.049999) (end 158.75 129.199999) (width 0.1) (layer "F.Cu") (net 39))
  (segment (start 158.55 127.15) (end 158.55 127.6) (width 0.1) (layer "F.Cu") (net 39))
  (segment (start 158.9 125.025) (end 159.225 125.025) (width 0.1) (layer "F.Cu") (net 39))
  (segment (start 159.50675 113.99325) (end 159.50675 114) (width 0.1) (layer "F.Cu") (net 39))
  (segment (start 159.25 125.05) (end 159.25 125.5) (width 0.1) (layer "F.Cu") (net 39))
  (segment (start 158.775 123.625) (end 158.875 123.625) (width 0.1) (layer "F.Cu") (net 39))
  (segment (start 158.775 126.425) (end 158.9 126.425) (width 0.1) (layer "F.Cu") (net 39))
  (segment (start 158.775 125.025) (end 158.9 125.025) (width 0.1) (layer "F.Cu") (net 39))
  (segment (start 158.9 115.858578) (end 158.9 122.7) (width 0.1) (layer "F.Cu") (net 39))
  (segment (start 158.875 123.625) (end 159.225 123.625) (width 0.1) (layer "F.Cu") (net 39))
  (segment (start 158.875 122.725) (end 158.775 122.725) (width 0.1) (layer "F.Cu") (net 39))
  (segment (start 159.25 123.65) (end 159.25 124.1) (width 0.1) (layer "F.Cu") (net 39))
  (segment (start 159.75 113.74325) (end 159.75 113.75) (width 0.1) (layer "F.Cu") (net 39))
  (segment (start 158.9 127.85) (end 158.9 129.049999) (width 0.1) (layer "F.Cu") (net 39))
  (segment (start 158.775 127.825) (end 158.875 127.825) (width 0.1) (layer "F.Cu") (net 39))
  (segment (start 159.50675 114.49325) (end 159.50675 114.5) (width 0.1) (layer "F.Cu") (net 39))
  (segment (start 159.1 124.125) (end 158.775 124.125) (width 0.1) (layer "F.Cu") (net 39))
  (segment (start 159.225 125.525) (end 159.1 125.525) (width 0.1) (layer "F.Cu") (net 39))
  (segment (start 159.1 125.525) (end 158.775 125.525) (width 0.1) (layer "F.Cu") (net 39))
  (segment (start 159.225 124.125) (end 159.1 124.125) (width 0.1) (layer "F.Cu") (net 39))
  (segment (start 159.75 115.008578) (end 158.9 115.858578) (width 0.1) (layer "F.Cu") (net 39))
  (segment (start 159.75 114.24325) (end 159.75 114.25) (width 0.1) (layer "F.Cu") (net 39))
  (segment (start 159.25 126.45) (end 159.25 126.9) (width 0.1) (layer "F.Cu") (net 39))
  (segment (start 159.50675 113.49325) (end 159.50675 113.5) (width 0.1) (layer "F.Cu") (net 39))
  (segment (start 159.75 114.74325) (end 159.75 115.008578) (width 0.1) (layer "F.Cu") (net 39))
  (segment (start 158.55 125.75) (end 158.55 126.2) (width 0.1) (layer "F.Cu") (net 39))
  (segment (start 159.225 126.925) (end 159.1 126.925) (width 0.1) (layer "F.Cu") (net 39))
  (segment (start 158.55 122.95) (end 158.55 123.4) (width 0.1) (layer "F.Cu") (net 39))
  (segment (start 159.1 126.925) (end 158.775 126.925) (width 0.1) (layer "F.Cu") (net 39))
  (arc (start 158.775 122.725) (mid 158.615901 122.790901) (end 158.55 122.95) (width 0.1) (layer "F.Cu") (net 39))
  (arc (start 158.55 123.4) (mid 158.615901 123.559099) (end 158.775 123.625) (width 0.1) (layer "F.Cu") (net 39))
  (arc (start 159.75 113.75) (mid 159.714377 113.836002) (end 159.628375 113.871625) (width 0.1) (layer "F.Cu") (net 39))
  (arc (start 158.875 127.825) (mid 158.892678 127.832322) (end 158.9 127.85) (width 0.1) (layer "F.Cu") (net 39))
  (arc (start 158.775 124.125) (mid 158.615901 124.190901) (end 158.55 124.35) (width 0.1) (layer "F.Cu") (net 39))
  (arc (start 159.628375 114.621625) (mid 159.714377 114.657248) (end 159.75 114.74325) (width 0.1) (layer "F.Cu") (net 39))
  (arc (start 159.628375 114.371625) (mid 159.542373 114.407248) (end 159.50675 114.49325) (width 0.1) (layer "F.Cu") (net 39))
  (arc (start 158.55 126.2) (mid 158.615901 126.359099) (end 158.775 126.425) (width 0.1) (layer "F.Cu") (net 39))
  (arc (start 159.50675 114) (mid 159.542373 114.086002) (end 159.628375 114.121625) (width 0.1) (layer "F.Cu") (net 39))
  (arc (start 159.225 123.625) (mid 159.242678 123.632322) (end 159.25 123.65) (width 0.1) (layer "F.Cu") (net 39))
  (arc (start 159.25 124.1) (mid 159.242678 124.117678) (end 159.225 124.125) (width 0.1) (layer "F.Cu") (net 39))
  (arc (start 158.55 127.6) (mid 158.615901 127.759099) (end 158.775 127.825) (width 0.1) (layer "F.Cu") (net 39))
  (arc (start 159.628375 113.871625) (mid 159.542373 113.907248) (end 159.50675 113.99325) (width 0.1) (layer "F.Cu") (net 39))
  (arc (start 158.775 126.925) (mid 158.615901 126.990901) (end 158.55 127.15) (width 0.1) (layer "F.Cu") (net 39))
  (arc (start 158.55 124.8) (mid 158.615901 124.959099) (end 158.775 125.025) (width 0.1) (layer "F.Cu") (net 39))
  (arc (start 158.775 125.525) (mid 158.615901 125.590901) (end 158.55 125.75) (width 0.1) (layer "F.Cu") (net 39))
  (arc (start 159.628375 114.121625) (mid 159.714377 114.157248) (end 159.75 114.24325) (width 0.1) (layer "F.Cu") (net 39))
  (arc (start 159.50675 114.5) (mid 159.542373 114.586002) (end 159.628375 114.621625) (width 0.1) (layer "F.Cu") (net 39))
  (arc (start 159.25 126.9) (mid 159.242678 126.917678) (end 159.225 126.925) (width 0.1) (layer "F.Cu") (net 39))
  (arc (start 159.225 125.025) (mid 159.242678 125.032322) (end 159.25 125.05) (width 0.1) (layer "F.Cu") (net 39))
  (arc (start 159.50675 113.5) (mid 159.542373 113.586002) (end 159.628375 113.621625) (width 0.1) (layer "F.Cu") (net 39))
  (arc (start 159.225 126.425) (mid 159.242678 126.432322) (end 159.25 126.45) (width 0.1) (layer "F.Cu") (net 39))
  (arc (start 159.75 113.25) (mid 159.714377 113.336002) (end 159.628375 113.371625) (width 0.1) (layer "F.Cu") (net 39))
  (arc (start 159.628375 113.621625) (mid 159.714377 113.657248) (end 159.75 113.74325) (width 0.1) (layer "F.Cu") (net 39))
  (arc (start 158.9 122.7) (mid 158.892678 122.717678) (end 158.875 122.725) (width 0.1) (layer "F.Cu") (net 39))
  (arc (start 159.25 125.5) (mid 159.242678 125.517678) (end 159.225 125.525) (width 0.1) (layer "F.Cu") (net 39))
  (arc (start 159.75 114.25) (mid 159.714377 114.336002) (end 159.628375 114.371625) (width 0.1) (layer "F.Cu") (net 39))
  (arc (start 159.628375 113.371625) (mid 159.542373 113.407248) (end 159.50675 113.49325) (width 0.1) (layer "F.Cu") (net 39))
  (segment (start 159.29 112.265) (end 159.29 112.46) (width 0.1) (layer "F.Cu") (net 40))
  (segment (start 159.43 112.6) (end 159.43 112.819265) (width 0.1) (layer "F.Cu") (net 40))
  (segment (start 158.35 120.32) (end 158.1 120.32) (width 0.1) (layer "F.Cu") (net 40))
  (segment (start 158.7 119.87) (end 158.7 119.97) (width 0.1) (layer "F.Cu") (net 40))
  (segment (start 157.6 120.72) (end 157.7 120.72) (width 0.1) (layer "F.Cu") (net 40))
  (segment (start 159.43 112.819265) (end 159.3 112.949265) (width 0.1) (layer "F.Cu") (net 40))
  (segment locked (start 159.3 112.949265) (end 159.3 115.041422) (width 0.1) (layer "F.Cu") (net 40))
  (segment (start 158.35 119.12) (end 158.25 119.12) (width 0.1) (layer "F.Cu") (net 40))
  (segment (start 158.1 121.12) (end 158.1 123.274704) (width 0.1) (layer "F.Cu") (net 40))
  (segment (start 159.3 115.041422) (end 158.1 116.241422) (width 0.1) (layer "F.Cu") (net 40))
  (segment (start 157.6 119.52) (end 157.9 119.52) (width 0.1) (layer "F.Cu") (net 40))
  (segment (start 158.1 120.32) (end 157.6 120.32) (width 0.1) (layer "F.Cu") (net 40))
  (segment (start 159.1 112.075) (end 159.29 112.265) (width 0.1) (layer "F.Cu") (net 40))
  (segment (start 159.29 112.46) (end 159.43 112.6) (width 0.1) (layer "F.Cu") (net 40))
  (segment (start 157.9 119.52) (end 158.35 119.52) (width 0.1) (layer "F.Cu") (net 40))
  (segment (start 158.25 118.32) (end 158.35 118.32) (width 0.1) (layer "F.Cu") (net 40))
  (segment (start 158.1 123.274704) (end 158.1 129.049999) (width 0.1) (layer "F.Cu") (net 40))
  (segment (start 158.1 129.049999) (end 158.25 129.199999) (width 0.1) (layer "F.Cu") (net 40))
  (segment (start 158.25 119.12) (end 157.6 119.12) (width 0.1) (layer "F.Cu") (net 40))
  (segment (start 158.1 116.241422) (end 158.1 118.17) (width 0.1) (layer "F.Cu") (net 40))
  (segment (start 158.25 129.199999) (end 158.25 130.1) (width 0.1) (layer "F.Cu") (net 40))
  (segment (start 158.7 118.67) (end 158.7 118.77) (width 0.1) (layer "F.Cu") (net 40))
  (arc (start 158.35 118.32) (mid 158.597487 118.422513) (end 158.7 118.67) (width 0.1) (layer "F.Cu") (net 40))
  (arc (start 157.6 119.12) (mid 157.458579 119.178579) (end 157.4 119.32) (width 0.1) (layer "F.Cu") (net 40))
  (arc (start 158.7 118.77) (mid 158.597487 119.017487) (end 158.35 119.12) (width 0.1) (layer "F.Cu") (net 40))
  (arc (start 157.7 120.72) (mid 157.982843 120.837157) (end 158.1 121.12) (width 0.1) (layer "F.Cu") (net 40))
  (arc (start 158.1 118.17) (mid 158.143934 118.276066) (end 158.25 118.32) (width 0.1) (layer "F.Cu") (net 40))
  (arc (start 158.35 119.52) (mid 158.597487 119.622513) (end 158.7 119.87) (width 0.1) (layer "F.Cu") (net 40))
  (arc (start 157.6 120.32) (mid 157.458579 120.378579) (end 157.4 120.52) (width 0.1) (layer "F.Cu") (net 40))
  (arc (start 157.4 120.52) (mid 157.458579 120.661421) (end 157.6 120.72) (width 0.1) (layer "F.Cu") (net 40))
  (arc (start 157.4 119.32) (mid 157.458579 119.461421) (end 157.6 119.52) (width 0.1) (layer "F.Cu") (net 40))
  (arc (start 158.7 119.97) (mid 158.597487 120.217487) (end 158.35 120.32) (width 0.1) (layer "F.Cu") (net 40))
  (segment (start 159.1 112.725) (end 159.1 113.2) (width 0.1) (layer "F.Cu") (net 41))
  (segment (start 158.25 118.92) (end 157.6 118.92) (width 0.1) (layer "F.Cu") (net 41))
  (segment (start 159.1 114.775604) (end 159.1 114.8) (width 0.1) (layer "F.Cu") (net 41))
  (segment (start 157.75 129.199999) (end 157.75 130.1) (width 0.1) (layer "F.Cu") (net 41))
  (segment (start 159.1 113.975604) (end 159.1 114) (width 0.1) (layer "F.Cu") (net 41))
  (segment (start 157.9 121.12) (end 157.9 123.274704) (width 0.1) (layer "F.Cu") (net 41))
  (segment (start 157.9 116.158578) (end 157.9 118.17) (width 0.1) (layer "F.Cu") (net 41))
  (segment (start 158.35 120.12) (end 158.1 120.12) (width 0.1) (layer "F.Cu") (net 41))
  (segment (start 157.6 119.72) (end 157.9 119.72) (width 0.1) (layer "F.Cu") (net 41))
  (segment (start 158.1 120.12) (end 157.6 120.12) (width 0.1) (layer "F.Cu") (net 41))
  (segment (start 159.1 114.958578) (end 157.9 116.158578) (width 0.1) (layer "F.Cu") (net 41))
  (segment (start 157.9 129.049999) (end 157.75 129.199999) (width 0.1) (layer "F.Cu") (net 41))
  (segment (start 158.724396 113.575604) (end 158.724396 113.6) (width 0.1) (layer "F.Cu") (net 41))
  (segment (start 158.35 118.92) (end 158.25 118.92) (width 0.1) (layer "F.Cu") (net 41))
  (segment (start 157.9 119.72) (end 158.35 119.72) (width 0.1) (layer "F.Cu") (net 41))
  (segment (start 157.6 120.92) (end 157.7 120.92) (width 0.1) (layer "F.Cu") (net 41))
  (segment (start 157.9 123.274704) (end 157.9 129.049999) (width 0.1) (layer "F.Cu") (net 41))
  (segment (start 158.724396 114.375604) (end 158.724396 114.4) (width 0.1) (layer "F.Cu") (net 41))
  (segment (start 158.25 118.52) (end 158.35 118.52) (width 0.1) (layer "F.Cu") (net 41))
  (segment (start 159.1 114.8) (end 159.1 114.958578) (width 0.1) (layer "F.Cu") (net 41))
  (segment (start 158.5 119.87) (end 158.5 119.97) (width 0.1) (layer "F.Cu") (net 41))
  (segment (start 158.5 118.67) (end 158.5 118.77) (width 0.1) (layer "F.Cu") (net 41))
  (arc (start 158.912198 113.387802) (mid 158.779402 113.442808) (end 158.724396 113.575604) (width 0.1) (layer "F.Cu") (net 41))
  (arc (start 157.6 120.12) (mid 157.317157 120.237157) (end 157.2 120.52) (width 0.1) (layer "F.Cu") (net 41))
  (arc (start 157.6 118.92) (mid 157.317157 119.037157) (end 157.2 119.32) (width 0.1) (layer "F.Cu") (net 41))
  (arc (start 157.2 120.52) (mid 157.317157 120.802843) (end 157.6 120.92) (width 0.1) (layer "F.Cu") (net 41))
  (arc (start 158.912198 113.787802) (mid 159.044994 113.842808) (end 159.1 113.975604) (width 0.1) (layer "F.Cu") (net 41))
  (arc (start 157.9 118.17) (mid 158.002513 118.417487) (end 158.25 118.52) (width 0.1) (layer "F.Cu") (net 41))
  (arc (start 159.1 113.2) (mid 159.044994 113.332796) (end 158.912198 113.387802) (width 0.1) (layer "F.Cu") (net 41))
  (arc (start 157.2 119.32) (mid 157.317157 119.602843) (end 157.6 119.72) (width 0.1) (layer "F.Cu") (net 41))
  (arc (start 158.912198 114.187802) (mid 158.779402 114.242808) (end 158.724396 114.375604) (width 0.1) (layer "F.Cu") (net 41))
  (arc (start 158.5 119.97) (mid 158.456066 120.076066) (end 158.35 120.12) (width 0.1) (layer "F.Cu") (net 41))
  (arc (start 158.724396 113.6) (mid 158.779402 113.732796) (end 158.912198 113.787802) (width 0.1) (layer "F.Cu") (net 41))
  (arc (start 158.5 118.77) (mid 158.456066 118.876066) (end 158.35 118.92) (width 0.1) (layer "F.Cu") (net 41))
  (arc (start 158.912198 114.587802) (mid 159.044994 114.642808) (end 159.1 114.775604) (width 0.1) (layer "F.Cu") (net 41))
  (arc (start 157.7 120.92) (mid 157.841421 120.978579) (end 157.9 121.12) (width 0.1) (layer "F.Cu") (net 41))
  (arc (start 158.724396 114.4) (mid 158.779402 114.532796) (end 158.912198 114.587802) (width 0.1) (layer "F.Cu") (net 41))
  (arc (start 159.1 114) (mid 159.044994 114.132796) (end 158.912198 114.187802) (width 0.1) (layer "F.Cu") (net 41))
  (arc (start 158.35 118.52) (mid 158.456066 118.563934) (end 158.5 118.67) (width 0.1) (layer "F.Cu") (net 41))
  (arc (start 158.35 119.72) (mid 158.456066 119.763934) (end 158.5 119.87) (width 0.1) (layer "F.Cu") (net 41))
  (segment (start 156.6 129.049999) (end 156.75 129.199999) (width 0.1) (layer "F.Cu") (net 42))
  (segment (start 156.6 117.991422) (end 156.6 129.049999) (width 0.1) (layer "F.Cu") (net 42))
  (segment (start 160.6 116.291422) (end 160.326777 116.564645) (width 0.1) (layer "F.Cu") (net 42))
  (segment (start 160.72 112.58) (end 160.72 112.829265) (width 0.1) (layer "F.Cu") (net 42))
  (segment (start 160.6 112.275) (end 160.6 112.46) (width 0.1) (layer "F.Cu") (net 42))
  (segment (start 156.75 129.199999) (end 156.75 130.1) (width 0.1) (layer "F.Cu") (net 42))
  (segment (start 160.6 112.46) (end 160.72 112.58) (width 0.1) (layer "F.Cu") (net 42))
  (segment (start 160.326777 116.564645) (end 160.326777 116.776777) (width 0.1) (layer "F.Cu") (net 42))
  (segment (start 160.6 112.949265) (end 160.6 116.291422) (width 0.1) (layer "F.Cu") (net 42))
  (segment (start 160.4 112.075) (end 160.6 112.275) (width 0.1) (layer "F.Cu") (net 42))
  (segment (start 160.72 112.829265) (end 160.6 112.949265) (width 0.1) (layer "F.Cu") (net 42))
  (segment (start 157.267511 117.536043) (end 157.055379 117.536043) (width 0.1) (layer "F.Cu") (net 42))
  (segment (start 157.055379 117.536043) (end 156.6 117.991422) (width 0.1) (layer "F.Cu") (net 42))
  (via (at 160.326777 116.776777) (size 0.4) (drill 0.15) (layers "F.Cu" "B.Cu") (net 42))
  (via (at 157.267511 117.536043) (size 0.4) (drill 0.15) (layers "F.Cu" "B.Cu") (net 42))
  (segment (start 157.691422 116.9) (end 157.267511 117.323911) (width 0.1) (layer "B.Cu") (net 42))
  (segment (start 160.326777 116.776777) (end 160.114645 116.776777) (width 0.1) (layer "B.Cu") (net 42))
  (segment (start 160.114645 116.776777) (end 159.991422 116.9) (width 0.1) (layer "B.Cu") (net 42))
  (segment (start 157.267511 117.323911) (end 157.267511 117.536043) (width 0.1) (layer "B.Cu") (net 42))
  (segment (start 159.991422 116.9) (end 157.691422 116.9) (width 0.1) (layer "B.Cu") (net 42))
  (segment (start 160.306889 115.556889) (end 160.306888 115.556889) (width 0.1) (layer "F.Cu") (net 43))
  (segment (start 160.306888 115.306889) (end 160.306889 115.306889) (width 0.1) (layer "F.Cu") (net 43))
  (segment (start 156.4 117.908578) (end 156.4 129.049999) (width 0.1) (layer "F.Cu") (net 43))
  (segment (start 156.913957 117.394621) (end 156.4 117.908578) (width 0.1) (layer "F.Cu") (net 43))
  (segment (start 160.213777 115.463778) (end 160.213777 115.4) (width 0.1) (layer "F.Cu") (net 43))
  (segment (start 156.4 129.049999) (end 156.25 129.199999) (width 0.1) (layer "F.Cu") (net 43))
  (segment (start 160.185355 116.423223) (end 160.4 116.208578) (width 0.1) (layer "F.Cu") (net 43))
  (segment (start 160.275 116.025) (end 160.088777 116.025) (width 0.1) (layer "F.Cu") (net 43))
  (segment (start 160.4 115.213778) (end 160.4 115.15) (width 0.1) (layer "F.Cu") (net 43))
  (segment (start 160.088777 115.775) (end 160.275 115.775) (width 0.1) (layer "F.Cu") (net 43))
  (segment (start 159.973223 116.423223) (end 160.185355 116.423223) (width 0.1) (layer "F.Cu") (net 43))
  (segment (start 156.913957 117.182489) (end 156.913957 117.394621) (width 0.1) (layer "F.Cu") (net 43))
  (segment (start 156.25 129.199999) (end 156.25 130.1) (width 0.1) (layer "F.Cu") (net 43))
  (segment (start 160.4 116.208578) (end 160.4 116.15) (width 0.1) (layer "F.Cu") (net 43))
  (segment (start 160.4 115.15) (end 160.4 112.725) (width 0.1) (layer "F.Cu") (net 43))
  (via (at 159.973223 116.423223) (size 0.4) (drill 0.15) (layers "F.Cu" "B.Cu") (net 43))
  (via (at 156.913957 117.182489) (size 0.4) (drill 0.15) (layers "F.Cu" "B.Cu") (net 43))
  (arc (start 160.088777 116.025) (mid 160.000389 115.988388) (end 159.963777 115.9) (width 0.1) (layer "F.Cu") (net 43))
  (arc (start 160.4 116.15) (mid 160.363388 116.061612) (end 160.275 116.025) (width 0.1) (layer "F.Cu") (net 43))
  (arc (start 160.4 115.65) (mid 160.372728 115.584161) (end 160.306889 115.556889) (width 0.1) (layer "F.Cu") (net 43))
  (arc (start 160.306889 115.306889) (mid 160.372728 115.279617) (end 160.4 115.213778) (width 0.1) (layer "F.Cu") (net 43))
  (arc (start 160.213777 115.4) (mid 160.241049 115.334161) (end 160.306888 115.306889) (width 0.1) (layer "F.Cu") (net 43))
  (arc (start 160.306888 115.556889) (mid 160.241049 115.529617) (end 160.213777 115.463778) (width 0.1) (layer "F.Cu") (net 43))
  (arc (start 160.275 115.775) (mid 160.363388 115.738388) (end 160.4 115.65) (width 0.1) (layer "F.Cu") (net 43))
  (arc (start 159.963777 115.9) (mid 160.000389 115.811612) (end 160.088777 115.775) (width 0.1) (layer "F.Cu") (net 43))
  (segment (start 159.973223 116.423223) (end 159.973223 116.635355) (width 0.1) (layer "B.Cu") (net 43))
  (segment (start 159.908578 116.7) (end 157.608578 116.7) (width 0.1) (layer "B.Cu") (net 43))
  (segment (start 157.608578 116.7) (end 157.126089 117.182489) (width 0.1) (layer "B.Cu") (net 43))
  (segment (start 159.973223 116.635355) (end 159.908578 116.7) (width 0.1) (layer "B.Cu") (net 43))
  (segment (start 157.126089 117.182489) (end 156.913957 117.182489) (width 0.1) (layer "B.Cu") (net 43))
  (segment (start 146.611555 123.323111) (end 146.688445 123.323111) (width 0.1) (layer "F.Cu") (net 48))
  (segment (start 137.9 112.225) (end 137.9 112.450735) (width 0.1) (layer "F.Cu") (net 48))
  (segment (start 137.9 118.658578) (end 141.941422 122.7) (width 0.1) (layer "F.Cu") (net 48))
  (segment (start 146.85 123.161556) (end 146.85 123.061555) (width 0.1) (layer "F.Cu") (net 48))
  (segment (start 137.7 112.025) (end 137.9 112.225) (width 0.1) (layer "F.Cu") (net 48))
  (segment (start 137.9 112.899265) (end 137.9 118.658578) (width 0.1) (layer "F.Cu") (net 48))
  (segment (start 147.211555 122.7) (end 148.591422 122.7) (width 0.1) (layer "F.Cu") (net 48))
  (segment (start 148.591422 122.7) (end 152.1 126.208578) (width 0.1) (layer "F.Cu") (net 48))
  (segment (start 146.45 122.376889) (end 146.45 123.161556) (width 0.1) (layer "F.Cu") (net 48))
  (segment (start 137.9 112.450735) (end 138 112.550735) (width 0.1) (layer "F.Cu") (net 48))
  (segment (start 145.65 122.5) (end 145.65 122.376889) (width 0.1) (layer "F.Cu") (net 48))
  (segment (start 152.1 129.049999) (end 152.25 129.199999) (width 0.1) (layer "F.Cu") (net 48))
  (segment (start 138 112.550735) (end 138 112.799265) (width 0.1) (layer "F.Cu") (net 48))
  (segment (start 141.941422 122.7) (end 145.45 122.7) (width 0.1) (layer "F.Cu") (net 48))
  (segment (start 138 112.799265) (end 137.9 112.899265) (width 0.1) (layer "F.Cu") (net 48))
  (segment (start 152.25 129.199999) (end 152.25 130.1) (width 0.1) (layer "F.Cu") (net 48))
  (segment (start 152.1 126.208578) (end 152.1 129.049999) (width 0.1) (layer "F.Cu") (net 48))
  (arc (start 146.45 123.161556) (mid 146.497318 123.275793) (end 146.611555 123.323111) (width 0.1) (layer "F.Cu") (net 48))
  (arc (start 146.688445 123.323111) (mid 146.802682 123.275793) (end 146.85 123.161556) (width 0.1) (layer "F.Cu") (net 48))
  (arc (start 145.65 122.376889) (mid 145.767157 122.094046) (end 146.05 121.976889) (width 0.1) (layer "F.Cu") (net 48))
  (arc (start 146.85 123.061555) (mid 146.955897 122.805897) (end 147.211555 122.7) (width 0.1) (layer "F.Cu") (net 48))
  (arc (start 145.45 122.7) (mid 145.591421 122.641421) (end 145.65 122.5) (width 0.1) (layer "F.Cu") (net 48))
  (arc (start 146.05 121.976889) (mid 146.332843 122.094046) (end 146.45 122.376889) (width 0.1) (layer "F.Cu") (net 48))
  (segment (start 141.858578 122.9) (end 145.45 122.9) (width 0.1) (layer "F.Cu") (net 49))
  (segment (start 137.7 118.741422) (end 141.858578 122.9) (width 0.1) (layer "F.Cu") (net 49))
  (segment (start 137.7 112.675) (end 137.7 114.8) (width 0.1) (layer "F.Cu") (net 49))
  (segment (start 146.25 122.376889) (end 146.25 123.161556) (width 0.1) (layer "F.Cu") (net 49))
  (segment (start 137.575 114.925) (end 137.513777 114.925) (width 0.1) (layer "F.Cu") (net 49))
  (segment (start 146.611555 123.523111) (end 146.688445 123.523111) (width 0.1) (layer "F.Cu") (net 49))
  (segment (start 148.508578 122.9) (end 151.9 126.291422) (width 0.1) (layer "F.Cu") (net 49))
  (segment (start 137.513777 115.175) (end 137.575 115.175) (width 0.1) (layer "F.Cu") (net 49))
  (segment (start 151.9 129.049999) (end 151.75 129.199999) (width 0.1) (layer "F.Cu") (net 49))
  (segment (start 137.513777 115.675) (end 137.575 115.675) (width 0.1) (layer "F.Cu") (net 49))
  (segment (start 145.85 122.5) (end 145.85 122.376889) (width 0.1) (layer "F.Cu") (net 49))
  (segment (start 151.9 126.291422) (end 151.9 129.049999) (width 0.1) (layer "F.Cu") (net 49))
  (segment (start 151.75 129.199999) (end 151.75 130.1) (width 0.1) (layer "F.Cu") (net 49))
  (segment (start 137.575 115.425) (end 137.513777 115.425) (width 0.1) (layer "F.Cu") (net 49))
  (segment (start 137.7 115.8) (end 137.7 118.741422) (width 0.1) (layer "F.Cu") (net 49))
  (segment (start 147.211555 122.9) (end 148.508578 122.9) (width 0.1) (layer "F.Cu") (net 49))
  (segment (start 147.05 123.161556) (end 147.05 123.061555) (width 0.1) (layer "F.Cu") (net 49))
  (arc (start 137.513777 114.925) (mid 137.425389 114.961612) (end 137.388777 115.05) (width 0.1) (layer "F.Cu") (net 49))
  (arc (start 137.7 114.8) (mid 137.663388 114.888388) (end 137.575 114.925) (width 0.1) (layer "F.Cu") (net 49))
  (arc (start 137.575 115.675) (mid 137.663388 115.711612) (end 137.7 115.8) (width 0.1) (layer "F.Cu") (net 49))
  (arc (start 145.85 122.376889) (mid 145.908579 122.235468) (end 146.05 122.176889) (width 0.1) (layer "F.Cu") (net 49))
  (arc (start 137.388777 115.55) (mid 137.425389 115.638388) (end 137.513777 115.675) (width 0.1) (layer "F.Cu") (net 49))
  (arc (start 145.45 122.9) (mid 145.732843 122.782843) (end 145.85 122.5) (width 0.1) (layer "F.Cu") (net 49))
  (arc (start 146.688445 123.523111) (mid 146.944103 123.417214) (end 147.05 123.161556) (width 0.1) (layer "F.Cu") (net 49))
  (arc (start 146.05 122.176889) (mid 146.191421 122.235468) (end 146.25 122.376889) (width 0.1) (layer "F.Cu") (net 49))
  (arc (start 137.7 115.3) (mid 137.663388 115.388388) (end 137.575 115.425) (width 0.1) (layer "F.Cu") (net 49))
  (arc (start 146.25 123.161556) (mid 146.355897 123.417214) (end 146.611555 123.523111) (width 0.1) (layer "F.Cu") (net 49))
  (arc (start 137.513777 115.425) (mid 137.425389 115.461612) (end 137.388777 115.55) (width 0.1) (layer "F.Cu") (net 49))
  (arc (start 137.575 115.175) (mid 137.663388 115.211612) (end 137.7 115.3) (width 0.1) (layer "F.Cu") (net 49))
  (arc (start 147.05 123.061555) (mid 147.097318 122.947318) (end 147.211555 122.9) (width 0.1) (layer "F.Cu") (net 49))
  (arc (start 137.388777 115.05) (mid 137.425389 115.138388) (end 137.513777 115.175) (width 0.1) (layer "F.Cu") (net 49))
  (segment (start 144.465 124.487258) (end 144.465 124.375) (width 0.1) (layer "F.Cu") (net 50))
  (segment (start 145.817813 124.05) (end 148.041422 124.05) (width 0.1) (layer "F.Cu") (net 50))
  (segment (start 151.25 129.199999) (end 151.25 130.1) (width 0.1) (layer "F.Cu") (net 50))
  (segment (start 137.25 114.341422) (end 136.9 114.691422) (width 0.1) (layer "F.Cu") (net 50))
  (segment (start 136.9 119.708578) (end 141.241422 124.05) (width 0.1) (layer "F.Cu") (net 50))
  (segment (start 137.35 112.799265) (end 137.25 112.899265) (width 0.1) (layer "F.Cu") (net 50))
  (segment (start 144.215 123.925) (end 144.215 124.487258) (width 0.1) (layer "F.Cu") (net 50))
  (segment (start 137.25 112.450735) (end 137.35 112.550735) (width 0.1) (layer "F.Cu") (net 50))
  (segment (start 137.25 112.899265) (end 137.25 114.341422) (width 0.1) (layer "F.Cu") (net 50))
  (segment (start 151.1 129.049999) (end 151.25 129.199999) (width 0.1) (layer "F.Cu") (net 50))
  (segment (start 137.25 112.225) (end 137.25 112.450735) (width 0.1) (layer "F.Cu") (net 50))
  (segment (start 151.1 127.108578) (end 151.1 129.049999) (width 0.1) (layer "F.Cu") (net 50))
  (segment (start 137.05 112.025) (end 137.25 112.225) (width 0.1) (layer "F.Cu") (net 50))
  (segment (start 148.041422 124.05) (end 151.1 127.108578) (width 0.1) (layer "F.Cu") (net 50))
  (segment (start 137.35 112.550735) (end 137.35 112.799265) (width 0.1) (layer "F.Cu") (net 50))
  (segment (start 143.565 123.925) (end 143.565 123.812742) (width 0.1) (layer "F.Cu") (net 50))
  (segment (start 141.241422 124.05) (end 143.44 124.05) (width 0.1) (layer "F.Cu") (net 50))
  (segment (start 144.215 123.812742) (end 144.215 123.925) (width 0.1) (layer "F.Cu") (net 50))
  (segment (start 136.9 114.691422) (end 136.9 119.708578) (width 0.1) (layer "F.Cu") (net 50))
  (segment (start 144.79 124.05) (end 145.817813 124.05) (width 0.1) (layer "F.Cu") (net 50))
  (arc (start 143.89 123.487742) (mid 144.11981 123.582932) (end 144.215 123.812742) (width 0.1) (layer "F.Cu") (net 50))
  (arc (start 144.34 124.612258) (mid 144.428388 124.575646) (end 144.465 124.487258) (width 0.1) (layer "F.Cu") (net 50))
  (arc (start 143.565 123.812742) (mid 143.66019 123.582932) (end 143.89 123.487742) (width 0.1) (layer "F.Cu") (net 50))
  (arc (start 144.465 124.375) (mid 144.56019 124.14519) (end 144.79 124.05) (width 0.1) (layer "F.Cu") (net 50))
  (arc (start 144.215 124.487258) (mid 144.251612 124.575646) (end 144.34 124.612258) (width 0.1) (layer "F.Cu") (net 50))
  (arc (start 143.44 124.05) (mid 143.528388 124.013388) (end 143.565 123.925) (width 0.1) (layer "F.Cu") (net 50))
  (segment (start 144.015 123.812742) (end 144.015 123.925) (width 0.1) (layer "F.Cu") (net 51))
  (segment (start 144.665 124.487258) (end 144.665 124.375) (width 0.1) (layer "F.Cu") (net 51))
  (segment (start 144.79 124.25) (end 145.817813 124.25) (width 0.1) (layer "F.Cu") (net 51))
  (segment (start 150.9 129.049999) (end 150.75 129.199999) (width 0.1) (layer "F.Cu") (net 51))
  (segment (start 136.578392 114.980185) (end 136.578393 114.980185) (width 0.1) (layer "F.Cu") (net 51))
  (segment (start 137.05 112.675) (end 137.05 114.258578) (width 0.1) (layer "F.Cu") (net 51))
  (segment (start 136.578393 114.730185) (end 136.578392 114.730185) (width 0.1) (layer "F.Cu") (net 51))
  (segment (start 143.765 123.925) (end 143.765 123.812742) (width 0.1) (layer "F.Cu") (net 51))
  (segment (start 136.456785 114.851792) (end 136.456785 114.858578) (width 0.1) (layer "F.Cu") (net 51))
  (segment (start 141.158578 124.25) (end 143.44 124.25) (width 0.1) (layer "F.Cu") (net 51))
  (segment (start 136.578392 115.980185) (end 136.578393 115.980185) (width 0.1) (layer "F.Cu") (net 51))
  (segment (start 136.578392 115.480185) (end 136.578393 115.480185) (width 0.1) (layer "F.Cu") (net 51))
  (segment (start 136.578393 115.230185) (end 136.578392 115.230185) (width 0.1) (layer "F.Cu") (net 51))
  (segment (start 136.7 116.101792) (end 136.7 116.108578) (width 0.1) (layer "F.Cu") (net 51))
  (segment (start 136.7 116.108578) (end 136.7 119.791422) (width 0.1) (layer "F.Cu") (net 51))
  (segment (start 150.9 127.191422) (end 150.9 129.049999) (width 0.1) (layer "F.Cu") (net 51))
  (segment (start 136.456785 115.351792) (end 136.456785 115.358578) (width 0.1) (layer "F.Cu") (net 51))
  (segment (start 147.958578 124.25) (end 150.9 127.191422) (width 0.1) (layer "F.Cu") (net 51))
  (segment (start 136.578393 115.730185) (end 136.578392 115.730185) (width 0.1) (layer "F.Cu") (net 51))
  (segment (start 137.05 114.258578) (end 136.7 114.608578) (width 0.1) (layer "F.Cu") (net 51))
  (segment (start 136.7 119.791422) (end 141.158578 124.25) (width 0.1) (layer "F.Cu") (net 51))
  (segment (start 144.015 123.925) (end 144.015 124.487258) (width 0.1) (layer "F.Cu") (net 51))
  (segment (start 145.817813 124.25) (end 147.958578 124.25) (width 0.1) (layer "F.Cu") (net 51))
  (segment (start 136.456785 115.851792) (end 136.456785 115.858578) (width 0.1) (layer "F.Cu") (net 51))
  (segment (start 150.75 129.199999) (end 150.75 130.1) (width 0.1) (layer "F.Cu") (net 51))
  (segment (start 136.7 115.601792) (end 136.7 115.608578) (width 0.1) (layer "F.Cu") (net 51))
  (segment (start 136.7 115.101792) (end 136.7 115.108578) (width 0.1) (layer "F.Cu") (net 51))
  (arc (start 136.7 114.608578) (mid 136.664382 114.694567) (end 136.578393 114.730185) (width 0.1) (layer "F.Cu") (net 51))
  (arc (start 136.7 115.608578) (mid 136.664382 115.694567) (end 136.578393 115.730185) (width 0.1) (layer "F.Cu") (net 51))
  (arc (start 136.456785 114.858578) (mid 136.492403 114.944567) (end 136.578392 114.980185) (width 0.1) (layer "F.Cu") (net 51))
  (arc (start 136.578392 115.730185) (mid 136.492403 115.765803) (end 136.456785 115.851792) (width 0.1) (layer "F.Cu") (net 51))
  (arc (start 144.665 124.375) (mid 144.701612 124.286612) (end 144.79 124.25) (width 0.1) (layer "F.Cu") (net 51))
  (arc (start 136.578393 115.480185) (mid 136.664382 115.515803) (end 136.7 115.601792) (width 0.1) (layer "F.Cu") (net 51))
  (arc (start 136.456785 115.858578) (mid 136.492403 115.944567) (end 136.578392 115.980185) (width 0.1) (layer "F.Cu") (net 51))
  (arc (start 143.765 123.812742) (mid 143.801612 123.724354) (end 143.89 123.687742) (width 0.1) (layer "F.Cu") (net 51))
  (arc (start 136.578393 114.980185) (mid 136.664382 115.015803) (end 136.7 115.101792) (width 0.1) (layer "F.Cu") (net 51))
  (arc (start 144.34 124.812258) (mid 144.56981 124.717068) (end 144.665 124.487258) (width 0.1) (layer "F.Cu") (net 51))
  (arc (start 136.578393 115.980185) (mid 136.664382 116.015803) (end 136.7 116.101792) (width 0.1) (layer "F.Cu") (net 51))
  (arc (start 136.578392 114.730185) (mid 136.492403 114.765803) (end 136.456785 114.851792) (width 0.1) (layer "F.Cu") (net 51))
  (arc (start 136.7 115.108578) (mid 136.664382 115.194567) (end 136.578393 115.230185) (width 0.1) (layer "F.Cu") (net 51))
  (arc (start 136.456785 115.358578) (mid 136.492403 115.444567) (end 136.578392 115.480185) (width 0.1) (layer "F.Cu") (net 51))
  (arc (start 144.015 124.487258) (mid 144.11019 124.717068) (end 144.34 124.812258) (width 0.1) (layer "F.Cu") (net 51))
  (arc (start 136.578392 115.230185) (mid 136.492403 115.265803) (end 136.456785 115.351792) (width 0.1) (layer "F.Cu") (net 51))
  (arc (start 143.44 124.25) (mid 143.66981 124.15481) (end 143.765 123.925) (width 0.1) (layer "F.Cu") (net 51))
  (arc (start 143.89 123.687742) (mid 143.978388 123.724354) (end 144.015 123.812742) (width 0.1) (layer "F.Cu") (net 51))
  (segment (start 134.85 114.391422) (end 134.85 121.458578) (width 0.1) (layer "F.Cu") (net 52))
  (segment (start 150.25 129.199999) (end 150.25 130.1) (width 0.1) (layer "F.Cu") (net 52))
  (segment (start 142.406197 126.993802) (end 142.406197 127.093803) (width 0.1) (layer "F.Cu") (net 52))
  (segment (start 136.05 112.52) (end 136.05 112.550735) (width 0.1) (layer "F.Cu") (net 52))
  (segment locked (start 136.05 112.799265) (end 135.95 112.899265) (width 0.1) (layer "F.Cu") (net 52))
  (segment (start 141.962394 126.787605) (end 142.2 126.787605) (width 0.1) (layer "F.Cu") (net 52))
  (segment (start 135.95 112.42) (end 136.05 112.52) (width 0.1) (layer "F.Cu") (net 52))
  (segment locked (start 136.05 112.550735) (end 136.05 112.799265) (width 0.1) (layer "F.Cu") (net 52))
  (segment (start 134.85 121.458578) (end 140.491422 127.1) (width 0.1) (layer "F.Cu") (net 52))
  (segment (start 135.95 113.291422) (end 134.85 114.391422) (width 0.1) (layer "F.Cu") (net 52))
  (segment (start 135.95 112.225) (end 135.95 112.42) (width 0.1) (layer "F.Cu") (net 52))
  (segment (start 142.412394 127.1) (end 148.491422 127.1) (width 0.1) (layer "F.Cu") (net 52))
  (segment (start 135.75 112.025) (end 135.95 112.225) (width 0.1) (layer "F.Cu") (net 52))
  (segment (start 150.1 129.049999) (end 150.25 129.199999) (width 0.1) (layer "F.Cu") (net 52))
  (segment (start 141.756197 127.093803) (end 141.756197 126.993802) (width 0.1) (layer "F.Cu") (net 52))
  (segment (start 150.1 128.708578) (end 150.1 129.049999) (width 0.1) (layer "F.Cu") (net 52))
  (segment locked (start 135.95 112.899265) (end 135.95 113.291422) (width 0.1) (layer "F.Cu") (net 52))
  (segment (start 148.491422 127.1) (end 150.1 128.708578) (width 0.1) (layer "F.Cu") (net 52))
  (segment (start 140.491422 127.1) (end 141.75 127.1) (width 0.1) (layer "F.Cu") (net 52))
  (arc (start 141.75 127.1) (mid 141.754382 127.098185) (end 141.756197 127.093803) (width 0.1) (layer "F.Cu") (net 52))
  (arc (start 141.756197 126.993802) (mid 141.816591 126.847999) (end 141.962394 126.787605) (width 0.1) (layer "F.Cu") (net 52))
  (arc (start 142.406197 127.093803) (mid 142.408012 127.098185) (end 142.412394 127.1) (width 0.1) (layer "F.Cu") (net 52))
  (arc (start 142.2 126.787605) (mid 142.345803 126.847999) (end 142.406197 126.993802) (width 0.1) (layer "F.Cu") (net 52))
  (segment (start 134.65 115.508578) (end 134.65 121.541422) (width 0.1) (layer "F.Cu") (net 53))
  (segment (start 141.956197 127.093803) (end 141.956197 126.993802) (width 0.1) (layer "F.Cu") (net 53))
  (segment (start 149.75 129.199999) (end 149.75 130.1) (width 0.1) (layer "F.Cu") (net 53))
  (segment (start 140.408578 127.3) (end 141.75 127.3) (width 0.1) (layer "F.Cu") (net 53))
  (segment (start 135.196446 113.479288) (end 135.196445 113.479289) (width 0.1) (layer "F.Cu") (net 53))
  (segment (start 134.65 115.458578) (end 134.65 115.508578) (width 0.1) (layer "F.Cu") (net 53))
  (segment (start 141.962394 126.987605) (end 142.2 126.987605) (width 0.1) (layer "F.Cu") (net 53))
  (segment (start 134.4 115.158578) (end 134.4 115.208578) (width 0.1) (layer "F.Cu") (net 53))
  (segment (start 134.65 114.858578) (end 134.65 114.908578) (width 0.1) (layer "F.Cu") (net 53))
  (segment (start 134.65 121.541422) (end 140.408578 127.3) (width 0.1) (layer "F.Cu") (net 53))
  (segment (start 134.4 114.558578) (end 134.4 114.608578) (width 0.1) (layer "F.Cu") (net 53))
  (segment (start 149.9 129.049999) (end 149.75 129.199999) (width 0.1) (layer "F.Cu") (net 53))
  (segment (start 135.196445 113.479289) (end 135.125734 113.549999) (width 0.1) (layer "F.Cu") (net 53))
  (segment (start 142.206197 126.993802) (end 142.206197 127.093803) (width 0.1) (layer "F.Cu") (net 53))
  (segment (start 135.125734 113.832842) (end 134.65 114.308578) (width 0.1) (layer "F.Cu") (net 53))
  (segment (start 149.9 128.791422) (end 149.9 129.049999) (width 0.1) (layer "F.Cu") (net 53))
  (segment (start 135.75 112.675) (end 135.75 113.208578) (width 0.1) (layer "F.Cu") (net 53))
  (segment (start 148.408578 127.3) (end 149.9 128.791422) (width 0.1) (layer "F.Cu") (net 53))
  (segment (start 135.75 113.208578) (end 135.479289 113.479289) (width 0.1) (layer "F.Cu") (net 53))
  (segment (start 135.125733 113.832842) (end 135.125734 113.832842) (width 0.1) (layer "F.Cu") (net 53))
  (segment (start 142.412394 127.3) (end 148.408578 127.3) (width 0.1) (layer "F.Cu") (net 53))
  (arc (start 142.2 126.987605) (mid 142.204382 126.98942) (end 142.206197 126.993802) (width 0.1) (layer "F.Cu") (net 53))
  (arc (start 134.525 115.033578) (mid 134.436612 115.07019) (end 134.4 115.158578) (width 0.1) (layer "F.Cu") (net 53))
  (arc (start 134.65 114.308578) (mid 134.613388 114.396966) (end 134.525 114.433578) (width 0.1) (layer "F.Cu") (net 53))
  (arc (start 142.206197 127.093803) (mid 142.266591 127.239606) (end 142.412394 127.3) (width 0.1) (layer "F.Cu") (net 53))
  (arc (start 134.4 115.208578) (mid 134.436612 115.296966) (end 134.525 115.333578) (width 0.1) (layer "F.Cu") (net 53))
  (arc (start 134.4 114.608578) (mid 134.436612 114.696966) (end 134.525 114.733578) (width 0.1) (layer "F.Cu") (net 53))
  (arc (start 141.956197 126.993802) (mid 141.958012 126.98942) (end 141.962394 126.987605) (width 0.1) (layer "F.Cu") (net 53))
  (arc (start 135.337867 113.479289) (mid 135.267157 113.449999) (end 135.196446 113.479288) (width 0.1) (layer "F.Cu") (net 53))
  (arc (start 134.525 114.433578) (mid 134.436612 114.47019) (end 134.4 114.558578) (width 0.1) (layer "F.Cu") (net 53))
  (arc (start 134.65 114.908578) (mid 134.613388 114.996966) (end 134.525 115.033578) (width 0.1) (layer "F.Cu") (net 53))
  (arc (start 135.125734 113.691421) (mid 135.155023 113.762132) (end 135.125733 113.832842) (width 0.1) (layer "F.Cu") (net 53))
  (arc (start 134.525 115.333578) (mid 134.613388 115.37019) (end 134.65 115.458578) (width 0.1) (layer "F.Cu") (net 53))
  (arc (start 135.125734 113.549999) (mid 135.096445 113.62071) (end 135.125734 113.691421) (width 0.1) (layer "F.Cu") (net 53))
  (arc (start 134.525 114.733578) (mid 134.613388 114.77019) (end 134.65 114.858578) (width 0.1) (layer "F.Cu") (net 53))
  (arc (start 141.75 127.3) (mid 141.895803 127.239606) (end 141.956197 127.093803) (width 0.1) (layer "F.Cu") (net 53))
  (arc (start 135.479289 113.479289) (mid 135.408578 113.508578) (end 135.337867 113.479289) (width 0.1) (layer "F.Cu") (net 53))
  (segment (start 135.4 112.799265) (end 135.3 112.899265) (width 0.1) (layer "F.Cu") (net 54))
  (segment (start 135.3 112.225) (end 135.3 112.450735) (width 0.1) (layer "F.Cu") (net 54))
  (segment (start 135.3 112.899265) (end 135.3 113.041422) (width 0.1) (layer "F.Cu") (net 54))
  (segment (start 133.8 122.558578) (end 139.741422 128.5) (width 0.1) (layer "F.Cu") (net 54))
  (segment (start 133.8 114.541422) (end 133.8 122.558578) (width 0.1) (layer "F.Cu") (net 54))
  (segment (start 135.1 112.025) (end 135.3 112.225) (width 0.1) (layer "F.Cu") (net 54))
  (segment (start 135.4 112.550735) (end 135.4 112.799265) (width 0.1) (layer "F.Cu") (net 54))
  (segment (start 149.1 129.5) (end 149.25 129.65) (width 0.1) (layer "F.Cu") (net 54))
  (segment (start 148.341422 128.5) (end 149.1 129.258578) (width 0.1) (layer "F.Cu") (net 54))
  (segment (start 149.1 129.258578) (end 149.1 129.5) (width 0.1) (layer "F.Cu") (net 54))
  (segment (start 135.3 112.450735) (end 135.4 112.550735) (width 0.1) (layer "F.Cu") (net 54))
  (segment (start 135.3 113.041422) (end 133.8 114.541422) (width 0.1) (layer "F.Cu") (net 54))
  (segment (start 139.741422 128.5) (end 148.341422 128.5) (width 0.1) (layer "F.Cu") (net 54))
  (segment (start 134.055758 114.002817) (end 134.055759 114.002818) (width 0.1) (layer "F.Cu") (net 55))
  (segment (start 134.692156 113.154289) (end 134.669067 113.1312) (width 0.1) (layer "F.Cu") (net 55))
  (segment (start 134.692155 113.154289) (end 134.692156 113.154289) (width 0.1) (layer "F.Cu") (net 55))
  (segment (start 148.9 129.5) (end 148.75 129.65) (width 0.1) (layer "F.Cu") (net 55))
  (segment (start 134.456935 113.343332) (end 134.480023 113.36642) (width 0.1) (layer "F.Cu") (net 55))
  (segment (start 135.1 112.675) (end 135.1 112.958578) (width 0.1) (layer "F.Cu") (net 55))
  (segment (start 134.480024 113.578553) (end 134.480024 113.578554) (width 0.1) (layer "F.Cu") (net 55))
  (segment (start 135.1 112.958578) (end 134.904289 113.154289) (width 0.1) (layer "F.Cu") (net 55))
  (segment (start 148.258578 128.7) (end 148.9 129.341422) (width 0.1) (layer "F.Cu") (net 55))
  (segment (start 134.480023 113.578552) (end 134.480024 113.578553) (width 0.1) (layer "F.Cu") (net 55))
  (segment (start 133.6 122.641422) (end 139.658578 128.7) (width 0.1) (layer "F.Cu") (net 55))
  (segment (start 134.267891 113.578554) (end 134.244802 113.555465) (width 0.1) (layer "F.Cu") (net 55))
  (segment (start 133.6 114.458578) (end 133.6 122.641422) (width 0.1) (layer "F.Cu") (net 55))
  (segment (start 148.9 129.341422) (end 148.9 129.5) (width 0.1) (layer "F.Cu") (net 55))
  (segment (start 134.055759 114.002818) (end 133.6 114.458578) (width 0.1) (layer "F.Cu") (net 55))
  (segment (start 134.26789 113.578554) (end 134.267891 113.578554) (width 0.1) (layer "F.Cu") (net 55))
  (segment (start 139.658578 128.7) (end 148.258578 128.7) (width 0.1) (layer "F.Cu") (net 55))
  (segment (start 134.03267 113.767597) (end 134.055758 113.790685) (width 0.1) (layer "F.Cu") (net 55))
  (arc (start 134.055758 113.790685) (mid 134.099692 113.896751) (end 134.055758 114.002817) (width 0.1) (layer "F.Cu") (net 55))
  (arc (start 134.480024 113.578554) (mid 134.373957 113.622488) (end 134.26789 113.578554) (width 0.1) (layer "F.Cu") (net 55))
  (arc (start 134.456935 113.1312) (mid 134.413001 113.237266) (end 134.456935 113.343332) (width 0.1) (layer "F.Cu") (net 55))
  (arc (start 134.669067 113.1312) (mid 134.563001 113.087266) (end 134.456935 113.1312) (width 0.1) (layer "F.Cu") (net 55))
  (arc (start 134.904289 113.154289) (mid 134.798222 113.198223) (end 134.692155 113.154289) (width 0.1) (layer "F.Cu") (net 55))
  (arc (start 134.244802 113.555465) (mid 134.138736 113.511531) (end 134.03267 113.555465) (width 0.1) (layer "F.Cu") (net 55))
  (arc (start 134.480023 113.36642) (mid 134.523957 113.472486) (end 134.480023 113.578552) (width 0.1) (layer "F.Cu") (net 55))
  (arc (start 134.03267 113.555465) (mid 133.988736 113.661531) (end 134.03267 113.767597) (width 0.1) (layer "F.Cu") (net 55))
  (segment (start 136.7 112.799265) (end 136.6 112.899265) (width 0.1) (layer "F.Cu") (net 56))
  (segment (start 147.75 129.65) (end 147.6 129.5) (width 0.1) (layer "F.Cu") (net 56))
  (segment (start 135.9 114.591422) (end 135.9 120.858578) (width 0.1) (layer "F.Cu") (net 56))
  (segment (start 136.4 112.025) (end 136.6 112.225) (width 0.1) (layer "F.Cu") (net 56))
  (segment (start 143.540738 125.65) (end 143.55 125.65) (width 0.1) (layer "F.Cu") (net 56))
  (segment (start 140.691422 125.65) (end 142.35 125.65) (width 0.1) (layer "F.Cu") (net 56))
  (segment (start 147.24446 125.743948) (end 147.456592 125.743948) (width 0.1) (layer "F.Cu") (net 56))
  (segment (start 143.55 125.65) (end 147.150512 125.65) (width 0.1) (layer "F.Cu") (net 56))
  (segment (start 136.7 112.550735) (end 136.7 112.799265) (width 0.1) (layer "F.Cu") (net 56))
  (segment (start 135.9 120.858578) (end 140.691422 125.65) (width 0.1) (layer "F.Cu") (net 56))
  (segment (start 142.545369 125.454631) (end 142.545369 125.35463) (width 0.1) (layer "F.Cu") (net 56))
  (segment (start 147.150512 125.65) (end 147.24446 125.743948) (width 0.1) (layer "F.Cu") (net 56))
  (segment (start 136.6 112.899265) (end 136.6 113.891422) (width 0.1) (layer "F.Cu") (net 56))
  (segment (start 136.6 112.225) (end 136.6 112.450735) (width 0.1) (layer "F.Cu") (net 56))
  (segment (start 143.345369 125.35463) (end 143.345369 125.454631) (width 0.1) (layer "F.Cu") (net 56))
  (segment (start 142.940738 124.959261) (end 142.95 124.959261) (width 0.1) (layer "F.Cu") (net 56))
  (segment (start 136.6 112.450735) (end 136.7 112.550735) (width 0.1) (layer "F.Cu") (net 56))
  (segment (start 147.6 129.291987) (end 147.75 129.141987) (width 0.1) (layer "F.Cu") (net 56))
  (segment (start 147.6 129.5) (end 147.6 129.291987) (width 0.1) (layer "F.Cu") (net 56))
  (segment (start 136.6 113.891422) (end 135.9 114.591422) (width 0.1) (layer "F.Cu") (net 56))
  (via (at 147.456592 125.743948) (size 0.4) (drill 0.15) (layers "F.Cu" "B.Cu") (net 56))
  (via (at 147.75 129.141987) (size 0.4) (drill 0.15) (layers "F.Cu" "B.Cu") (net 56))
  (arc (start 142.35 125.65) (mid 142.488147 125.592778) (end 142.545369 125.454631) (width 0.1) (layer "F.Cu") (net 56))
  (arc (start 142.95 124.959261) (mid 143.229568 125.075062) (end 143.345369 125.35463) (width 0.1) (layer "F.Cu") (net 56))
  (arc (start 143.345369 125.454631) (mid 143.402591 125.592778) (end 143.540738 125.65) (width 0.1) (layer "F.Cu") (net 56))
  (arc (start 142.545369 125.35463) (mid 142.66117 125.075062) (end 142.940738 124.959261) (width 0.1) (layer "F.Cu") (net 56))
  (segment (start 147.6 126.099488) (end 147.6 128.991987) (width 0.1) (layer "B.Cu") (net 56))
  (segment (start 147.75 129.141987) (end 147.6 128.991987) (width 0.1) (layer "B.Cu") (net 56))
  (segment (start 147.456592 125.95608) (end 147.6 126.099488) (width 0.1) (layer "B.Cu") (net 56))
  (segment (start 147.456592 125.743948) (end 147.456592 125.95608) (width 0.1) (layer "B.Cu") (net 56))
  (segment (start 136.4 113.808578) (end 136.329289 113.879289) (width 0.1) (layer "F.Cu") (net 57))
  (segment (start 147.4 129.5) (end 147.4 129.291987) (width 0.1) (layer "F.Cu") (net 57))
  (segment (start 143.145369 125.35463) (end 143.145369 125.454631) (width 0.1) (layer "F.Cu") (net 57))
  (segment (start 140.608578 125.85) (end 142.35 125.85) (width 0.1) (layer "F.Cu") (net 57))
  (segment (start 135.7 115.501808) (end 135.7 115.508578) (width 0.1) (layer "F.Cu") (net 57))
  (segment (start 135.45677 114.751808) (end 135.45677 114.758578) (width 0.1) (layer "F.Cu") (net 57))
  (segment (start 135.7 120.941422) (end 140.608578 125.85) (width 0.1) (layer "F.Cu") (net 57))
  (segment (start 135.985309 113.879289) (end 135.980521 113.884076) (width 0.1) (layer "F.Cu") (net 57))
  (segment (start 147.25 129.65) (end 147.4 129.5) (width 0.1) (layer "F.Cu") (net 57))
  (segment (start 135.7 115.001808) (end 135.7 115.008578) (width 0.1) (layer "F.Cu") (net 57))
  (segment (start 143.540738 125.85) (end 143.55 125.85) (width 0.1) (layer "F.Cu") (net 57))
  (segment (start 135.98052 114.228054) (end 135.980521 114.228054) (width 0.1) (layer "F.Cu") (net 57))
  (segment (start 147.067668 125.85) (end 147.103038 125.88537) (width 0.1) (layer "F.Cu") (net 57))
  (segment (start 143.55 125.85) (end 147.067668 125.85) (width 0.1) (layer "F.Cu") (net 57))
  (segment (start 147.4 129.291987) (end 147.25 129.141987) (width 0.1) (layer "F.Cu") (net 57))
  (segment (start 135.980521 114.228054) (end 135.7 114.508578) (width 0.1) (layer "F.Cu") (net 57))
  (segment (start 136.4 112.675) (end 136.4 113.808578) (width 0.1) (layer "F.Cu") (net 57))
  (segment (start 135.45677 115.251808) (end 135.45677 115.258578) (width 0.1) (layer "F.Cu") (net 57))
  (segment (start 142.940738 125.159261) (end 142.95 125.159261) (width 0.1) (layer "F.Cu") (net 57))
  (segment (start 135.980522 114.056065) (end 135.980521 114.056065) (width 0.1) (layer "F.Cu") (net 57))
  (segment (start 135.7 115.508578) (end 135.7 120.941422) (width 0.1) (layer "F.Cu") (net 57))
  (segment (start 142.745369 125.454631) (end 142.745369 125.35463) (width 0.1) (layer "F.Cu") (net 57))
  (segment (start 135.98531 113.879288) (end 135.985309 113.879289) (width 0.1) (layer "F.Cu") (net 57))
  (segment (start 147.103038 125.88537) (end 147.103038 126.097502) (width 0.1) (layer "F.Cu") (net 57))
  (via (at 147.103038 126.097502) (size 0.4) (drill 0.15) (layers "F.Cu" "B.Cu") (net 57))
  (via (at 147.25 129.141987) (size 0.4) (drill 0.15) (layers "F.Cu" "B.Cu") (net 57))
  (arc (start 135.7 115.008578) (mid 135.66438 115.094573) (end 135.578385 115.130193) (width 0.1) (layer "F.Cu") (net 57))
  (arc (start 135.45677 114.758578) (mid 135.49239 114.844573) (end 135.578385 114.880193) (width 0.1) (layer "F.Cu") (net 57))
  (arc (start 142.95 125.159261) (mid 143.088147 125.216483) (end 143.145369 125.35463) (width 0.1) (layer "F.Cu") (net 57))
  (arc (start 142.35 125.85) (mid 142.629568 125.734199) (end 142.745369 125.454631) (width 0.1) (layer "F.Cu") (net 57))
  (arc (start 143.145369 125.454631) (mid 143.26117 125.734199) (end 143.540738 125.85) (width 0.1) (layer "F.Cu") (net 57))
  (arc (start 136.157299 113.879289) (mid 136.071305 113.843668) (end 135.98531 113.879288) (width 0.1) (layer "F.Cu") (net 57))
  (arc (start 136.329289 113.879289) (mid 136.243294 113.914909) (end 136.157299 113.879289) (width 0.1) (layer "F.Cu") (net 57))
  (arc (start 135.980521 113.884076) (mid 135.944901 113.970071) (end 135.980522 114.056065) (width 0.1) (layer "F.Cu") (net 57))
  (arc (start 135.578385 115.380193) (mid 135.66438 115.415813) (end 135.7 115.501808) (width 0.1) (layer "F.Cu") (net 57))
  (arc (start 135.578385 114.630193) (mid 135.49239 114.665813) (end 135.45677 114.751808) (width 0.1) (layer "F.Cu") (net 57))
  (arc (start 142.745369 125.35463) (mid 142.802591 125.216483) (end 142.940738 125.159261) (width 0.1) (layer "F.Cu") (net 57))
  (arc (start 135.578385 115.130193) (mid 135.49239 115.165813) (end 135.45677 115.251808) (width 0.1) (layer "F.Cu") (net 57))
  (arc (start 135.980521 114.056065) (mid 136.016141 114.14206) (end 135.98052 114.228054) (width 0.1) (layer "F.Cu") (net 57))
  (arc (start 135.578385 114.880193) (mid 135.66438 114.915813) (end 135.7 115.001808) (width 0.1) (layer "F.Cu") (net 57))
  (arc (start 135.7 114.508578) (mid 135.66438 114.594573) (end 135.578385 114.630193) (width 0.1) (layer "F.Cu") (net 57))
  (arc (start 135.45677 115.258578) (mid 135.49239 115.344573) (end 135.578385 115.380193) (width 0.1) (layer "F.Cu") (net 57))
  (segment (start 147.4 126.182332) (end 147.4 128.991987) (width 0.1) (layer "B.Cu") (net 57))
  (segment (start 147.31517 126.097502) (end 147.4 126.182332) (width 0.1) (layer "B.Cu") (net 57))
  (segment (start 147.103038 126.097502) (end 147.31517 126.097502) (width 0.1) (layer "B.Cu") (net 57))
  (segment (start 147.25 129.141987) (end 147.4 128.991987) (width 0.1) (layer "B.Cu") (net 57))
  (segment (start 157.8 110.12) (end 157.48 109.8) (width 0.1) (layer "F.Cu") (net 66))
  (segment (start 142.25 130.1) (end 142.25 129.200497) (width 0.1) (layer "F.Cu") (net 66))
  (segment (start 142.25 129.200497) (end 142.249503 129.2) (width 0.1) (layer "F.Cu") (net 66))
  (via (at 157.48 109.8) (size 0.4) (drill 0.15) (layers "F.Cu" "B.Cu") (net 66))
  (via (at 142.249503 129.2) (size 0.4) (drill 0.15) (layers "F.Cu" "B.Cu") (net 66))
  (segment (start 155.8 117.45) (end 156.65 116.6) (width 0.1) (layer "B.Cu") (net 66))
  (segment (start 156.65 116.6) (end 156.65 115.85) (width 0.1) (layer "B.Cu") (net 66))
  (segment (start 157.2 112.4) (end 157.2 110.08) (width 0.1) (layer "B.Cu") (net 66))
  (segment (start 157.55 114.95) (end 157.55 112.75) (width 0.1) (layer "B.Cu") (net 66))
  (segment (start 157.55 112.75) (end 157.2 112.4) (width 0.1) (layer "B.Cu") (net 66))
  (segment (start 142.249503 129.2) (end 142.249503 126.600497) (width 0.1) (layer "B.Cu") (net 66))
  (segment (start 157.2 110.08) (end 157.48 109.8) (width 0.1) (layer "B.Cu") (net 66))
  (segment (start 156.65 115.85) (end 157.55 114.95) (width 0.1) (layer "B.Cu") (net 66))
  (segment (start 151.4 117.45) (end 155.8 117.45) (width 0.1) (layer "B.Cu") (net 66))
  (segment (start 142.249503 126.600497) (end 151.4 117.45) (width 0.1) (layer "B.Cu") (net 66))
  (segment (start 157.125 110.125) (end 156.8 109.8) (width 0.1) (layer "F.Cu") (net 67))
  (segment (start 141.75 130.1) (end 141.75 129.2) (width 0.1) (layer "F.Cu") (net 67))
  (via (at 141.75 129.2) (size 0.4) (drill 0.15) (layers "F.Cu" "B.Cu") (net 67))
  (via (at 156.8 109.8) (size 0.4) (drill 0.15) (layers "F.Cu" "B.Cu") (net 67))
  (segment (start 156.3 115.75) (end 156.3 116.35) (width 0.1) (layer "B.Cu") (net 67))
  (segment (start 157.2 114.85) (end 156.3 115.75) (width 0.1) (layer "B.Cu") (net 67))
  (segment (start 156.8 109.8) (end 156.8 112.45) (width 0.1) (layer "B.Cu") (net 67))
  (segment (start 156.3 116.35) (end 155.55 117.1) (width 0.1) (layer "B.Cu") (net 67))
  (segment (start 156.8 112.45) (end 157.2 112.85) (width 0.1) (layer "B.Cu") (net 67))
  (segment (start 141.75 126.55) (end 141.75 129.2) (width 0.1) (layer "B.Cu") (net 67))
  (segment (start 155.55 117.1) (end 151.2 117.1) (width 0.1) (layer "B.Cu") (net 67))
  (segment (start 157.2 112.85) (end 157.2 114.85) (width 0.1) (layer "B.Cu") (net 67))
  (segment (start 151.2 117.1) (end 141.75 126.55) (width 0.1) (layer "B.Cu") (net 67))
  (segment (start 133.8 110.07) (end 133.48 109.75) (width 0.1) (layer "F.Cu") (net 68))
  (segment (start 141.25 130.1) (end 141.25 129.200497) (width 0.1) (layer "F.Cu") (net 68))
  (segment (start 141.25 129.200497) (end 141.249503 129.2) (width 0.1) (layer "F.Cu") (net 68))
  (via (at 141.249503 129.2) (size 0.4) (drill 0.15) (layers "F.Cu" "B.Cu") (net 68))
  (via (at 133.48 109.75) (size 0.4) (drill 0.15) (layers "F.Cu" "B.Cu") (net 68))
  (segment (start 133.6 120.85) (end 133.6 112.917158) (width 0.1) (layer "B.Cu") (net 68))
  (segment (start 133.6 112.917158) (end 133.2 112.517158) (width 0.1) (layer "B.Cu") (net 68))
  (segment (start 133.2 112.517158) (end 133.2 110.03) (width 0.1) (layer "B.Cu") (net 68))
  (segment (start 141.249503 129.2) (end 141.249503 128.499503) (width 0.1) (layer "B.Cu") (net 68))
  (segment (start 141.249503 128.499503) (end 133.6 120.85) (width 0.1) (layer "B.Cu") (net 68))
  (segment (start 133.2 110.03) (end 133.48 109.75) (width 0.1) (layer "B.Cu") (net 68))
  (segment (start 133.125 110.075) (end 132.8 109.75) (width 0.1) (layer "F.Cu") (net 69))
  (segment (start 140.75 130.1) (end 140.75 129.2) (width 0.1) (layer "F.Cu") (net 69))
  (via (at 132.8 109.75) (size 0.4) (drill 0.15) (layers "F.Cu" "B.Cu") (net 69))
  (via (at 140.75 129.2) (size 0.4) (drill 0.15) (layers "F.Cu" "B.Cu") (net 69))
  (segment (start 133.2 121.2) (end 140.75 128.75) (width 0.1) (layer "B.Cu") (net 69))
  (segment (start 132.8 109.75) (end 132.8 112.4) (width 0.1) (layer "B.Cu") (net 69))
  (segment (start 132.8 112.4) (end 133.2 112.8) (width 0.1) (layer "B.Cu") (net 69))
  (segment (start 140.75 128.75) (end 140.75 129.2) (width 0.1) (layer "B.Cu") (net 69))
  (segment (start 133.2 112.8) (end 133.2 121.2) (width 0.1) (layer "B.Cu") (net 69))
  (segment (start 133.813602 107.142156) (end 133.813601 107.142156) (width 0.1) (layer "F.Cu") (net 74))
  (segment (start 133.578351 106.95314) (end 133.601469 106.930023) (width 0.1) (layer "F.Cu") (net 74))
  (segment (start 132.9 105.75) (end 132.5 105.35) (width 0.1) (layer "F.Cu") (net 74))
  (segment (start 134.237867 107.566421) (end 134.237866 107.566421) (width 0.1) (layer "F.Cu") (net 74))
  (segment (start 132.5 103.55) (end 132.9 103.15) (width 0.1) (layer "F.Cu") (net 74))
  (segment (start 132.5 104.325) (end 132.5 103.55) (width 0.1) (layer "F.Cu") (net 74))
  (segment (start 134.025734 107.142156) (end 134.025735 107.142157) (width 0.1) (layer "F.Cu") (net 74))
  (segment (start 133.813601 107.142156) (end 133.790484 107.165274) (width 0.1) (layer "F.Cu") (net 74))
  (segment (start 134.237866 107.566421) (end 134.214749 107.589539) (width 0.1) (layer "F.Cu") (net 74))
  (segment (start 134.002616 107.377406) (end 134.002616 107.377405) (width 0.1) (layer "F.Cu") (net 74))
  (segment (start 132.5 105.35) (end 132.5 104.325) (width 0.1) (layer "F.Cu") (net 74))
  (segment (start 132.9 103.15) (end 132.9 101.1) (width 0.1) (layer "F.Cu") (net 74))
  (segment (start 133.601469 106.717891) (end 133.60147 106.717892) (width 0.1) (layer "F.Cu") (net 74))
  (segment (start 133.60147 106.717892) (end 132.9 106.016422) (width 0.1) (layer "F.Cu") (net 74))
  (segment (start 134.002616 107.377405) (end 134.025734 107.354288) (width 0.1) (layer "F.Cu") (net 74))
  (segment (start 134.45 108.125) (end 134.45 107.566422) (width 0.1) (layer "F.Cu") (net 74))
  (segment (start 132.9 101.1) (end 132.499999 100.699999) (width 0.1) (layer "F.Cu") (net 74))
  (segment (start 132.9 106.016422) (end 132.9 105.75) (width 0.1) (layer "F.Cu") (net 74))
  (segment (start 132.499999 100.699999) (end 132.499999 99.360004) (width 0.1) (layer "F.Cu") (net 74))
  (segment (start 133.578351 106.953141) (end 133.578351 106.95314) (width 0.1) (layer "F.Cu") (net 74))
  (arc (start 133.578352 107.165274) (mid 133.534416 107.059207) (end 133.578351 106.953141) (width 0.1) (layer "F.Cu") (net 74))
  (arc (start 134.214749 107.589539) (mid 134.108683 107.633473) (end 134.002617 107.589539) (width 0.1) (layer "F.Cu") (net 74))
  (arc (start 133.790484 107.165274) (mid 133.684418 107.209208) (end 133.578352 107.165274) (width 0.1) (layer "F.Cu") (net 74))
  (arc (start 134.45 107.566422) (mid 134.343933 107.522486) (end 134.237867 107.566421) (width 0.1) (layer "F.Cu") (net 74))
  (arc (start 133.601469 106.930023) (mid 133.645403 106.823957) (end 133.601469 106.717891) (width 0.1) (layer "F.Cu") (net 74))
  (arc (start 134.025735 107.142157) (mid 133.919668 107.098221) (end 133.813602 107.142156) (width 0.1) (layer "F.Cu") (net 74))
  (arc (start 134.002617 107.589539) (mid 133.958681 107.483472) (end 134.002616 107.377406) (width 0.1) (layer "F.Cu") (net 74))
  (arc (start 134.025734 107.354288) (mid 134.069668 107.248222) (end 134.025734 107.142156) (width 0.1) (layer "F.Cu") (net 74))
  (segment (start 134.75 108.000735) (end 134.65 107.900735) (width 0.1) (layer "F.Cu") (net 75))
  (segment (start 133.5 104.325) (end 133.5 103.55) (width 0.1) (layer "F.Cu") (net 75))
  (segment (start 133.1 105.933578) (end 133.1 105.75) (width 0.1) (layer "F.Cu") (net 75))
  (segment (start 133.1 101.1) (end 133.5 100.7) (width 0.1) (layer "F.Cu") (net 75))
  (segment (start 133.5 103.55) (end 133.1 103.15) (width 0.1) (layer "F.Cu") (net 75))
  (segment (start 134.45 108.775) (end 134.75 108.475) (width 0.1) (layer "F.Cu") (net 75))
  (segment (start 134.65 107.483578) (end 133.1 105.933578) (width 0.1) (layer "F.Cu") (net 75))
  (segment (start 134.75 108.475) (end 134.75 108.000735) (width 0.1) (layer "F.Cu") (net 75))
  (segment (start 133.5 100.7) (end 133.5 99.360004) (width 0.1) (layer "F.Cu") (net 75))
  (segment (start 133.5 105.35) (end 133.5 104.325) (width 0.1) (layer "F.Cu") (net 75))
  (segment (start 133.1 103.15) (end 133.1 101.1) (width 0.1) (layer "F.Cu") (net 75))
  (segment (start 133.1 105.75) (end 133.5 105.35) (width 0.1) (layer "F.Cu") (net 75))
  (segment (start 134.65 107.900735) (end 134.65 107.483578) (width 0.1) (layer "F.Cu") (net 75))
  (segment (start 134.4 101.105002) (end 134.000001 100.705003) (width 0.1) (layer "F.Cu") (net 76))
  (segment (start 134.000001 100.705003) (end 134.000001 99.360004) (width 0.1) (layer "F.Cu") (net 76))
  (segment (start 135.1 108.125) (end 135.1 107.9) (width 0.1) (layer "F.Cu") (net 76))
  (segment (start 134.777867 106.85) (end 134.95 106.85) (width 0.1) (layer "F.Cu") (net 76))
  (segment (start 134 103.55) (end 134.4 103.15) (width 0.1) (layer "F.Cu") (net 76))
  (segment (start 134.4 105.75) (end 134 105.35) (width 0.1) (layer "F.Cu") (net 76))
  (segment (start 135.1 106.641422) (end 134.4 105.941422) (width 0.1) (layer "F.Cu") (net 76))
  (segment (start 135.1 106.7) (end 135.1 106.65) (width 0.1) (layer "F.Cu") (net 76))
  (segment (start 134 105.35) (end 134 104.325) (width 0.1) (layer "F.Cu") (net 76))
  (segment (start 135.1 107.427868) (end 135.1 107.3) (width 0.1) (layer "F.Cu") (net 76))
  (segment (start 134.95 107.15) (end 134.777867 107.15) (width 0.1) (layer "F.Cu") (net 76))
  (segment (start 135.013934 107.813934) (end 135.013933 107.813934) (width 0.1) (layer "F.Cu") (net 76))
  (segment (start 134.927867 107.727868) (end 134.927867 107.6) (width 0.1) (layer "F.Cu") (net 76))
  (segment (start 135.013933 107.513934) (end 135.013934 107.513934) (width 0.1) (layer "F.Cu") (net 76))
  (segment (start 134 104.325) (end 134 103.55) (width 0.1) (layer "F.Cu") (net 76))
  (segment (start 135.1 106.65) (end 135.1 106.641422) (width 0.1) (layer "F.Cu") (net 76))
  (segment (start 134.4 103.15) (end 134.4 101.105002) (width 0.1) (layer "F.Cu") (net 76))
  (segment (start 134.4 105.941422) (end 134.4 105.75) (width 0.1) (layer "F.Cu") (net 76))
  (arc (start 135.1 107.9) (mid 135.074792 107.839142) (end 135.013934 107.813934) (width 0.1) (layer "F.Cu") (net 76))
  (arc (start 134.95 106.85) (mid 135.056066 106.806066) (end 135.1 106.7) (width 0.1) (layer "F.Cu") (net 76))
  (arc (start 135.1 107.3) (mid 135.056066 107.193934) (end 134.95 107.15) (width 0.1) (layer "F.Cu") (net 76))
  (arc (start 134.927867 107.6) (mid 134.953075 107.539142) (end 135.013933 107.513934) (width 0.1) (layer "F.Cu") (net 76))
  (arc (start 134.777867 107.15) (mid 134.671801 107.106066) (end 134.627867 107) (width 0.1) (layer "F.Cu") (net 76))
  (arc (start 135.013934 107.513934) (mid 135.074792 107.488726) (end 135.1 107.427868) (width 0.1) (layer "F.Cu") (net 76))
  (arc (start 135.013933 107.813934) (mid 134.953075 107.788726) (end 134.927867 107.727868) (width 0.1) (layer "F.Cu") (net 76))
  (arc (start 134.627867 107) (mid 134.671801 106.893934) (end 134.777867 106.85) (width 0.1) (layer "F.Cu") (net 76))
  (segment (start 135.4 108.000735) (end 135.3 107.900735) (width 0.1) (layer "F.Cu") (net 77))
  (segment (start 135.1 108.775) (end 135.4 108.475) (width 0.1) (layer "F.Cu") (net 77))
  (segment (start 134.6 105.858578) (end 134.6 105.74375) (width 0.1) (layer "F.Cu") (net 77))
  (segment (start 135 104.325) (end 135 103.553125) (width 0.1) (layer "F.Cu") (net 77))
  (segment (start 134.6 105.74375) (end 134.64375 105.7) (width 0.1) (layer "F.Cu") (net 77))
  (segment (start 134.64375 105.7) (end 134.644975 105.7) (width 0.1) (layer "F.Cu") (net 77))
  (segment (start 134.6 103.153125) (end 134.6 101.1) (width 0.1) (layer "F.Cu") (net 77))
  (segment (start 135.3 106.558578) (end 134.6 105.858578) (width 0.1) (layer "F.Cu") (net 77))
  (segment (start 134.644975 105.7) (end 135 105.344975) (width 0.1) (layer "F.Cu") (net 77))
  (segment (start 134.999999 100.700001) (end 134.999999 99.360004) (width 0.1) (layer "F.Cu") (net 77))
  (segment (start 135 105.344975) (end 135 104.325) (width 0.1) (layer "F.Cu") (net 77))
  (segment (start 135.3 107.900735) (end 135.3 106.558578) (width 0.1) (layer "F.Cu") (net 77))
  (segment (start 135.4 108.475) (end 135.4 108.000735) (width 0.1) (layer "F.Cu") (net 77))
  (segment (start 135 103.553125) (end 134.6 103.153125) (width 0.1) (layer "F.Cu") (net 77))
  (segment (start 134.6 101.1) (end 134.999999 100.700001) (width 0.1) (layer "F.Cu") (net 77))
  (segment (start 135.75 107.975) (end 135.9 107.825) (width 0.1) (layer "F.Cu") (net 78))
  (segment (start 135.9 106.75) (end 135.9 106.7) (width 0.1) (layer "F.Cu") (net 78))
  (segment (start 135.9 101.105002) (end 135.500001 100.705003) (width 0.1) (layer "F.Cu") (net 78))
  (segment (start 135.9 103.15) (end 135.9 101.105002) (width 0.1) (layer "F.Cu") (net 78))
  (segment (start 135.9 106.7) (end 135.9 105.756251) (width 0.1) (layer "F.Cu") (net 78))
  (segment (start 135.734487 106.875) (end 135.775 106.875) (width 0.1) (layer "F.Cu") (net 78))
  (segment (start 135.75 108.125) (end 135.75 107.975) (width 0.1) (layer "F.Cu") (net 78))
  (segment (start 135.734487 107.375) (end 135.775 107.375) (width 0.1) (layer "F.Cu") (net 78))
  (segment (start 135.9 105.756251) (end 135.5 105.356251) (width 0.1) (layer "F.Cu") (net 78))
  (segment (start 135.5 104.325) (end 135.5 103.55) (width 0.1) (layer "F.Cu") (net 78))
  (segment (start 135.9 107.825) (end 135.9 107.75) (width 0.1) (layer "F.Cu") (net 78))
  (segment (start 135.775 107.625) (end 135.734487 107.625) (width 0.1) (layer "F.Cu") (net 78))
  (segment (start 135.5 103.55) (end 135.9 103.15) (width 0.1) (layer "F.Cu") (net 78))
  (segment (start 135.500001 100.705003) (end 135.500001 99.360004) (width 0.1) (layer "F.Cu") (net 78))
  (segment (start 135.5 105.356251) (end 135.5 104.325) (width 0.1) (layer "F.Cu") (net 78))
  (segment (start 135.775 107.125) (end 135.734487 107.125) (width 0.1) (layer "F.Cu") (net 78))
  (arc (start 135.734487 107.625) (mid 135.646099 107.588388) (end 135.609487 107.5) (width 0.1) (layer "F.Cu") (net 78))
  (arc (start 135.609487 107) (mid 135.646099 106.911612) (end 135.734487 106.875) (width 0.1) (layer "F.Cu") (net 78))
  (arc (start 135.775 107.375) (mid 135.863388 107.338388) (end 135.9 107.25) (width 0.1) (layer "F.Cu") (net 78))
  (arc (start 135.9 107.75) (mid 135.863388 107.661612) (end 135.775 107.625) (width 0.1) (layer "F.Cu") (net 78))
  (arc (start 135.609487 107.5) (mid 135.646099 107.411612) (end 135.734487 107.375) (width 0.1) (layer "F.Cu") (net 78))
  (arc (start 135.734487 107.125) (mid 135.646099 107.088388) (end 135.609487 107) (width 0.1) (layer "F.Cu") (net 78))
  (arc (start 135.9 107.25) (mid 135.863388 107.161612) (end 135.775 107.125) (width 0.1) (layer "F.Cu") (net 78))
  (arc (start 135.775 106.875) (mid 135.863388 106.838388) (end 135.9 106.75) (width 0.1) (layer "F.Cu") (net 78))
  (segment (start 136.1 108.23) (end 136.09 108.22) (width 0.1) (layer "F.Cu") (net 79))
  (segment (start 136.5 103.55) (end 136.1 103.15) (width 0.1) (layer "F.Cu") (net 79))
  (segment (start 136.1 108.425) (end 136.1 108.23) (width 0.1) (layer "F.Cu") (net 79))
  (segment (start 135.75 108.775) (end 136.1 108.425) (width 0.1) (layer "F.Cu") (net 79))
  (segment (start 136.500001 100.699999) (end 136.500001 99.360004) (width 0.1) (layer "F.Cu") (net 79))
  (segment (start 136.1 107.999735) (end 136.1 105.75) (width 0.1) (layer "F.Cu") (net 79))
  (segment (start 136.5 105.35) (end 136.5 103.55) (width 0.1) (layer "F.Cu") (net 79))
  (segment (start 136.1 105.75) (end 136.5 105.35) (width 0.1) (layer "F.Cu") (net 79))
  (segment (start 136.1 103.15) (end 136.1 101.1) (width 0.1) (layer "F.Cu") (net 79))
  (segment (start 136.1 101.1) (end 136.500001 100.699999) (width 0.1) (layer "F.Cu") (net 79))
  (segment (start 136.09 108.009735) (end 136.1 107.999735) (width 0.1) (layer "F.Cu") (net 79))
  (segment (start 136.09 108.22) (end 136.09 108.009735) (width 0.1) (layer "F.Cu") (net 79))
  (segment (start 137.4 101.1) (end 137 100.7) (width 0.1) (layer "F.Cu") (net 80))
  (segment (start 137.315321 106.768258) (end 137.4 106.683578) (width 0.1) (layer "F.Cu") (net 80))
  (segment (start 137.315322 106.768259) (end 137.315321 106.768258) (width 0.1) (layer "F.Cu") (net 80))
  (segment (start 136.4 107.683578) (end 136.466789 107.616789) (width 0.1) (layer "F.Cu") (net 80))
  (segment (start 137.4 106.683578) (end 137.4 105.75) (width 0.1) (layer "F.Cu") (net 80))
  (segment (start 137.4 105.75) (end 137 105.35) (width 0.1) (layer "F.Cu") (net 80))
  (segment (start 137 105.35) (end 137 104.325) (width 0.1) (layer "F.Cu") (net 80))
  (segment (start 137.080072 106.745142) (end 137.080072 106.745141) (width 0.1) (layer "F.Cu") (net 80))
  (segment (start 137 104.325) (end 137 103.546874) (width 0.1) (layer "F.Cu") (net 80))
  (segment (start 136.891055 106.980391) (end 136.867938 106.957274) (width 0.1) (layer "F.Cu") (net 80))
  (segment (start 136.4 108.125) (end 136.4 107.683578) (width 0.1) (layer "F.Cu") (net 80))
  (segment (start 136.655806 107.169407) (end 136.678924 107.192525) (width 0.1) (layer "F.Cu") (net 80))
  (segment (start 136.655806 107.169408) (end 136.655806 107.169407) (width 0.1) (layer "F.Cu") (net 80))
  (segment (start 137 100.7) (end 137 99.360004) (width 0.1) (layer "F.Cu") (net 80))
  (segment (start 137.080072 106.745141) (end 137.10319 106.768259) (width 0.1) (layer "F.Cu") (net 80))
  (segment (start 137.4 103.146874) (end 137.4 101.1) (width 0.1) (layer "F.Cu") (net 80))
  (segment (start 136.891056 107.192525) (end 136.891055 107.192524) (width 0.1) (layer "F.Cu") (net 80))
  (segment (start 137 103.546874) (end 137.4 103.146874) (width 0.1) (layer "F.Cu") (net 80))
  (segment (start 136.891055 107.192524) (end 136.891055 107.192523) (width 0.1) (layer "F.Cu") (net 80))
  (segment (start 136.466789 107.404657) (end 136.443672 107.38154) (width 0.1) (layer "F.Cu") (net 80))
  (arc (start 136.443672 107.38154) (mid 136.399738 107.275474) (end 136.443672 107.169408) (width 0.1) (layer "F.Cu") (net 80))
  (arc (start 136.678924 107.192525) (mid 136.78499 107.236459) (end 136.891056 107.192525) (width 0.1) (layer "F.Cu") (net 80))
  (arc (start 136.443672 107.169408) (mid 136.54974 107.125473) (end 136.655806 107.169408) (width 0.1) (layer "F.Cu") (net 80))
  (arc (start 137.10319 106.768259) (mid 137.209256 106.812193) (end 137.315322 106.768259) (width 0.1) (layer "F.Cu") (net 80))
  (arc (start 136.466789 107.616789) (mid 136.510723 107.510723) (end 136.466789 107.404657) (width 0.1) (layer "F.Cu") (net 80))
  (arc (start 136.867938 106.745142) (mid 136.974006 106.701207) (end 137.080072 106.745142) (width 0.1) (layer "F.Cu") (net 80))
  (arc (start 136.867938 106.957274) (mid 136.824004 106.851208) (end 136.867938 106.745142) (width 0.1) (layer "F.Cu") (net 80))
  (arc (start 136.891055 107.192523) (mid 136.934989 107.086457) (end 136.891055 106.980391) (width 0.1) (layer "F.Cu") (net 80))
  (segment (start 137.6 105.75) (end 138 105.35) (width 0.1) (layer "F.Cu") (net 81))
  (segment (start 136.6 107.900735) (end 136.6 107.766422) (width 0.1) (layer "F.Cu") (net 81))
  (segment (start 137.6 101.1) (end 138.000001 100.699999) (width 0.1) (layer "F.Cu") (net 81))
  (segment (start 137.6 103.15) (end 137.6 101.1) (width 0.1) (layer "F.Cu") (net 81))
  (segment (start 136.7 108.475) (end 136.7 108.000735) (width 0.1) (layer "F.Cu") (net 81))
  (segment (start 136.7 108.000735) (end 136.6 107.900735) (width 0.1) (layer "F.Cu") (net 81))
  (segment (start 136.4 108.775) (end 136.7 108.475) (width 0.1) (layer "F.Cu") (net 81))
  (segment (start 138 104.325) (end 138 103.55) (width 0.1) (layer "F.Cu") (net 81))
  (segment (start 138 103.55) (end 137.6 103.15) (width 0.1) (layer "F.Cu") (net 81))
  (segment (start 138 105.35) (end 138 104.325) (width 0.1) (layer "F.Cu") (net 81))
  (segment (start 137.6 106.766422) (end 137.6 105.75) (width 0.1) (layer "F.Cu") (net 81))
  (segment (start 138.000001 100.699999) (end 138.000001 99.360004) (width 0.1) (layer "F.Cu") (net 81))
  (segment (start 136.6 107.766422) (end 137.6 106.766422) (width 0.1) (layer "F.Cu") (net 81))
  (segment (start 133.3 107.174528) (end 133.8 107.674528) (width 0.1) (layer "F.Cu") (net 82))
  (segment (start 133.3 107.0505) (end 133.3 107.174528) (width 0.1) (layer "F.Cu") (net 82))
  (segment (start 138.5 99.360004) (end 138.5 101) (width 0.1) (layer "F.Cu") (net 82))
  (segment (start 133.8 107.674528) (end 133.8 108.125) (width 0.1) (layer "F.Cu") (net 82))
  (segment (start 132.9 106.6505) (end 133.3 107.0505) (width 0.1) (layer "F.Cu") (net 82))
  (via (at 138.5 101) (size 0.4) (drill 0.15) (layers "F.Cu" "B.Cu") (net 82))
  (via (at 132.9 106.6505) (size 0.4) (drill 0.15) (layers "F.Cu" "B.Cu") (net 82))
  (segment (start 132.9 106.6505) (end 133.659672 105.890828) (width 0.1) (layer "B.Cu") (net 82))
  (segment (start 133.659672 105.890828) (end 133.659672 103.040328) (width 0.1) (layer "B.Cu") (net 82))
  (segment (start 135.6 101.1) (end 138.255025 101.1) (width 0.1) (layer "B.Cu") (net 82))
  (segment (start 133.659672 103.040328) (end 135.6 101.1) (width 0.1) (layer "B.Cu") (net 82))
  (segment (start 138.355025 101) (end 138.5 101) (width 0.1) (layer "B.Cu") (net 82))
  (segment (start 138.255025 101.1) (end 138.355025 101) (width 0.1) (layer "B.Cu") (net 82))
  (segment (start 139.9 101.45) (end 140.9 101.45) (width 0.1) (layer "F.Cu") (net 84))
  (segment (start 141.35 101.9) (end 141.35 102.3875) (width 0.1) (layer "F.Cu") (net 84))
  (segment (start 139.500001 101.050001) (end 139.9 101.45) (width 0.1) (layer "F.Cu") (net 84))
  (segment (start 139.4 101.95) (end 139.9 101.45) (width 0.1) (layer "F.Cu") (net 84))
  (segment (start 139.500001 99.360004) (end 139.500001 101.050001) (width 0.1) (layer "F.Cu") (net 84))
  (segment (start 140.9 101.45) (end 141.35 101.9) (width 0.1) (layer "F.Cu") (net 84))
  (segment (start 140 100.9) (end 140 99.360004) (width 0.1) (layer "F.Cu") (net 85))
  (segment (start 140.25 101.15) (end 140 100.9) (width 0.1) (layer "F.Cu") (net 85))
  (segment (start 141.85 101.9) (end 141.1 101.15) (width 0.1) (layer "F.Cu") (net 85))
  (segment (start 141.1 101.15) (end 140.25 101.15) (width 0.1) (layer "F.Cu") (net 85))
  (segment (start 142.125 102.85) (end 142.45 102.85) (width 0.1) (layer "F.Cu") (net 85))
  (segment (start 142.45 102.85) (end 143.385 103.785) (width 0.1) (layer "F.Cu") (net 85))
  (segment (start 143.385 103.785) (end 143.385 104.59) (width 0.1) (layer "F.Cu") (net 85))
  (segment (start 141.85 102.3875) (end 141.85 101.9) (width 0.1) (layer "F.Cu") (net 85))
  (segment (start 141.85 102.575) (end 142.125 102.85) (width 0.1) (layer "F.Cu") (net 85))
  (segment (start 141 99.360004) (end 141 100.65) (width 0.1) (layer "F.Cu") (net 86))
  (segment (start 144.2 103.35) (end 144.2 101.85) (width 0.1) (layer "F.Cu") (net 86))
  (segment (start 141 100.65) (end 141.8 101.45) (width 0.1) (layer "F.Cu") (net 86))
  (segment (start 143.8 101.45) (end 144.2 101.85) (width 0.1) (layer "F.Cu") (net 86))
  (segment (start 141.8 101.45) (end 143.8 101.45) (width 0.1) (layer "F.Cu") (net 86))
  (segment (start 141.500002 100.650002) (end 141.95 101.1) (width 0.1) (layer "F.Cu") (net 87))
  (segment (start 141.500002 99.360004) (end 141.500002 100.650002) (width 0.1) (layer "F.Cu") (net 87))
  (segment (start 144.85 101.1) (end 145.6 101.85) (width 0.1) (layer "F.Cu") (net 87))
  (segment (start 141.95 101.1) (end 144.85 101.1) (width 0.1) (layer "F.Cu") (net 87))
  (segment (start 156.5 103.6) (end 156.9 103.2) (width 0.1) (layer "F.Cu") (net 88))
  (segment (start 156.5 105.4) (end 156.5 104.375) (width 0.1) (layer "F.Cu") (net 88))
  (segment (start 156.9 106.066422) (end 156.9 105.8) (width 0.1) (layer "F.Cu") (net 88))
  (segment (start 156.9 101.15) (end 156.499999 100.749999) (width 0.1) (layer "F.Cu") (net 88))
  (segment (start 157.60147 106.767892) (end 156.9 106.066422) (width 0.1) (layer "F.Cu") (net 88))
  (segment (start 156.9 103.2) (end 156.9 101.15) (width 0.1) (layer "F.Cu") (net 88))
  (segment (start 158.45 108.175) (end 158.45 107.616422) (width 0.1) (layer "F.Cu") (net 88))
  (segment (start 157.601469 106.767891) (end 157.60147 106.767892) (width 0.1) (layer "F.Cu") (net 88))
  (segment (start 158.237867 107.616421) (end 158.237866 107.616421) (width 0.1) (layer "F.Cu") (net 88))
  (segment (start 158.002616 107.427406) (end 158.002616 107.427405) (width 0.1) (layer "F.Cu") (net 88))
  (segment (start 158.237866 107.616421) (end 158.214749 107.639539) (width 0.1) (layer "F.Cu") (net 88))
  (segment (start 158.002616 107.427405) (end 158.025734 107.404288) (width 0.1) (layer "F.Cu") (net 88))
  (segment (start 156.499999 100.749999) (end 156.499999 99.410004) (width 0.1) (layer "F.Cu") (net 88))
  (segment (start 157.813601 107.192156) (end 157.790484 107.215274) (width 0.1) (layer "F.Cu") (net 88))
  (segment (start 157.578351 107.003141) (end 157.578351 107.00314) (width 0.1) (layer "F.Cu") (net 88))
  (segment (start 157.578351 107.00314) (end 157.601469 106.980023) (width 0.1) (layer "F.Cu") (net 88))
  (segment (start 157.813602 107.192156) (end 157.813601 107.192156) (width 0.1) (layer "F.Cu") (net 88))
  (segment (start 156.5 104.375) (end 156.5 103.6) (width 0.1) (layer "F.Cu") (net 88))
  (segment (start 156.9 105.8) (end 156.5 105.4) (width 0.1) (layer "F.Cu") (net 88))
  (segment (start 158.025734 107.192156) (end 158.025735 107.192157) (width 0.1) (layer "F.Cu") (net 88))
  (arc (start 158.214749 107.639539) (mid 158.108683 107.683473) (end 158.002617 107.639539) (width 0.1) (layer "F.Cu") (net 88))
  (arc (start 158.025734 107.404288) (mid 158.069668 107.298222) (end 158.025734 107.192156) (width 0.1) (layer "F.Cu") (net 88))
  (arc (start 158.002617 107.639539) (mid 157.958681 107.533472) (end 158.002616 107.427406) (width 0.1) (layer "F.Cu") (net 88))
  (arc (start 157.790484 107.215274) (mid 157.684418 107.259208) (end 157.578352 107.215274) (width 0.1) (layer "F.Cu") (net 88))
  (arc (start 158.025735 107.192157) (mid 157.919668 107.148221) (end 157.813602 107.192156) (width 0.1) (layer "F.Cu") (net 88))
  (arc (start 157.601469 106.980023) (mid 157.645403 106.873957) (end 157.601469 106.767891) (width 0.1) (layer "F.Cu") (net 88))
  (arc (start 157.578352 107.215274) (mid 157.534416 107.109207) (end 157.578351 107.003141) (width 0.1) (layer "F.Cu") (net 88))
  (arc (start 158.45 107.616422) (mid 158.343933 107.572486) (end 158.237867 107.616421) (width 0.1) (layer "F.Cu") (net 88))
  (segment (start 157.5 103.6) (end 157.1 103.2) (width 0.1) (layer "F.Cu") (net 89))
  (segment (start 158.67 107.553578) (end 157.1 105.983578) (width 0.1) (layer "F.Cu") (net 89))
  (segment (start 157.1 101.15) (end 157.5 100.75) (width 0.1) (layer "F.Cu") (net 89))
  (segment (start 158.45 108.825) (end 158.75 108.525) (width 0.1) (layer "F.Cu") (net 89))
  (segment (start 158.67 107.92) (end 158.67 107.553578) (width 0.1) (layer "F.Cu") (net 89))
  (segment (start 158.75 108.300265) (end 158.751 108.299265) (width 0.1) (layer "F.Cu") (net 89))
  (segment (start 158.751 108.001) (end 158.67 107.92) (width 0.1) (layer "F.Cu") (net 89))
  (segment (start 157.5 105.4) (end 157.5 103.6) (width 0.1) (layer "F.Cu") (net 89))
  (segment (start 158.751 108.299265) (end 158.751 108.001) (width 0.1) (layer "F.Cu") (net 89))
  (segment (start 157.1 105.983578) (end 157.1 105.8) (width 0.1) (layer "F.Cu") (net 89))
  (segment (start 157.5 100.75) (end 157.5 99.410004) (width 0.1) (layer "F.Cu") (net 89))
  (segment (start 157.1 103.2) (end 157.1 101.15) (width 0.1) (layer "F.Cu") (net 89))
  (segment (start 157.1 105.8) (end 157.5 105.4) (width 0.1) (layer "F.Cu") (net 89))
  (segment (start 158.75 108.525) (end 158.75 108.300265) (width 0.1) (layer "F.Cu") (net 89))
  (segment (start 158.000001 100.755003) (end 158.000001 99.410004) (width 0.1) (layer "F.Cu") (net 90))
  (segment (start 159.1 106.75) (end 159.1 106.7) (width 0.1) (layer "F.Cu") (net 90))
  (segment (start 158.777867 106.9) (end 158.95 106.9) (width 0.1) (layer "F.Cu") (net 90))
  (segment (start 158.4 105.991422) (end 158.4 105.8) (width 0.1) (layer "F.Cu") (net 90))
  (segment (start 159.1 106.7) (end 159.1 106.691422) (width 0.1) (layer "F.Cu") (net 90))
  (segment (start 158.4 105.8) (end 158 105.4) (width 0.1) (layer "F.Cu") (net 90))
  (segment (start 158 104.375) (end 158 103.6) (width 0.1) (layer "F.Cu") (net 90))
  (segment (start 159.1 108.175) (end 159.1 107.95) (width 0.1) (layer "F.Cu") (net 90))
  (segment (start 158.4 103.2) (end 158.4 101.155002) (width 0.1) (layer "F.Cu") (net 90))
  (segment (start 158.927867 107.777868) (end 158.927867 107.65) (width 0.1) (layer "F.Cu") (net 90))
  (segment (start 158 103.6) (end 158.4 103.2) (width 0.1) (layer "F.Cu") (net 90))
  (segment (start 159.1 107.477868) (end 159.1 107.35) (width 0.1) (layer "F.Cu") (net 90))
  (segment (start 159.1 106.691422) (end 158.4 105.991422) (width 0.1) (layer "F.Cu") (net 90))
  (segment (start 159.013934 107.863934) (end 159.013933 107.863934) (width 0.1) (layer "F.Cu") (net 90))
  (segment (start 158.4 101.155002) (end 158.000001 100.755003) (width 0.1) (layer "F.Cu") (net 90))
  (segment (start 158 105.4) (end 158 104.375) (width 0.1) (layer "F.Cu") (net 90))
  (segment (start 159.013933 107.563934) (end 159.013934 107.563934) (width 0.1) (layer "F.Cu") (net 90))
  (segment (start 158.95 107.2) (end 158.777867 107.2) (width 0.1) (layer "F.Cu") (net 90))
  (arc (start 158.627867 107.05) (mid 158.671801 106.943934) (end 158.777867 106.9) (width 0.1) (layer "F.Cu") (net 90))
  (arc (start 159.1 107.35) (mid 159.056066 107.243934) (end 158.95 107.2) (width 0.1) (layer "F.Cu") (net 90))
  (arc (start 159.1 107.95) (mid 159.074792 107.889142) (end 159.013934 107.863934) (width 0.1) (layer "F.Cu") (net 90))
  (arc (start 159.013933 107.863934) (mid 158.953075 107.838726) (end 158.927867 107.777868) (width 0.1) (layer "F.Cu") (net 90))
  (arc (start 158.927867 107.65) (mid 158.953075 107.589142) (end 159.013933 107.563934) (width 0.1) (layer "F.Cu") (net 90))
  (arc (start 158.95 106.9) (mid 159.056066 106.856066) (end 159.1 106.75) (width 0.1) (layer "F.Cu") (net 90))
  (arc (start 159.013934 107.563934) (mid 159.074792 107.538726) (end 159.1 107.477868) (width 0.1) (layer "F.Cu") (net 90))
  (arc (start 158.777867 107.2) (mid 158.671801 107.156066) (end 158.627867 107.05) (width 0.1) (layer "F.Cu") (net 90))
  (segment (start 159.4 108.050735) (end 159.3 107.950735) (width 0.1) (layer "F.Cu") (net 91))
  (segment (start 158.999999 100.750001) (end 158.999999 99.410004) (width 0.1) (layer "F.Cu") (net 91))
  (segment (start 159 105.394975) (end 159 104.375) (width 0.1) (layer "F.Cu") (net 91))
  (segment (start 159.3 107.950735) (end 159.3 106.608578) (width 0.1) (layer "F.Cu") (net 91))
  (segment (start 158.64375 105.75) (end 158.644975 105.75) (width 0.1) (layer "F.Cu") (net 91))
  (segment (start 158.6 101.15) (end 158.999999 100.750001) (width 0.1) (layer "F.Cu") (net 91))
  (segment (start 158.6 105.79375) (end 158.64375 105.75) (width 0.1) (layer "F.Cu") (net 91))
  (segment (start 159 103.603125) (end 158.6 103.203125) (width 0.1) (layer "F.Cu") (net 91))
  (segment (start 159.1 108.825) (end 159.4 108.525) (width 0.1) (layer "F.Cu") (net 91))
  (segment (start 158.644975 105.75) (end 159 105.394975) (width 0.1) (layer "F.Cu") (net 91))
  (segment (start 159 104.375) (end 159 103.603125) (width 0.1) (layer "F.Cu") (net 91))
  (segment (start 159.4 108.525) (end 159.4 108.050735) (width 0.1) (layer "F.Cu") (net 91))
  (segment (start 159.3 106.608578) (end 158.6 105.908578) (width 0.1) (layer "F.Cu") (net 91))
  (segment (start 158.6 105.908578) (end 158.6 105.79375) (width 0.1) (layer "F.Cu") (net 91))
  (segment (start 158.6 103.203125) (end 158.6 101.15) (width 0.1) (layer "F.Cu") (net 91))
  (segment (start 159.9 106.8) (end 159.9 106.75) (width 0.1) (layer "F.Cu") (net 92))
  (segment (start 159.5 104.375) (end 159.5 103.6) (width 0.1) (layer "F.Cu") (net 92))
  (segment (start 159.775 107.175) (end 159.734487 107.175) (width 0.1) (layer "F.Cu") (net 92))
  (segment (start 159.9 107.875) (end 159.9 107.8) (width 0.1) (layer "F.Cu") (net 92))
  (segment (start 159.734487 107.425) (end 159.775 107.425) (width 0.1) (layer "F.Cu") (net 92))
  (segment (start 159.9 103.2) (end 159.9 101.155002) (width 0.1) (layer "F.Cu") (net 92))
  (segment (start 159.75 108.175) (end 159.75 108.025) (width 0.1) (layer "F.Cu") (net 92))
  (segment (start 159.9 106.75) (end 159.9 105.806251) (width 0.1) (layer "F.Cu") (net 92))
  (segment (start 159.9 101.155002) (end 159.500001 100.755003) (width 0.1) (layer "F.Cu") (net 92))
  (segment (start 159.5 103.6) (end 159.9 103.2) (width 0.1) (layer "F.Cu") (net 92))
  (segment (start 159.5 105.406251) (end 159.5 104.375) (width 0.1) (layer "F.Cu") (net 92))
  (segment (start 159.775 107.675) (end 159.734487 107.675) (width 0.1) (layer "F.Cu") (net 92))
  (segment (start 159.734487 106.925) (end 159.775 106.925) (width 0.1) (layer "F.Cu") (net 92))
  (segment (start 159.75 108.025) (end 159.9 107.875) (width 0.1) (layer "F.Cu") (net 92))
  (segment (start 159.9 105.806251) (end 159.5 105.406251) (width 0.1) (layer "F.Cu") (net 92))
  (segment (start 159.500001 100.755003) (end 159.500001 99.410004) (width 0.1) (layer "F.Cu") (net 92))
  (arc (start 159.734487 107.175) (mid 159.646099 107.138388) (end 159.609487 107.05) (width 0.1) (layer "F.Cu") (net 92))
  (arc (start 159.9 107.8) (mid 159.863388 107.711612) (end 159.775 107.675) (width 0.1) (layer "F.Cu") (net 92))
  (arc (start 159.775 107.425) (mid 159.863388 107.388388) (end 159.9 107.3) (width 0.1) (layer "F.Cu") (net 92))
  (arc (start 159.609487 107.55) (mid 159.646099 107.461612) (end 159.734487 107.425) (width 0.1) (layer "F.Cu") (net 92))
  (arc (start 159.9 107.3) (mid 159.863388 107.211612) (end 159.775 107.175) (width 0.1) (layer "F.Cu") (net 92))
  (arc (start 159.609487 107.05) (mid 159.646099 106.961612) (end 159.734487 106.925) (width 0.1) (layer "F.Cu") (net 92))
  (arc (start 159.734487 107.675) (mid 159.646099 107.638388) (end 159.609487 107.55) (width 0.1) (layer "F.Cu") (net 92))
  (arc (start 159.775 106.925) (mid 159.863388 106.888388) (end 159.9 106.8) (width 0.1) (layer "F.Cu") (net 92))
  (segment (start 160.1 105.8) (end 160.5 105.4) (width 0.1) (layer "F.Cu") (net 93))
  (segment (start 160.1 108.475) (end 160.1 105.8) (width 0.1) (layer "F.Cu") (net 93))
  (segment (start 160.1 101.15) (end 160.500001 100.749999) (width 0.1) (layer "F.Cu") (net 93))
  (segment (start 160.5 103.6) (end 160.1 103.2) (width 0.1) (layer "F.Cu") (net 93))
  (segment (start 160.5 104.375) (end 160.5 103.6) (width 0.1) (layer "F.Cu") (net 93))
  (segment (start 160.500001 100.749999) (end 160.500001 99.410004) (width 0.1) (layer "F.Cu") (net 93))
  (segment (start 160.1 103.2) (end 160.1 101.15) (width 0.1) (layer "F.Cu") (net 93))
  (segment (start 160.5 105.4) (end 160.5 104.375) (width 0.1) (layer "F.Cu") (net 93))
  (segment (start 159.75 108.825) (end 160.1 108.475) (width 0.1) (layer "F.Cu") (net 93))
  (segment (start 161.4 106.733578) (end 161.4 105.8) (width 0.1) (layer "F.Cu") (net 94))
  (segment (start 160.466789 107.454657) (end 160.443672 107.43154) (width 0.1) (layer "F.Cu") (net 94))
  (segment (start 161 100.75) (end 161 99.410004) (width 0.1) (layer "F.Cu") (net 94))
  (segment (start 161.080072 106.795141) (end 161.10319 106.818259) (width 0.1) (layer "F.Cu") (net 94))
  (segment (start 161.4 103.196874) (end 161.4 101.15) (width 0.1) (layer "F.Cu") (net 94))
  (segment (start 161.315321 106.818258) (end 161.4 106.733578) (width 0.1) (layer "F.Cu") (net 94))
  (segment (start 160.655806 107.219408) (end 160.655806 107.219407) (width 0.1) (layer "F.Cu") (net 94))
  (segment (start 161 103.596874) (end 161.4 103.196874) (width 0.1) (layer "F.Cu") (net 94))
  (segment (start 161.080072 106.795142) (end 161.080072 106.795141) (width 0.1) (layer "F.Cu") (net 94))
  (segment (start 160.655806 107.219407) (end 160.678924 107.242525) (width 0.1) (layer "F.Cu") (net 94))
  (segment (start 161.315322 106.818259) (end 161.315321 106.818258) (width 0.1) (layer "F.Cu") (net 94))
  (segment (start 160.4 108.175) (end 160.4 107.733578) (width 0.1) (layer "F.Cu") (net 94))
  (segment (start 160.891056 107.242525) (end 160.891055 107.242524) (width 0.1) (layer "F.Cu") (net 94))
  (segment (start 161 104.375) (end 161 103.596874) (width 0.1) (layer "F.Cu") (net 94))
  (segment (start 160.891055 107.242524) (end 160.891055 107.242523) (width 0.1) (layer "F.Cu") (net 94))
  (segment (start 161.4 101.15) (end 161 100.75) (width 0.1) (layer "F.Cu") (net 94))
  (segment (start 160.4 107.733578) (end 160.466789 107.666789) (width 0.1) (layer "F.Cu") (net 94))
  (segment (start 160.891055 107.030391) (end 160.867938 107.007274) (width 0.1) (layer "F.Cu") (net 94))
  (segment (start 161.4 105.8) (end 161 105.4) (width 0.1) (layer "F.Cu") (net 94))
  (segment (start 161 105.4) (end 161 104.375) (width 0.1) (layer "F.Cu") (net 94))
  (arc (start 160.891055 107.242523) (mid 160.934989 107.136457) (end 160.891055 107.030391) (width 0.1) (layer "F.Cu") (net 94))
  (arc (start 160.678924 107.242525) (mid 160.78499 107.286459) (end 160.891056 107.242525) (width 0.1) (layer "F.Cu") (net 94))
  (arc (start 161.10319 106.818259) (mid 161.209256 106.862193) (end 161.315322 106.818259) (width 0.1) (layer "F.Cu") (net 94))
  (arc (start 160.443672 107.43154) (mid 160.399738 107.325474) (end 160.443672 107.219408) (width 0.1) (layer "F.Cu") (net 94))
  (arc (start 160.443672 107.219408) (mid 160.54974 107.175473) (end 160.655806 107.219408) (width 0.1) (layer "F.Cu") (net 94))
  (arc (start 160.867938 107.007274) (mid 160.824004 106.901208) (end 160.867938 106.795142) (width 0.1) (layer "F.Cu") (net 94))
  (arc (start 160.466789 107.666789) (mid 160.510723 107.560723) (end 160.466789 107.454657) (width 0.1) (layer "F.Cu") (net 94))
  (arc (start 160.867938 106.795142) (mid 160.974006 106.751207) (end 161.080072 106.795142) (width 0.1) (layer "F.Cu") (net 94))
  (segment (start 165 100.7) (end 165.8 101.5) (width 0.1) (layer "F.Cu") (net 96))
  (segment (start 165.8 101.5) (end 167.8 101.5) (width 0.1) (layer "F.Cu") (net 96))
  (segment (start 167.8 101.5) (end 168.2 101.9) (width 0.1) (layer "F.Cu") (net 96))
  (segment (start 165 99.410004) (end 165 100.7) (width 0.1) (layer "F.Cu") (net 96))
  (segment (start 168.2 103.4) (end 168.2 101.9) (width 0.1) (layer "F.Cu") (net 96))
  (segment (start 131.8 105.1) (end 131.8 106.1) (width 0.1) (layer "F.Cu") (net 97))
  (segment (start 145.6 103.35) (end 145.6 104.5) (width 0.1) (layer "F.Cu") (net 97))
  (segment (start 130.75 104.05) (end 131.8 105.1) (width 0.1) (layer "F.Cu") (net 97))
  (segment (start 132.8 107.1) (end 132.8 108.6) (width 0.1) (layer "F.Cu") (net 97))
  (segment (start 132.8 108.6) (end 132.975 108.775) (width 0.1) (layer "F.Cu") (net 97))
  (segment (start 132.975 108.775) (end 133.15 108.775) (width 0.1) (layer "F.Cu") (net 97))
  (segment (start 129.95 104.05) (end 130.75 104.05) (width 0.1) (layer "F.Cu") (net 97))
  (segment (start 131.8 106.1) (end 132.8 107.1) (width 0.1) (layer "F.Cu") (net 97))
  (via (at 129.95 104.05) (size 0.6) (drill 0.2) (layers "F.Cu" "B.Cu") (net 97))
  (via (at 145.6 104.5) (size 0.6) (drill 0.2) (layers "F.Cu" "B.Cu") (net 97))
  (segment (start 132.1 101.9) (end 133.5 100.5) (width 0.1) (layer "B.Cu") (net 97))
  (segment (start 130.2 101.9) (end 129.4 102.7) (width 0.1) (layer "B.Cu") (net 97))
  (segment (start 133.5 100.5) (end 143.3 100.5) (width 0.1) (layer "B.Cu") (net 97))
  (segment (start 143.3 100.5) (end 145.6 102.8) (width 0.1) (layer "B.Cu") (net 97))
  (segment (start 130.2 101.9) (end 132.1 101.9) (width 0.1) (layer "B.Cu") (net 97))
  (segment (start 145.6 104.5) (end 145.6 102.8) (width 0.1) (layer "B.Cu") (net 97))
  (segment (start 129.4 102.7) (end 129.4 103.5) (width 0.1) (layer "B.Cu") (net 97))
  (segment (start 129.4 103.5) (end 129.95 104.05) (width 0.1) (layer "B.Cu") (net 97))
  (segment (start 133.5 111.025) (end 132.603616 111.025) (width 0.1) (layer "F.Cu") (net 98))
  (segment (start 133.8 110.725) (end 133.5 111.025) (width 0.1) (layer "F.Cu") (net 98))
  (segment (start 132.603616 111.025) (end 132.4505 111.178116) (width 0.1) (layer "F.Cu") (net 98))
  (via (at 132.4505 111.178116) (size 0.4) (drill 0.15) (layers "F.Cu" "B.Cu") (net 98))
  (segment (start 131.585 112.043616) (end 132.4505 111.178116) (width 0.1) (layer "B.Cu") (net 98))
  (segment (start 137.8 106.77) (end 137.8 106.849264) (width 0.1) (layer "F.Cu") (net 100))
  (segment (start 139.01 105.78) (end 138.79 105.78) (width 0.1) (layer "F.Cu") (net 100))
  (segment (start 137.05 108.05) (end 137.3 107.8) (width 0.3) (layer "F.Cu") (net 100))
  (segment (start 138.79 105.78) (end 137.8 106.77) (width 0.1) (layer "F.Cu") (net 100))
  (segment (start 134.45 109.425) (end 134.125 109.75) (width 0.1) (layer "F.Cu") (net 100))
  (segment (start 131.485 109.4) (end 132.2 109.4) (width 0.4) (layer "F.Cu") (net 100))
  (segment (start 137.8 106.849264) (end 137.3 107.349264) (width 0.1) (layer "F.Cu") (net 100))
  (segment (start 137.05 108.125) (end 137.05 108.05) (width 0.3) (layer "F.Cu") (net 100))
  (segment (start 137.3 107.349264) (end 137.3 107.8) (width 0.1) (layer "F.Cu") (net 100))
  (via (at 137.3 107.8) (size 0.4) (drill 0.15) (layers "F.Cu" "B.Cu") (net 100))
  (via (at 132.2 109.4) (size 0.4) (drill 0.15) (layers "F.Cu" "B.Cu") (net 100))
  (via (at 134.125 109.75) (size 0.4) (drill 0.15) (layers "F.Cu" "B.Cu") (net 100))
  (segment (start 132.2 109.4) (end 132.36 109.24) (width 0.4) (layer "In2.Cu") (net 100))
  (segment (start 133.9 109.1) (end 135.2 107.8) (width 0.4) (layer "In2.Cu") (net 100))
  (segment (start 133.84 109.16) (end 133.9 109.1) (width 0.4) (layer "In2.Cu") (net 100))
  (segment (start 133.76 109.24) (end 133.9 109.1) (width 0.4) (layer "In2.Cu") (net 100))
  (segment (start 132.36 109.24) (end 133.76 109.24) (width 0.4) (layer "In2.Cu") (net 100))
  (segment (start 135.2 107.8) (end 137.3 107.8) (width 0.4) (layer "In2.Cu") (net 100))
  (segment (start 134.125 109.555) (end 133.84 109.27) (width 0.4) (layer "In2.Cu") (net 100))
  (segment (start 134.125 109.75) (end 134.125 109.555) (width 0.4) (layer "In2.Cu") (net 100))
  (segment (start 133.84 109.27) (end 133.84 109.16) (width 0.4) (layer "In2.Cu") (net 100))
  (segment (start 132.2 109.4) (end 131.5 109.4) (width 0.4) (layer "B.Cu") (net 100))
  (segment (start 132.6 108.8) (end 132.9 109.1) (width 0.1) (layer "F.Cu") (net 104))
  (segment (start 141.85 105.773842) (end 141.85 105.2125) (width 0.1) (layer "F.Cu") (net 104))
  (segment (start 132.6 107.394268) (end 132.6 108.8) (width 0.1) (layer "F.Cu") (net 104))
  (segment (start 145.4 107) (end 145.1 107.3) (width 0.1) (layer "F.Cu") (net 104))
  (segment (start 141.855518 105.77936) (end 141.85 105.773842) (width 0.1) (layer "F.Cu") (net 104))
  (segment (start 133.475 109.1) (end 133.8 109.425) (width 0.1) (layer "F.Cu") (net 104))
  (segment (start 132.352866 107.147134) (end 132.6 107.394268) (width 0.1) (layer "F.Cu") (net 104))
  (segment (start 132.9 109.1) (end 133.475 109.1) (width 0.1) (layer "F.Cu") (net 104))
  (segment (start 145.1 107.3) (end 145.1 107.6) (width 0.1) (layer "F.Cu") (net 104))
  (via (at 141.855518 105.77936) (size 0.4) (drill 0.15) (layers "F.Cu" "B.Cu") (net 104))
  (via (at 145.4 107) (size 0.6) (drill 0.2) (layers "F.Cu" "B.Cu") (net 104))
  (via (at 132.352866 107.147134) (size 0.4) (drill 0.15) (layers "F.Cu" "B.Cu") (net 104))
  (segment (start 133.405025 107) (end 132.5 107) (width 0.1) (layer "B.Cu") (net 104))
  (segment (start 141.855518 105.77936) (end 141.534878 106.1) (width 0.1) (layer "B.Cu") (net 104))
  (segment (start 132.5 107) (end 132.352866 107.147134) (width 0.1) (layer "B.Cu") (net 104))
  (segment (start 134.305025 106.1) (end 133.405025 107) (width 0.1) (layer "B.Cu") (net 104))
  (segment (start 141.855518 105.77936) (end 142.134878 105.5) (width 0.1) (layer "B.Cu") (net 104))
  (segment (start 141.534878 106.1) (end 134.305025 106.1) (width 0.1) (layer "B.Cu") (net 104))
  (segment (start 144.763603 107) (end 145.4 107) (width 0.1) (layer "B.Cu") (net 104))
  (segment (start 142.134878 105.5) (end 143.263603 105.5) (width 0.1) (layer "B.Cu") (net 104))
  (segment (start 143.263603 105.5) (end 144.763603 107) (width 0.1) (layer "B.Cu") (net 104))
  (segment (start 132.4 108.0495) (end 132.4 108.882842) (width 0.1) (layer "F.Cu") (net 105))
  (segment (start 132.2505 107.9) (end 132.4 108.0495) (width 0.1) (layer "F.Cu") (net 105))
  (segment (start 132.817158 109.3) (end 133.025 109.3) (width 0.1) (layer "F.Cu") (net 105))
  (segment (start 132.4 108.882842) (end 132.817158 109.3) (width 0.1) (layer "F.Cu") (net 105))
  (segment (start 141.905025 106.4) (end 141.35 105.844975) (width 0.1) (layer "F.Cu") (net 105))
  (segment (start 141.35 105.844975) (end 141.35 105.2125) (width 0.1) (layer "F.Cu") (net 105))
  (segment (start 133.025 109.3) (end 133.15 109.425) (width 0.1) (layer "F.Cu") (net 105))
  (segment (start 143.8 107.1) (end 144.1 107.4) (width 0.1) (layer "F.Cu") (net 105))
  (segment (start 142.1 106.4) (end 141.905025 106.4) (width 0.1) (layer "F.Cu") (net 105))
  (via (at 142.1 106.4) (size 0.4) (drill 0.15) (layers "F.Cu" "B.Cu") (net 105))
  (via (at 132.2505 107.9) (size 0.4) (drill 0.15) (layers "F.Cu" "B.Cu") (net 105))
  (via (at 143.8 107.1) (size 0.6) (drill 0.2) (layers "F.Cu" "B.Cu") (net 105))
  (segment (start 142.1 106.4) (end 142.0505 106.4495) (width 0.1) (layer "B.Cu") (net 105))
  (segment (start 142.1 106.4) (end 142.8 107.1) (width 0.1) (layer "B.Cu") (net 105))
  (segment (start 133.35 108.05) (end 132.4005 108.05) (width 0.1) (layer "B.Cu") (net 105))
  (segment (start 132.4005 108.05) (end 132.2505 107.9) (width 0.1) (layer "B.Cu") (net 105))
  (segment (start 134.9505 106.4495) (end 133.35 108.05) (width 0.1) (layer "B.Cu") (net 105))
  (segment (start 142.0505 106.4495) (end 134.9505 106.4495) (width 0.1) (layer "B.Cu") (net 105))
  (segment (start 142.8 107.1) (end 143.8 107.1) (width 0.1) (layer "B.Cu") (net 105))
  (segment (start 156.8 108.65) (end 156.975 108.825) (width 0.1) (layer "F.Cu") (net 106))
  (segment (start 156.975 108.825) (end 157.15 108.825) (width 0.1) (layer "F.Cu") (net 106))
  (segment (start 169.6 103.4) (end 169.6 104.55) (width 0.1) (layer "F.Cu") (net 106))
  (segment (start 156.8 107.15) (end 156.8 108.65) (width 0.1) (layer "F.Cu") (net 106))
  (segment (start 155.8 106.15) (end 156.8 107.15) (width 0.1) (layer "F.Cu") (net 106))
  (segment (start 153.95 104.1) (end 154.75 104.1) (width 0.1) (layer "F.Cu") (net 106))
  (segment (start 155.8 105.15) (end 155.8 106.15) (width 0.1) (layer "F.Cu") (net 106))
  (segment (start 154.75 104.1) (end 155.8 105.15) (width 0.1) (layer "F.Cu") (net 106))
  (via (at 169.6 104.55) (size 0.6) (drill 0.2) (layers "F.Cu" "B.Cu") (net 106))
  (via (at 153.95 104.1) (size 0.6) (drill 0.2) (layers "F.Cu" "B.Cu") (net 106))
  (segment (start 157.5 100.55) (end 167.3 100.55) (width 0.1) (layer "B.Cu") (net 106))
  (segment (start 156.1 101.95) (end 157.5 100.55) (width 0.1) (layer "B.Cu") (net 106))
  (segment (start 167.3 100.55) (end 169.6 102.85) (width 0.1) (layer "B.Cu") (net 106))
  (segment (start 154.2 101.95) (end 153.4 102.75) (width 0.1) (layer "B.Cu") (net 106))
  (segment (start 169.6 104.55) (end 169.6 102.85) (width 0.1) (layer "B.Cu") (net 106))
  (segment (start 153.4 102.75) (end 153.4 103.55) (width 0.1) (layer "B.Cu") (net 106))
  (segment (start 154.2 101.95) (end 156.1 101.95) (width 0.1) (layer "B.Cu") (net 106))
  (segment (start 153.4 103.55) (end 153.95 104.1) (width 0.1) (layer "B.Cu") (net 106))
  (segment (start 157.8 110.775) (end 157.5 111.075) (width 0.1) (layer "F.Cu") (net 107))
  (segment (start 157.5 111.075) (end 156.603616 111.075) (width 0.1) (layer "F.Cu") (net 107))
  (segment (start 156.603616 111.075) (end 156.4505 111.228116) (width 0.1) (layer "F.Cu") (net 107))
  (via (at 156.4505 111.228116) (size 0.4) (drill 0.15) (layers "F.Cu" "B.Cu") (net 107))
  (segment (start 155.585 112.093616) (end 156.4505 111.228116) (width 0.1) (layer "B.Cu") (net 107))
  (segment (start 162.77 105.929264) (end 161.3 107.399264) (width 0.1) (layer "F.Cu") (net 108))
  (segment (start 161.05 108.1) (end 161.3 107.85) (width 0.3) (layer "F.Cu") (net 108))
  (segment (start 163 105.86) (end 162.78 105.86) (width 0.1) (layer "F.Cu") (net 108))
  (segment (start 162.77 105.85) (end 162.77 105.929264) (width 0.1) (layer "F.Cu") (net 108))
  (segment (start 162.78 105.86) (end 162.77 105.85) (width 0.1) (layer "F.Cu") (net 108))
  (segment (start 158.45 109.475) (end 158.125 109.8) (width 0.1) (layer "F.Cu") (net 108))
  (segment (start 155.485 109.45) (end 156.2 109.45) (width 0.4) (layer "F.Cu") (net 108))
  (segment (start 161.3 107.399264) (end 161.3 107.85) (width 0.1) (layer "F.Cu") (net 108))
  (segment (start 161.05 108.175) (end 161.05 108.1) (width 0.3) (layer "F.Cu") (net 108))
  (via (at 161.3 107.85) (size 0.4) (drill 0.15) (layers "F.Cu" "B.Cu") (net 108))
  (via (at 158.125 109.8) (size 0.4) (drill 0.15) (layers "F.Cu" "B.Cu") (net 108))
  (via (at 156.2 109.45) (size 0.4) (drill 0.15) (layers "F.Cu" "B.Cu") (net 108))
  (segment (start 156.36 109.29) (end 157.76 109.29) (width 0.4) (layer "In2.Cu") (net 108))
  (segment (start 158.125 109.605) (end 157.84 109.32) (width 0.4) (layer "In2.Cu") (net 108))
  (segment (start 157.84 109.32) (end 157.84 109.21) (width 0.4) (layer "In2.Cu") (net 108))
  (segment (start 156.2 109.45) (end 156.36 109.29) (width 0.4) (layer "In2.Cu") (net 108))
  (segment (start 159.2 107.85) (end 161.3 107.85) (width 0.4) (layer "In2.Cu") (net 108))
  (segment (start 157.84 109.21) (end 157.9 109.15) (width 0.4) (layer "In2.Cu") (net 108))
  (segment (start 157.9 109.15) (end 159.2 107.85) (width 0.4) (layer "In2.Cu") (net 108))
  (segment (start 157.76 109.29) (end 157.9 109.15) (width 0.4) (layer "In2.Cu") (net 108))
  (segment (start 158.125 109.8) (end 158.125 109.605) (width 0.4) (layer "In2.Cu") (net 108))
  (segment (start 156.2 109.45) (end 155.5 109.45) (width 0.4) (layer "B.Cu") (net 108))
  (segment (start 159.75 109.489473) (end 159.4255 109.813973) (width 0.1) (layer "F.Cu") (net 109))
  (segment (start 163.315 108.45) (end 163.315 107.105) (width 0.4) (layer "F.Cu") (net 109))
  (segment (start 163.645 108.78) (end 165.58 108.78) (width 0.3) (layer "F.Cu") (net 109))
  (segment (start 163.315 108.45) (end 163.645 108.78) (width 0.3) (layer "F.Cu") (net 109))
  (segment (start 163.315 108.45) (end 162.6 108.45) (width 0.4) (layer "F.Cu") (net 109))
  (segment (start 161.05 108.825) (end 161.375 108.5) (width 0.1) (layer "F.Cu") (net 109))
  (segment (start 159.4255 109.813973) (end 159.4255 109.813996) (width 0.1) (layer "F.Cu") (net 109))
  (segment (start 165.58 108.78) (end 166.6 109.8) (width 0.3) (layer "F.Cu") (net 109))
  (segment (start 163.315 107.105) (end 163.24 107.03) (width 0.4) (layer "F.Cu") (net 109))
  (via (at 159.4255 109.813996) (size 0.4) (drill 0.15) (layers "F.Cu" "B.Cu") (net 109))
  (via (at 161.375 108.5) (size 0.4) (drill 0.15) (layers "F.Cu" "B.Cu") (net 109))
  (via (at 162.6 108.45) (size 0.4) (drill 0.15) (layers "F.Cu" "B.Cu") (net 109))
  (segment (start 159.4255 109.813996) (end 159.4255 109.2245) (width 0.4) (layer "In2.Cu") (net 109))
  (segment (start 159.4255 109.2245) (end 160.15 108.5) (width 0.4) (layer "In2.Cu") (net 109))
  (segment (start 162.382107 108.325) (end 161.55 108.325) (width 0.4) (layer "In2.Cu") (net 109))
  (segment (start 160.15 108.5) (end 161.375 108.5) (width 0.4) (layer "In2.Cu") (net 109))
  (segment (start 162.6 108.45) (end 162.507107 108.45) (width 0.4) (layer "In2.Cu") (net 109))
  (segment (start 162.507107 108.45) (end 162.382107 108.325) (width 0.4) (layer "In2.Cu") (net 109))
  (segment (start 161.55 108.325) (end 161.375 108.5) (width 0.4) (layer "In2.Cu") (net 109))
  (segment (start 165.45 115.55) (end 165.45 114.6) (width 0.4) (layer "F.Cu") (net 110))
  (segment (start 165.45 114.6) (end 164.7 113.85) (width 0.4) (layer "F.Cu") (net 110))
  (segment (start 160.4 111.425) (end 160.075 111.75) (width 0.3) (layer "F.Cu") (net 110))
  (segment (start 163.315 112.865) (end 163.5 113.05) (width 0.4) (layer "F.Cu") (net 110))
  (segment (start 163.315 111.85) (end 163.315 112.865) (width 0.4) (layer "F.Cu") (net 110))
  (segment (start 163.5 113.05) (end 164.3 113.85) (width 0.4) (layer "F.Cu") (net 110))
  (segment (start 163.315 111.85) (end 162.6 111.85) (width 0.4) (layer "F.Cu") (net 110))
  (segment (start 158.45 111.425) (end 158.125 111.75) (width 0.1) (layer "F.Cu") (net 110))
  (segment (start 164.3 113.85) (end 164.7 113.85) (width 0.4) (layer "F.Cu") (net 110))
  (via (at 162.6 111.85) (size 0.4) (drill 0.15) (layers "F.Cu" "B.Cu") (net 110))
  (via (at 158.125 111.75) (size 0.4) (drill 0.15) (layers "F.Cu" "B.Cu") (net 110))
  (via (at 160.075 111.75) (size 0.4) (drill 0.15) (layers "F.Cu" "B.Cu") (net 110))
  (segment (start 160.075 111.875) (end 160.075 111.75) (width 0.4) (layer "In2.Cu") (net 110))
  (segment (start 158.567893 112.25) (end 159.7 112.25) (width 0.4) (layer "In2.Cu") (net 110))
  (segment (start 158.125 111.75) (end 158.125 111.807107) (width 0.4) (layer "In2.Cu") (net 110))
  (segment (start 162.6 111.85) (end 162.2 112.25) (width 0.4) (layer "In2.Cu") (net 110))
  (segment (start 162.2 112.25) (end 160.575 112.25) (width 0.4) (layer "In2.Cu") (net 110))
  (segment (start 160.575 112.25) (end 160.075 111.75) (width 0.4) (layer "In2.Cu") (net 110))
  (segment (start 158.125 111.807107) (end 158.567893 112.25) (width 0.4) (layer "In2.Cu") (net 110))
  (segment (start 159.7 112.25) (end 160.075 111.875) (width 0.4) (layer "In2.Cu") (net 110))
  (segment (start 169.15 107.05) (end 169.15 107.465) (width 0.1) (layer "F.Cu") (net 111))
  (segment (start 156.6 107.444268) (end 156.6 108.85) (width 0.1) (layer "F.Cu") (net 111))
  (segment (start 156.6 108.85) (end 156.9 109.15) (width 0.1) (layer "F.Cu") (net 111))
  (segment (start 157.475 109.15) (end 157.8 109.475) (width 0.1) (layer "F.Cu") (net 111))
  (segment (start 156.352866 107.197134) (end 156.6 107.444268) (width 0.1) (layer "F.Cu") (net 111))
  (segment (start 156.9 109.15) (end 157.475 109.15) (width 0.1) (layer "F.Cu") (net 111))
  (segment (start 165.8 105.85) (end 165.8 105.3125) (width 0.1) (layer "F.Cu") (net 111))
  (segment (start 169.4 106.8) (end 169.15 107.05) (width 0.1) (layer "F.Cu") (net 111))
  (via (at 169.4 106.8) (size 0.6) (drill 0.2) (layers "F.Cu" "B.Cu") (net 111))
  (via (at 156.352866 107.197134) (size 0.4) (drill 0.15) (layers "F.Cu" "B.Cu") (net 111))
  (via (at 165.8 105.85) (size 0.4) (drill 0.15) (layers "F.Cu" "B.Cu") (net 111))
  (segment (start 166.65 105.45) (end 166.1 105.45) (width 0.1) (layer "B.Cu") (net 111))
  (segment (start 158.305025 106.15) (end 165.5 106.15) (width 0.1) (layer "B.Cu") (net 111))
  (segment (start 167.55 106.35) (end 166.65 105.45) (width 0.1) (layer "B.Cu") (net 111))
  (segment (start 165.5 106.15) (end 165.8 105.85) (width 0.1) (layer "B.Cu") (net 111))
  (segment (start 156.5 107.05) (end 157.405025 107.05) (width 0.1) (layer "B.Cu") (net 111))
  (segment (start 166.1 105.45) (end 165.8 105.75) (width 0.1) (layer "B.Cu") (net 111))
  (segment (start 165.8 105.75) (end 165.8 105.85) (width 0.1) (layer "B.Cu") (net 111))
  (segment (start 168.613603 106.35) (end 167.55 106.35) (width 0.1) (layer "B.Cu") (net 111))
  (segment (start 169.063603 106.8) (end 168.613603 106.35) (width 0.1) (layer "B.Cu") (net 111))
  (segment (start 156.352866 107.197134) (end 156.5 107.05) (width 0.1) (layer "B.Cu") (net 111))
  (segment (start 157.405025 107.05) (end 158.305025 106.15) (width 0.1) (layer "B.Cu") (net 111))
  (segment (start 169.4 106.8) (end 169.063603 106.8) (width 0.1) (layer "B.Cu") (net 111))
  (segment (start 168.1 107.465) (end 168.1 106.9) (width 0.1) (layer "F.Cu") (net 112))
  (segment (start 156.2505 107.95) (end 156.4 108.0995) (width 0.1) (layer "F.Cu") (net 112))
  (segment (start 165.755025 106.3) (end 165.35 105.894975) (width 0.1) (layer "F.Cu") (net 112))
  (segment (start 156.4 108.932842) (end 156.817158 109.35) (width 0.1) (layer "F.Cu") (net 112))
  (segment (start 166.05 106.3) (end 165.755025 106.3) (width 0.1) (layer "F.Cu") (net 112))
  (segment (start 156.817158 109.35) (end 157.025 109.35) (width 0.1) (layer "F.Cu") (net 112))
  (segment (start 157.025 109.35) (end 157.15 109.475) (width 0.1) (layer "F.Cu") (net 112))
  (segment (start 156.4 108.0995) (end 156.4 108.932842) (width 0.1) (layer "F.Cu") (net 112))
  (segment (start 165.35 105.894975) (end 165.35 105.2625) (width 0.1) (layer "F.Cu") (net 112))
  (via (at 168.1 106.9) (size 0.6) (drill 0.2) (layers "F.Cu" "B.Cu") (net 112))
  (via (at 156.2505 107.95) (size 0.4) (drill 0.15) (layers "F.Cu" "B.Cu") (net 112))
  (via (at 166.05 106.3) (size 0.4) (drill 0.15) (layers "F.Cu" "B.Cu") (net 112))
  (segment (start 157.35 108.1) (end 156.4005 108.1) (width 0.1) (layer "B.Cu") (net 112))
  (segment (start 168.1 106.9) (end 166.65 106.9) (width 0.1) (layer "B.Cu") (net 112))
  (segment (start 165.8505 106.4995) (end 158.9505 106.4995) (width 0.1) (layer "B.Cu") (net 112))
  (segment (start 166.65 106.9) (end 166.05 106.3) (width 0.1) (layer "B.Cu") (net 112))
  (segment (start 166.05 106.3) (end 165.8505 106.4995) (width 0.1) (layer "B.Cu") (net 112))
  (segment (start 156.4005 108.1) (end 156.2505 107.95) (width 0.1) (layer "B.Cu") (net 112))
  (segment (start 158.9505 106.4995) (end 157.35 108.1) (width 0.1) (layer "B.Cu") (net 112))
  (segment (start 139.97 105.78) (end 139.48 106.27) (width 0.1) (layer "F.Cu") (net 113))
  (segment (start 139.48 106.27) (end 138.91 106.27) (width 0.1) (layer "F.Cu") (net 113))
  (segment (start 138.91 106.27) (end 137.7 107.48) (width 0.1) (layer "F.Cu") (net 113))
  (segment (start 137.7 107.48) (end 137.7 108.125) (width 0.1) (layer "F.Cu") (net 113))
  (segment (start 163.72 105.86) (end 163.24 106.34) (width 0.1) (layer "F.Cu") (net 114))
  (segment (start 161.7 107.442842) (end 161.7 108.175) (width 0.1) (layer "F.Cu") (net 114))
  (segment (start 163.96 105.86) (end 163.72 105.86) (width 0.1) (layer "F.Cu") (net 114))
  (segment (start 163.24 106.34) (end 162.802842 106.34) (width 0.1) (layer "F.Cu") (net 114))
  (segment (start 162.802842 106.34) (end 161.7 107.442842) (width 0.1) (layer "F.Cu") (net 114))
  (segment (start 133.15 108.125) (end 133.15 107.77) (width 0.1) (layer "F.Cu") (net 115))
  (segment (start 133.15 107.77) (end 133.22 107.7) (width 0.1) (layer "F.Cu") (net 115))
  (segment (start 133.22 107.7) (end 133.2 107.7) (width 0.1) (layer "F.Cu") (net 115))
  (via (at 133.2 107.7) (size 0.4) (drill 0.15) (layers "F.Cu" "B.Cu") (net 115))
  (segment (start 132.75 107.55) (end 132.3 107.55) (width 0.1) (layer "B.Cu") (net 115))
  (segment (start 131.9 107.2) (end 132.25 107.55) (width 0.1) (layer "B.Cu") (net 115))
  (segment (start 131.9 107.2) (end 131.9 104.6492) (width 0.1) (layer "B.Cu") (net 115))
  (segment (start 130.3 103.0492) (end 131.9 104.6492) (width 0.1) (layer "B.Cu") (net 115))
  (segment (start 132.75 107.55) (end 132.9 107.7) (width 0.1) (layer "B.Cu") (net 115))
  (segment (start 133.2 107.7) (end 132.9 107.7) (width 0.1) (layer "B.Cu") (net 115))
  (segment (start 132.3 107.55) (end 132.25 107.55) (width 0.1) (layer "B.Cu") (net 115))
  (segment (start 133.5 113.6) (end 132.7 114.4) (width 0.1) (layer "F.Cu") (net 116))
  (segment (start 133.8 111.375) (end 133.5 111.675) (width 0.1) (layer "F.Cu") (net 116))
  (segment (start 133.5 111.675) (end 133.5 113.6) (width 0.1) (layer "F.Cu") (net 116))
  (via (at 132.7 114.4) (size 0.4) (drill 0.15) (layers "F.Cu" "B.Cu") (net 116))
  (segment (start 132.7 114.4) (end 132.7 114.8492) (width 0.1) (layer "B.Cu") (net 116))
  (segment (start 132.7 114.8492) (end 131.4 116.1492) (width 0.1) (layer "B.Cu") (net 116))
  (segment (start 133.15 111.375) (end 132.7755 111.375) (width 0.1) (layer "F.Cu") (net 117))
  (segment (start 132.7755 111.375) (end 132.4505 111.7) (width 0.1) (layer "F.Cu") (net 117))
  (via (at 132.4505 111.7) (size 0.4) (drill 0.15) (layers "F.Cu" "B.Cu") (net 117))
  (segment (start 131.4 114.9492) (end 132.4505 113.8987) (width 0.1) (layer "B.Cu") (net 117))
  (segment (start 132.4505 113.8987) (end 132.4505 111.7) (width 0.1) (layer "B.Cu") (net 117))
  (segment (start 142.35 102.3875) (end 142.9625 102.3875) (width 0.1) (layer "F.Cu") (net 118))
  (segment (start 142.9625 102.3875) (end 143 102.35) (width 0.1) (layer "F.Cu") (net 118))
  (via (at 143 102.35) (size 0.6) (drill 0.2) (layers "F.Cu" "B.Cu") (net 118))
  (segment (start 143 102.35) (end 143.7 102.35) (width 0.1) (layer "B.Cu") (net 118))
  (segment (start 157.22 107.75) (end 157.2 107.75) (width 0.1) (layer "F.Cu") (net 119))
  (segment (start 157.15 108.175) (end 157.15 107.82) (width 0.1) (layer "F.Cu") (net 119))
  (segment (start 157.15 107.82) (end 157.22 107.75) (width 0.1) (layer "F.Cu") (net 119))
  (via (at 157.2 107.75) (size 0.4) (drill 0.15) (layers "F.Cu" "B.Cu") (net 119))
  (segment (start 155.9 107.25) (end 155.9 104.6992) (width 0.1) (layer "B.Cu") (net 119))
  (segment (start 156.3 107.6) (end 156.25 107.6) (width 0.1) (layer "B.Cu") (net 119))
  (segment (start 156.75 107.6) (end 156.3 107.6) (width 0.1) (layer "B.Cu") (net 119))
  (segment (start 156.75 107.6) (end 156.9 107.75) (width 0.1) (layer "B.Cu") (net 119))
  (segment (start 155.9 107.25) (end 156.25 107.6) (width 0.1) (layer "B.Cu") (net 119))
  (segment (start 154.3 103.0992) (end 155.9 104.6992) (width 0.1) (layer "B.Cu") (net 119))
  (segment (start 157.2 107.75) (end 156.9 107.75) (width 0.1) (layer "B.Cu") (net 119))
  (segment (start 157.8 111.425) (end 157.5 111.725) (width 0.1) (layer "F.Cu") (net 120))
  (segment (start 157.5 113.65) (end 156.7 114.45) (width 0.1) (layer "F.Cu") (net 120))
  (segment (start 157.5 111.725) (end 157.5 113.65) (width 0.1) (layer "F.Cu") (net 120))
  (via (at 156.7 114.45) (size 0.4) (drill 0.15) (layers "F.Cu" "B.Cu") (net 120))
  (segment (start 156.7 114.45) (end 156.7 114.8992) (width 0.1) (layer "B.Cu") (net 120))
  (segment (start 156.7 114.8992) (end 155.4 116.1992) (width 0.1) (layer "B.Cu") (net 120))
  (segment (start 156.7755 111.425) (end 156.4505 111.75) (width 0.1) (layer "F.Cu") (net 121))
  (segment (start 157.15 111.425) (end 156.7755 111.425) (width 0.1) (layer "F.Cu") (net 121))
  (via (at 156.4505 111.75) (size 0.4) (drill 0.15) (layers "F.Cu" "B.Cu") (net 121))
  (segment (start 156.4505 113.9487) (end 156.4505 111.75) (width 0.1) (layer "B.Cu") (net 121))
  (segment (start 155.4 114.9992) (end 156.4505 113.9487) (width 0.1) (layer "B.Cu") (net 121))
  (segment (start 166.9625 102.4375) (end 167 102.4) (width 0.1) (layer "F.Cu") (net 122))
  (segment (start 166.35 102.4375) (end 166.9625 102.4375) (width 0.1) (layer "F.Cu") (net 122))
  (via (at 167 102.4) (size 0.6) (drill 0.2) (layers "F.Cu" "B.Cu") (net 122))
  (segment (start 167 102.4) (end 167.7 102.4) (width 0.1) (layer "B.Cu") (net 122))
  (segment (start 161.6 103.2) (end 161.6 101.15) (width 0.1) (layer "F.Cu") (net 137))
  (segment (start 160.7 108.525) (end 160.7 108.050735) (width 0.1) (layer "F.Cu") (net 137))
  (segment (start 161.6 106.816422) (end 161.6 105.8) (width 0.1) (layer "F.Cu") (net 137))
  (segment (start 160.6 107.816422) (end 161.6 106.816422) (width 0.1) (layer "F.Cu") (net 137))
  (segment (start 162 105.4) (end 162 104.375) (width 0.1) (layer "F.Cu") (net 137))
  (segment (start 160.6 107.950735) (end 160.6 107.816422) (width 0.1) (layer "F.Cu") (net 137))
  (segment (start 161.6 101.15) (end 162.000001 100.749999) (width 0.1) (layer "F.Cu") (net 137))
  (segment (start 161.6 105.8) (end 162 105.4) (width 0.1) (layer "F.Cu") (net 137))
  (segment (start 160.7 108.050735) (end 160.6 107.950735) (width 0.1) (layer "F.Cu") (net 137))
  (segment (start 162.000001 100.749999) (end 162.000001 99.410004) (width 0.1) (layer "F.Cu") (net 137))
  (segment (start 160.4 108.825) (end 160.7 108.525) (width 0.1) (layer "F.Cu") (net 137))
  (segment (start 162 104.375) (end 162 103.6) (width 0.1) (layer "F.Cu") (net 137))
  (segment (start 162 103.6) (end 161.6 103.2) (width 0.1) (layer "F.Cu") (net 137))
  (segment (start 157.8 107.729541) (end 157.8 108.175) (width 0.1) (layer "F.Cu") (net 138))
  (segment (start 157.3 107.1005) (end 157.3 107.229541) (width 0.1) (layer "F.Cu") (net 138))
  (segment (start 156.9 106.7005) (end 157.3 107.1005) (width 0.1) (layer "F.Cu") (net 138))
  (segment (start 157.3 107.229541) (end 157.8 107.729541) (width 0.1) (layer "F.Cu") (net 138))
  (segment (start 162.5 99.410004) (end 162.5 101.05) (width 0.1) (layer "F.Cu") (net 138))
  (via (at 156.9 106.7005) (size 0.4) (drill 0.15) (layers "F.Cu" "B.Cu") (net 138))
  (via (at 162.5 101.05) (size 0.4) (drill 0.15) (layers "F.Cu" "B.Cu") (net 138))
  (segment (start 156.9 106.7005) (end 157.659672 105.940828) (width 0.1) (layer "B.Cu") (net 138))
  (segment (start 162.355025 101.05) (end 162.5 101.05) (width 0.1) (layer "B.Cu") (net 138))
  (segment (start 157.659672 103.090328) (end 159.6 101.15) (width 0.1) (layer "B.Cu") (net 138))
  (segment (start 157.659672 105.940828) (end 157.659672 103.090328) (width 0.1) (layer "B.Cu") (net 138))
  (segment (start 162.255025 101.15) (end 162.355025 101.05) (width 0.1) (layer "B.Cu") (net 138))
  (segment (start 159.6 101.15) (end 162.255025 101.15) (width 0.1) (layer "B.Cu") (net 138))
  (segment (start 165.35 101.95) (end 165.35 102.4375) (width 0.1) (layer "F.Cu") (net 139))
  (segment (start 164.9 101.5) (end 165.35 101.95) (width 0.1) (layer "F.Cu") (net 139))
  (segment (start 163.4 102) (end 163.9 101.5) (width 0.1) (layer "F.Cu") (net 139))
  (segment (start 163.9 101.5) (end 164.9 101.5) (width 0.1) (layer "F.Cu") (net 139))
  (segment (start 163.500001 101.100001) (end 163.9 101.5) (width 0.1) (layer "F.Cu") (net 139))
  (segment (start 163.500001 99.410004) (end 163.500001 101.100001) (width 0.1) (layer "F.Cu") (net 139))
  (segment (start 166.125 102.9) (end 166.45 102.9) (width 0.1) (layer "F.Cu") (net 140))
  (segment (start 164.25 101.2) (end 164 100.95) (width 0.1) (layer "F.Cu") (net 140))
  (segment (start 167.43 103.88) (end 167.43 104.65) (width 0.1) (layer "F.Cu") (net 140))
  (segment (start 165.1 101.2) (end 164.25 101.2) (width 0.1) (layer "F.Cu") (net 140))
  (segment (start 165.85 102.4375) (end 165.85 101.95) (width 0.1) (layer "F.Cu") (net 140))
  (segment (start 166.45 102.9) (end 167.43 103.88) (width 0.1) (layer "F.Cu") (net 140))
  (segment (start 165.85 101.95) (end 165.1 101.2) (width 0.1) (layer "F.Cu") (net 140))
  (segment (start 165.85 102.625) (end 166.125 102.9) (width 0.1) (layer "F.Cu") (net 140))
  (segment (start 164 100.95) (end 164 99.410004) (width 0.1) (layer "F.Cu") (net 140))
  (segment (start 165.500002 100.700002) (end 165.95 101.15) (width 0.1) (layer "F.Cu") (net 141))
  (segment (start 165.95 101.15) (end 168.85 101.15) (width 0.1) (layer "F.Cu") (net 141))
  (segment (start 165.500002 99.410004) (end 165.500002 100.700002) (width 0.1) (layer "F.Cu") (net 141))
  (segment (start 168.85 101.15) (end 169.6 101.9) (width 0.1) (layer "F.Cu") (net 141))

  (zone (net 0) (net_name "") (layer "F.Cu") (hatch edge 0.508)
    (connect_pads (clearance 0))
    (min_thickness 0.2) (filled_areas_thickness no)
    (keepout (tracks allowed) (vias allowed) (pads allowed) (copperpour not_allowed) (footprints allowed))
    (fill (thermal_gap 0.508) (thermal_bridge_width 0.508))
    (polygon
      (pts
        (xy 166 129)
        (xy 163 132)
        (xy 139 132)
        (xy 131 124)
        (xy 131 91)
        (xy 144 91)
        (xy 143.95 119.1)
        (xy 155 119.1)
        (xy 155 91)
        (xy 166 91)
      )
    )
  )
  (zone (net 2) (net_name "GND") (layer "F.Cu") (hatch edge 0.508)
    (priority 3)
    (connect_pads (clearance 0.2))
    (min_thickness 0.2) (filled_areas_thickness no)
    (fill yes (thermal_gap 0.508) (thermal_bridge_width 0.508))
    (polygon
      (pts
        (xy 183 135)
        (xy 115 135)
        (xy 115 90)
        (xy 183 90)
      )
    )
  )
  (zone (net 2) (net_name "GND") (layer "In1.Cu") (hatch edge 0.508)
    (connect_pads (clearance 0.1))
    (min_thickness 0.1) (filled_areas_thickness no)
    (fill yes (thermal_gap 0.508) (thermal_bridge_width 0.508))
    (polygon
      (pts
        (xy 138.925 113.925)
        (xy 131.95 113.925)
        (xy 131.95 106.9)
        (xy 138.925 106.9)
      )
    )
  )
  (zone (net 2) (net_name "GND") (layer "In1.Cu") (hatch edge 0.508)
    (connect_pads (clearance 0.2))
    (min_thickness 0.2) (filled_areas_thickness no)
    (fill yes (thermal_gap 0.508) (thermal_bridge_width 0.508))
    (polygon
      (pts
        (xy 183 135)
        (xy 115 135)
        (xy 115 90)
        (xy 183 90)
      )
    )
  )
  (zone (net 2) (net_name "GND") (layer "In2.Cu") (hatch edge 0.508)
    (priority 100)
    (connect_pads (clearance 0.2))
    (min_thickness 0.2) (filled_areas_thickness no)
    (fill yes (thermal_gap 0.508) (thermal_bridge_width 0.508))
    (polygon
      (pts
        (xy 149.1 130.1)
        (xy 145.8 130.1)
        (xy 145.8 125.05)
        (xy 149.1 125.05)
      )
    )
  )
  (zone (net 14) (net_name "+5V") (layer "In2.Cu") (hatch edge 0.508)
    (priority 1)
    (connect_pads (clearance 0.2))
    (min_thickness 0.2) (filled_areas_thickness no)
    (fill yes (thermal_gap 0.508) (thermal_bridge_width 0.508))
    (polygon
      (pts
        (xy 169 105.8)
        (xy 165.55 105.8)
        (xy 163.75 104)
        (xy 163.75 100.95)
        (xy 149.05 100.95)
        (xy 144.3 105.65)
        (xy 141.5 105.65)
        (xy 137.75 101.9)
        (xy 137.75 100.95)
        (xy 121.95 100.95)
        (xy 121.95 112.7)
        (xy 137.4 128.15)
        (xy 137.4 135)
        (xy 115 135)
        (xy 115 90)
        (xy 169 90)
      )
    )
  )
  (zone (net 12) (net_name "CH1_1V2") (layer "In2.Cu") (hatch edge 0.508)
    (priority 3)
    (connect_pads (clearance 0.2))
    (min_thickness 0.2) (filled_areas_thickness no)
    (fill yes (thermal_gap 0.508) (thermal_bridge_width 0.508))
    (polygon
      (pts
        (xy 138.95 104.35)
        (xy 144.95 110.35)
        (xy 144.95 115.1)
        (xy 142.65 115.1)
        (xy 142.65 111)
        (xy 138.5 106.85)
        (xy 126.3 106.85)
        (xy 126.3 104.35)
      )
    )
  )
  (zone (net 2) (net_name "GND") (layer "In2.Cu") (hatch edge 0.508)
    (priority 100)
    (connect_pads (clearance 0.2))
    (min_thickness 0.2) (filled_areas_thickness no)
    (fill yes (thermal_gap 0.508) (thermal_bridge_width 0.508))
    (polygon
      (pts
        (xy 161.3 118.45)
        (xy 156.25 118.45)
        (xy 156.25 115.9)
        (xy 161.3 115.9)
      )
    )
  )
  (zone (net 9) (net_name "+3V3") (layer "In2.Cu") (hatch edge 0.508)
    (connect_pads (clearance 0.2))
    (min_thickness 0.2) (filled_areas_thickness no)
    (fill yes (thermal_gap 0.508) (thermal_bridge_width 0.508))
    (polygon
      (pts
        (xy 183 135)
        (xy 115 135)
        (xy 115 90)
        (xy 183 90)
      )
    )
  )
  (zone (net 25) (net_name "CH2_1V2") (layer "In2.Cu") (hatch edge 0.508)
    (priority 3)
    (connect_pads (clearance 0.2))
    (min_thickness 0.2) (filled_areas_thickness no)
    (fill yes (thermal_gap 0.508) (thermal_bridge_width 0.508))
    (polygon
      (pts
        (xy 162.95 104.4)
        (xy 168.95 110.4)
        (xy 168.95 115.15)
        (xy 166.65 115.15)
        (xy 166.65 111.05)
        (xy 162.5 106.9)
        (xy 150.3 106.9)
        (xy 150.3 104.4)
      )
    )
  )
  (zone (net 0) (net_name "") (layer "B.Cu") (hatch edge 0.508)
    (connect_pads (clearance 0))
    (min_thickness 0.2) (filled_areas_thickness no)
    (keepout (tracks allowed) (vias allowed) (pads allowed) (copperpour not_allowed) (footprints allowed))
    (fill (thermal_gap 0.508) (thermal_bridge_width 0.508))
    (polygon
      (pts
        (xy 161 118)
        (xy 156.7 118)
        (xy 156.7 115.65)
        (xy 161 115.65)
      )
    )
  )
  (zone (net 2) (net_name "GND") (layer "B.Cu") (hatch edge 0.508)
    (priority 3)
    (connect_pads (clearance 0.2))
    (min_thickness 0.2) (filled_areas_thickness no)
    (fill yes (thermal_gap 0.508) (thermal_bridge_width 0.508))
    (polygon
      (pts
        (xy 183 135)
        (xy 115 135)
        (xy 115 90)
        (xy 183 90)
      )
    )
  )
  (zone (net 0) (net_name "") (layer "B.Cu") (hatch edge 0.508)
    (connect_pads (clearance 0))
    (min_thickness 0.2) (filled_areas_thickness no)
    (keepout (tracks allowed) (vias allowed) (pads allowed) (copperpour not_allowed) (footprints allowed))
    (fill (thermal_gap 0.508) (thermal_bridge_width 0.508))
    (polygon
      (pts
        (xy 148.5 130)
        (xy 146.5 130)
        (xy 146.5 125)
        (xy 148.5 125)
      )
    )
  )
)
